G04 ================== begin FILE IDENTIFICATION RECORD ==================*
G04 Layout Name:  DAT6MTH3AD0_t6m_cm_d_brd_103112_274.brd*
G04 Film Name:    bot.art*
G04 File Format:  Gerber RS274X*
G04 File Origin:  Cadence Allegro 16.3-S048*
G04 Origin Date:  Tue Nov 26 10:18:27 2013*
G04 *
G04 Layer:  VIA CLASS/BOTTOM*
G04 Layer:  PIN/BOTTOM*
G04 Layer:  MANUFACTURING/PHOTOPLOT_OUTLINE*
G04 Layer:  ETCH/BOTTOM*
G04 Layer:  DRAWING FORMAT/TITLE_BLOCK*
G04 Layer:  DRAWING FORMAT/TITLE_DATA_BOT*
G04 *
G04 Offset:    (0.00 0.00)*
G04 Mirror:    No*
G04 Mode:      Positive*
G04 Rotation:  0*
G04 FullContactRelief:  No*
G04 UndefLineWidth:     6.00*
G04 ================== end FILE IDENTIFICATION RECORD ====================*
%FSLAX25Y25*MOIN*%
%IR0*IPPOS*OFA0.00000B0.00000*MIA0B0*SFA1.00000B1.00000*%
%ADD47R,.004X.02*%
%ADD22O,.04X.135*%
%ADD52R,.03X.126*%
%ADD11C,.01*%
%AMMACRO50*
4,1,8,-.005,.02,
-.005,-.002,
-.01,-.002,
-.01,-.02,
.01,-.02,
.01,-.002,
.005,-.002,
.005,.02,
-.005,.02,
0.0*
%
%ADD50MACRO50*%
%AMMACRO49*
4,1,8,-.02,-.005,
.002,-.005,
.002,-.01,
.02,-.01,
.02,.01,
.002,.01,
.002,.005,
-.02,.005,
-.02,-.005,
0.0*
%
%ADD49MACRO49*%
%ADD14R,.008X.012*%
%ADD12C,.02*%
%ADD42C,.03*%
%ADD28R,.03X.166*%
%ADD48R,.016X.005*%
%ADD44R,.0042X.016*%
%AMMACRO43*
21,1,.016,.0042,0.0,0.0,45.*%
%ADD43MACRO43*%
%ADD38R,.016X.0042*%
%ADD51C,.042*%
%ADD18C,.06*%
%ADD67C,.052*%
%ADD65C,.061*%
%ADD10C,.026*%
%ADD21C,.045*%
%ADD55C,.046*%
%ADD66C,.047*%
%ADD36C,.065*%
%ADD62C,.066*%
%ADD29C,.039*%
%ADD74C,.058*%
%ADD70R,.042X.042*%
%ADD69C,.076*%
%ADD40C,.0193*%
%ADD17R,.06X.06*%
%ADD68R,.052X.052*%
%ADD64R,.061X.061*%
%ADD31C,.068*%
%ADD23C,.059*%
%ADD20C,.077*%
%ADD24R,.045X.045*%
%ADD60R,.064X.064*%
%ADD63R,.066X.066*%
%ADD75R,.058X.058*%
%ADD30R,.068X.068*%
%ADD25R,.077X.077*%
%ADD71R,.04X.032*%
%ADD61R,.04X.05*%
%ADD37R,.02X.018*%
%ADD53R,.053X.022*%
%ADD27R,.018X.02*%
%ADD19C,.12*%
%ADD73C,.14*%
%ADD54R,.046X.013*%
%ADD72C,.15*%
%ADD59R,.013X.046*%
%ADD41R,.032X.028*%
%ADD39R,.028X.032*%
%ADD32C,.142*%
%AMMACRO46*
4,1,8,.005,-.02,
.005,.002,
.01,.002,
.01,.02,
-.01,.02,
-.01,.002,
-.005,.002,
-.005,-.02,
.005,-.02,
0.0*
%
%ADD46MACRO46*%
%ADD35R,.054X.044*%
%ADD58C,.306*%
%ADD57R,.062X.046*%
%ADD34R,.044X.054*%
%ADD45R,.059X.014*%
%ADD33C,.118*%
%ADD26R,.046X.062*%
%ADD56C,.158*%
%ADD76C,.012*%
%ADD77C,.013*%
%ADD78C,.014*%
%ADD79C,.015*%
%ADD80C,.016*%
%ADD81C,.018*%
%ADD82C,.004*%
%ADD83C,.0041*%
%ADD84C,.006*%
%ADD85C,.005*%
%ADD86C,.0042*%
%ADD87C,.008*%
%ADD88C,.0045*%
%ADD89C,.0067*%
%ADD95O,.05002X.14502*%
%ADD93C,.03004*%
%ADD103C,.03006*%
%ADD94C,.03604*%
%ADD98C,.03606*%
%ADD101C,.07604*%
%ADD96C,.09107*%
%ADD97C,.02934*%
%ADD91C,.08704*%
%ADD102C,.15004*%
%ADD90C,.15206*%
%ADD99C,.198*%
%ADD100R,.07604X.07602*%
%ADD92R,.08704X.08704*%
G75*
%LPD*%
G75*
G36*
G01X7246Y376095D02*
X10270Y379119D01*
X50459D01*
X54480Y375098D01*
Y314318D01*
X51956Y311794D01*
G02X51603Y311647I-354J353D01*
G01X11331D01*
X7246Y315732D01*
Y376095D01*
G37*
G36*
G01X8449Y383713D02*
X6370Y385792D01*
Y658450D01*
X8850Y660930D01*
X14768D01*
G02X15689Y659539I1J-1000D01*
G03X18453I1382J-588D01*
G02X19374Y660930I920J391D01*
G01X23882D01*
X28470Y656342D01*
Y614380D01*
G02X28017Y613882I-500J0D01*
G03Y610294I168J-1794D01*
G02X28470Y609796I-47J-498D01*
G01Y604173D01*
G02X28045Y603679I-500J0D01*
G03Y600709I225J-1485D01*
G02X28470Y600215I-75J-494D01*
G01Y594016D01*
G02X28001Y593517I-500J0D01*
G03Y589919I111J-1799D01*
G02X28470Y589420I-31J-499D01*
G01Y536611D01*
X22160Y530301D01*
Y416638D01*
X38454Y400344D01*
X49810D01*
X57500Y392654D01*
Y385903D01*
X55310Y383713D01*
X8449D01*
G37*
G36*
G01X40204Y181478D02*
G02X40470Y180554I0J-500D01*
G03X44129Y179876I1460J-2333D01*
G02X44682Y181447I799J602D01*
G01Y187011D01*
G02X44129Y188582I246J969D01*
G03X44650Y190653I-2199J1654D01*
G03X43565Y192451I-2720J-415D01*
G02Y194031I613J790D01*
G03Y198459I-1635J2214D01*
G02Y200039I613J790D01*
G03X43566Y204466I-1635J2214D01*
G02Y206047I613J791D01*
G03X43565Y210474I-1636J2213D01*
G02Y212054I613J790D01*
G03Y216482I-1635J2214D01*
G02Y218062I613J790D01*
G03X40295I-1635J2214D01*
G02Y216482I-613J-790D01*
G03Y212054I1635J-2214D01*
G02Y210474I-613J-790D01*
G03X40294Y206047I1635J-2214D01*
G02Y204466I-613J-791D01*
G03X40295Y200039I1636J-2213D01*
G02Y198459I-613J-790D01*
G03Y194031I1635J-2214D01*
G02Y192451I-613J-790D01*
G03X39191Y189973I1635J-2213D01*
G03X39731Y188582I2739J263D01*
G02X39578Y187217I-799J-602D01*
G02X38759Y187543I-322J382D01*
G03X38706Y187849I-2734J-316D01*
G03X37659Y189447I-2682J-615D01*
G02Y191027I613J790D01*
G03Y195455I-1635J2214D01*
G02Y197035I613J790D01*
G03X37525Y201556I-1635J2214D01*
G01X37481Y201585D01*
X36075Y202991D01*
X34548D01*
X33677Y203862D01*
Y206824D01*
X34473Y207620D01*
X36500D01*
Y208326D01*
X36694Y208590D01*
X36850Y208639D01*
G03X38772Y211118I-826J2625D01*
G03X37659Y213478I-2748J146D01*
G02Y215058I613J790D01*
G03X38776Y217222I-1635J2214D01*
G03X38180Y218982I-2752J49D01*
G03X36986Y219851I-2157J-1709D01*
G01X36845Y219903D01*
X36500Y220374D01*
Y273320D01*
X47019Y283839D01*
X97725D01*
X99020Y282544D01*
Y254576D01*
X98874Y254337D01*
X98749Y254272D01*
G03Y240216I3613J-7028D01*
G01X98874Y240151D01*
X99020Y239912D01*
Y236644D01*
X98574Y236156D01*
X98412Y236124D01*
G03X97232Y234331I288J-1474D01*
G02X96231Y233119I-977J-212D01*
G03X94976Y232532I-63J-1501D01*
G03X94977Y230703I1192J-914D01*
G03X97306Y232598I1191J915D01*
G02X97939Y233355I379J326D01*
G03X98412Y233176I761J1295D01*
G01X98574Y233144D01*
X99020Y232656D01*
Y225323D01*
G02X97608Y224412I-1000J0D01*
G03Y221674I-618J-1369D01*
G02X99020Y220763I412J-911D01*
G01Y166061D01*
X89749Y156790D01*
X81351D01*
G02X80351Y157802I0J1000D01*
G03X77472Y158464I-1501J64D01*
G02X76379Y157920I-899J437D01*
G03X75704Y157924I-348J-1768D01*
G03X74464Y157043I326J-1772D01*
G01X74397Y156926D01*
X74164Y156790D01*
X45625D01*
X44583Y157832D01*
X36500Y165916D01*
Y178123D01*
G02X36850Y178600I500J0D01*
G03X38768Y181016I-826J2625D01*
G01X38783Y181211D01*
X39070Y181478D01*
X40204D01*
G37*
G36*
G01X54092Y451100D02*
X55900Y449293D01*
Y411704D01*
X41378D01*
X38950Y414132D01*
Y449650D01*
X40400Y451100D01*
X54092D01*
G37*
G36*
G01X42856Y467276D02*
Y468720D01*
Y474929D01*
X49360D01*
X50556D01*
X50981Y474504D01*
Y467937D01*
X53360Y465558D01*
Y461120D01*
X53021Y460781D01*
X48020D01*
X42856Y465945D01*
Y467068D01*
Y467276D01*
G37*
G36*
G01X43415Y495956D02*
X50404D01*
X50665Y495695D01*
Y477476D01*
X50167Y476978D01*
X43070D01*
X42708Y477340D01*
Y495249D01*
X43415Y495956D01*
G37*
G36*
G01X63774Y485533D02*
Y476962D01*
X62986Y476174D01*
X61153D01*
X53196D01*
X52171Y477199D01*
Y487988D01*
Y495090D01*
X52821Y495740D01*
X57415D01*
X62897D01*
X63774Y494863D01*
Y485533D01*
G37*
G36*
G01X55556Y512251D02*
X58782D01*
X58908Y512125D01*
Y509928D01*
X58470Y509490D01*
X58447D01*
X54216Y505259D01*
Y497227D01*
X53994Y497005D01*
X49121D01*
X48656Y497470D01*
Y510885D01*
X49429Y511658D01*
X52593D01*
X52724Y511565D01*
G03X55266Y512029I1045J1468D01*
G01X55336Y512134D01*
X55556Y512251D01*
G37*
G36*
G01X59870Y633700D02*
G02X59410Y633201I-500J-1D01*
G03X58152Y632302I120J-1497D01*
G02X56880Y631766I-917J399D01*
G03X58014Y629763I-640J-1685D01*
G02X58266Y630114I492J-88D01*
G01X58787Y630399D01*
G03X58889Y630346I743J1305D01*
G02X59441Y629238I-427J-904D01*
G03X59769Y627783I1764J-367D01*
G01X59870Y627649D01*
Y625091D01*
X59769Y624958D01*
G03Y622782I1436J-1088D01*
G01X59870Y622649D01*
Y614417D01*
X58200Y612747D01*
X44799D01*
X44720Y612826D01*
G03X43412Y614229I-1770J-339D01*
G01X43282Y614264D01*
X42608Y614938D01*
Y648424D01*
G02X43976Y649354I1000J0D01*
G03Y652704I664J1675D01*
G02X42608Y653634I-368J930D01*
G01Y655066D01*
X44011Y656469D01*
X57680D01*
X59870Y654279D01*
Y654115D01*
G03Y653106I1730J-504D01*
G01Y644908D01*
G02X59375Y644408I-500J0D01*
G03Y641404I15J-1502D01*
G02X59870Y640904I-5J-500D01*
G01Y633700D01*
G37*
G36*
G01X68536Y776020D02*
X66960Y774444D01*
X58147D01*
X52892Y779699D01*
Y794348D01*
X49794Y797446D01*
Y815847D01*
X49912Y815965D01*
X51976D01*
G02X52476Y815465I0J-500D01*
G01Y799441D01*
X52806Y799110D01*
X53515D01*
X53736Y799331D01*
Y815864D01*
X53936Y816064D01*
X56341D01*
X56536Y815869D01*
Y799331D01*
X56870Y798998D01*
X57316D01*
X57663Y799345D01*
Y816020D01*
X57720Y816077D01*
X60026D01*
G02X60526Y815577I0J-500D01*
G01Y799351D01*
X60616Y799261D01*
X61460D01*
X61590Y799391D01*
Y815839D01*
G02X62016Y816077I426J-263D01*
G01X64296D01*
X64436Y815937D01*
Y799098D01*
X64780Y798754D01*
X65186D01*
X65556Y799124D01*
Y815867D01*
X65596Y815907D01*
X68125D01*
X68396Y815636D01*
Y798205D01*
X68536Y798065D01*
Y776020D01*
G37*
G36*
G01X69912Y291930D02*
X65335D01*
X63164Y294101D01*
Y302961D01*
X64100Y303897D01*
X77072D01*
X79077Y301892D01*
Y293199D01*
X78679Y292801D01*
X70783D01*
X69912Y291930D01*
G37*
G36*
G01X62820Y462853D02*
X63230Y463263D01*
X70540D01*
X72809Y465532D01*
X107160D01*
X109240Y463452D01*
Y450519D01*
X108850Y450129D01*
X95219D01*
X93274Y448184D01*
Y436754D01*
X93200Y436679D01*
Y422996D01*
X93790Y422406D01*
Y415936D01*
X92810Y414956D01*
X63320D01*
G02X62820Y415456I0J500D01*
G01Y462853D01*
G37*
G36*
G01X59583Y499241D02*
X58574Y500250D01*
Y506608D01*
G02X59074Y507108I500J0D01*
G01X69279D01*
X76088Y500299D01*
X81906D01*
X82037Y500206D01*
G03X83783I873J1222D01*
G01X83914Y500299D01*
X87258D01*
X87569Y499988D01*
Y497391D01*
G02X87069Y496891I-500J0D01*
G01X73778D01*
X66837Y503831D01*
X62816D01*
X62616Y503631D01*
Y499555D01*
X62048Y498987D01*
X59922D01*
X59783Y499101D01*
G03X59631Y499211I-955J-1160D01*
G01X59583Y499241D01*
G37*
G36*
G01X60226Y509773D02*
X60082Y509917D01*
Y515590D01*
G02X60582Y516090I500J0D01*
G01X66255D01*
X66435Y515910D01*
Y509989D01*
X66219Y509773D01*
X60226D01*
G37*
G36*
G01X62634Y580554D02*
X70000Y587920D01*
X74270D01*
X75302Y586888D01*
Y582290D01*
X72768Y579756D01*
Y550748D01*
Y547064D01*
X71121Y545417D01*
X63320D01*
X62634Y546103D01*
Y555676D01*
Y580554D01*
G37*
G36*
G01X122047Y85630D02*
G02X74805I-23621J197D01*
G01X74804Y105511D01*
G02X122048I23622J1D01*
G01X122047Y85630D01*
G37*
G36*
G01X85639Y487177D02*
X79975D01*
X79563Y487589D01*
Y489016D01*
X79545Y489034D01*
Y495506D01*
X79691Y495652D01*
X87474D01*
X89303D01*
X100078D01*
X101809D01*
X103128D01*
X104052Y494728D01*
Y493409D01*
Y476892D01*
X102898Y475738D01*
X99232D01*
X86917D01*
X86298Y476357D01*
Y486518D01*
X85639Y487177D01*
G37*
G36*
G01X112409Y521697D02*
X88857D01*
X85388D01*
X84820Y522265D01*
Y524245D01*
X82810Y526255D01*
X76540D01*
X75620Y527175D01*
Y545710D01*
X76520Y546610D01*
X80599D01*
X86793D01*
X87637Y545766D01*
Y532389D01*
X92310Y527716D01*
X104017D01*
X107107Y530806D01*
Y545156D01*
X108609Y546658D01*
X113441D01*
X113450Y546649D01*
X121570D01*
X122410Y545809D01*
Y526288D01*
X121618Y525496D01*
X116208D01*
X115224Y524512D01*
X112409Y521697D01*
G37*
G36*
G01X75468Y550407D02*
Y556389D01*
X75371Y556487D01*
Y579476D01*
X77576Y581681D01*
Y587030D01*
X81282Y590736D01*
X91510D01*
X93434Y588812D01*
Y585059D01*
X92630Y584255D01*
Y564634D01*
X91448Y563452D01*
X87669Y559673D01*
Y548530D01*
X86960Y547821D01*
X76142D01*
X75468Y548495D01*
Y550407D01*
G37*
G36*
G01X122047Y699803D02*
G02X74805I-23621J197D01*
G01X74804Y719684D01*
G02X122048I23622J1D01*
G01X122047Y699803D01*
G37*
G36*
G01X97220Y409440D02*
X95190Y411470D01*
Y447086D01*
X95825Y447721D01*
X109592D01*
X111500Y449629D01*
Y462813D01*
X114450Y465763D01*
X122796D01*
G02X123151Y465615I0J-500D01*
G01X123152Y465614D01*
X125368D01*
X125499Y465520D01*
G03X126261Y465240I880J1217D01*
G01X126445Y465226D01*
X130709Y460963D01*
Y439173D01*
X148002Y421880D01*
Y413438D01*
X147589Y413025D01*
X111328D01*
X107743Y409440D01*
X97220D01*
G37*
G36*
G01X119990Y502530D02*
X125336D01*
X126570D01*
Y495842D01*
X125583D01*
X117700D01*
X115574D01*
X114117Y494385D01*
X108357D01*
X106710Y496032D01*
X105062Y497680D01*
X101177D01*
X100630Y498227D01*
Y505820D01*
X102020Y507210D01*
X112567D01*
X114531Y505246D01*
X114790Y504987D01*
Y503078D01*
X115100Y502768D01*
X115338Y502530D01*
X119990D01*
G37*
G36*
G01X92948Y529006D02*
X89279Y532676D01*
Y558668D01*
X94018Y563407D01*
Y579406D01*
X94440Y579828D01*
X99742D01*
X99756Y579814D01*
X100835D01*
X101700Y578949D01*
Y570837D01*
X102802Y569734D01*
X108504D01*
X109280Y568958D01*
Y567605D01*
X110914Y565970D01*
X121737D01*
X122310Y565397D01*
Y565050D01*
Y563847D01*
Y548741D01*
X121390Y547821D01*
X107798D01*
X106076Y546099D01*
Y531551D01*
X103531Y529006D01*
X92948D01*
G37*
G36*
G01X135519Y598150D02*
G03X136477Y597851I901J1202D01*
G02X136850Y597705I20J-500D01*
G01X138844Y595711D01*
X140333D01*
X143909Y592136D01*
X147688D01*
G03X148072Y592173I1J2001D01*
G01X148195Y592197D01*
X148433Y592124D01*
X149898Y590659D01*
X149899Y590452D01*
G03X150485Y589039I2001J2D01*
G01X151040Y588483D01*
Y588056D01*
X148263Y585279D01*
G02X147556I-354J354D01*
G01X147295Y585540D01*
G03X143880Y584050I-1415J-1415D01*
G02X142881Y583013I-999J-37D01*
G01X116990D01*
X116962Y583041D01*
X111658D01*
X109073Y580456D01*
Y572081D01*
G02X108573Y571581I-500J0D01*
G01X103518D01*
X103128Y571971D01*
Y579771D01*
X99548Y583351D01*
X96438D01*
X95538Y584251D01*
Y590611D01*
X95644Y590718D01*
Y594964D01*
X98930Y598250D01*
X135386D01*
X135519Y598150D01*
G37*
G36*
G01X92780Y623066D02*
X102718D01*
X103250Y622534D01*
Y611048D01*
X103160Y610958D01*
X92424D01*
X91670Y611712D01*
Y621956D01*
X92780Y623066D01*
G37*
G36*
G01X93380Y650519D02*
X102890D01*
Y642314D01*
X92670D01*
X92090Y642894D01*
Y649229D01*
X93380Y650519D01*
G37*
G36*
G01X116180Y411981D02*
X121596D01*
X121665Y411912D01*
Y400357D01*
X120935Y399627D01*
X113580D01*
G02X112597Y400810I0J1000D01*
G03X111856Y402393I-1477J274D01*
G02X111601Y402829I245J436D01*
G01Y403537D01*
Y410609D01*
X112973Y411981D01*
X116180D01*
G37*
G36*
G01X303328Y471136D02*
G03X303420Y471120I303J1471D01*
G02X303850Y470625I-70J-495D01*
G01Y452620D01*
X291696Y440466D01*
X246840D01*
X240913Y446393D01*
X205330D01*
X202404Y449319D01*
G02X202258Y449672I354J353D01*
G01Y452060D01*
X200340Y453977D01*
X199375Y454942D01*
X196780D01*
X189612Y462110D01*
X131464D01*
X131328Y462246D01*
X130842D01*
X129989Y463099D01*
X127738Y465350D01*
X127616Y465472D01*
X127574Y465814D01*
X127663Y465962D01*
G03X127680Y465991I-1287J774D01*
G03X127406Y467833I-1303J748D01*
G02X127359Y469243I685J729D01*
G03X127245Y471401I-1099J1024D01*
G03X124838Y470752I-985J-1134D01*
G02X123190Y470384I-941J339D01*
G01X122682Y470892D01*
X122631Y471210D01*
X122703Y471355D01*
G03X120729Y473391I-1343J673D01*
G01X120683Y473370D01*
X120567Y473343D01*
G02X120098Y473476I-115J486D01*
G01X115110Y478464D01*
G02X115120Y479888I707J707D01*
G03X115151Y479919I-1047J1078D01*
G03X113050Y482065I-1079J1045D01*
G03X112995Y482011I1025J-1098D01*
G02X111572Y482001I-716J698D01*
G01X111190Y482383D01*
Y492454D01*
G02X111690Y492954I500J0D01*
G01X125922D01*
X126813Y492063D01*
G02X126755Y490594I-707J-708D01*
G03X126730Y490573I953J-1160D01*
G02X126080I-325J380D01*
G03Y488289I-975J-1142D01*
G02X126730I325J-380D01*
G03X128868Y488481I975J1142D01*
G02X130337Y488539I761J-649D01*
G01X135404Y483472D01*
X135424Y483089D01*
X135303Y482940D01*
G03X137416Y480827I1167J-946D01*
G02X138084Y480792I315J-389D01*
G01X138446Y480430D01*
X138494D01*
G02X138994Y479930I0J-500D01*
G02X138698Y479473I-501J0D01*
G03X139179Y476606I613J-1371D01*
G03X140733Y478582I131J1496D01*
G03X140577Y478908I-1423J-481D01*
G02X141430Y480430I853J522D01*
G01X167140D01*
X168838Y482128D01*
X182562D01*
X182688Y482002D01*
X200542D01*
G02X201530Y481152I-1J-1000D01*
G03X201545Y481067I1978J305D01*
G03X201588Y480893I1962J393D01*
G01X201608Y480824D01*
Y480230D01*
G02X201108Y479730I-500J0D01*
G01X201021D01*
X200939Y479759D01*
G03X199410Y479444I-506J-1414D01*
G03X200110Y476878I1023J-1099D01*
G03X200686Y476864I324J1467D01*
G02X201827Y475939I143J-990D01*
G03X204372Y474352I1801J54D01*
G03X204867Y477302I-744J1641D01*
G02X204710Y477665I343J364D01*
G01Y478874D01*
G02X205188Y479352I501J-22D01*
G01X205410D01*
Y479452D01*
X207213D01*
X208214Y480452D01*
X209038Y481276D01*
X210627D01*
G02X211509Y479806I0J-1000D01*
G03X213872Y477992I1300J-753D01*
G02X214521Y478042I354J-354D01*
G03X216706Y478496I888J1211D01*
G03X216780Y479867I-1297J757D01*
G02X217692Y481276I912J409D01*
G01X219159D01*
X219310Y481126D01*
X219655D01*
G02X220621Y480057I-32J-1000D01*
G03X221673Y478293I1798J-124D01*
G03X221756Y478258I741J1642D01*
G02X222350Y477077I-374J-928D01*
G03X223443Y475176I1436J-439D01*
G01X223582Y475143D01*
X224746Y473979D01*
X224789Y473640D01*
X224702Y473493D01*
G03X226489Y470792I1553J-914D01*
G02X227618Y469801I129J-991D01*
G01Y469330D01*
X227490Y468999D01*
X227437Y468936D01*
G03X227096Y467256I1383J-1155D01*
G03X227572Y466480I1724J524D01*
G02X227416Y464936I-705J-709D01*
G03X226756Y463463I826J-1255D01*
G03X226774Y463363I1486J216D01*
G02X225987Y462178I-979J-204D01*
G03X225961Y462173I271J-1477D01*
G03X225867Y462149I324J-1467D01*
G02X225287Y462860I-136J481D01*
G03X225452Y463458I-1334J690D01*
G03X223567Y465002I-1499J92D01*
G02X222310Y465937I-257J967D01*
G01Y471953D01*
G03X220809Y473454I-1501J0D01*
G01X220340D01*
G02X219840Y473932I0J500D01*
G03X216240I-1800J-79D01*
G02X215740Y473454I-500J22D01*
G01X206509D01*
G03X205008Y471953I0J-1501D01*
G01Y464779D01*
G02X204524Y464279I-500J0D01*
G03X204370Y464267I63J-1801D01*
G03X204406Y460685I215J-1789D01*
G01X204560Y460669D01*
X205025Y460278D01*
X205067Y460133D01*
G03X205256Y459726I1442J422D01*
G03X206509Y459052I1253J828D01*
G01X214794D01*
X214810Y459036D01*
X221426D01*
X222310Y459920D01*
Y461163D01*
G02X223567Y462098I1000J-32D01*
G03X223796Y462056I385J1452D01*
G03X223872Y462050I156J1494D01*
G02X224792Y460935I-73J-997D01*
G03X225222Y459634I1484J-231D01*
G03X227761Y460929I1054J1070D01*
G03X227744Y461022I-1485J-223D01*
G02X228531Y462207I979J204D01*
G03X228573Y462216I-294J1473D01*
G03X228698Y462250I-331J1465D01*
G02X229865Y461754I281J-960D01*
G03X229911Y461673I1589J849D01*
G03X229989Y461552I1552J915D01*
G01X230080Y461423D01*
Y460982D01*
X231938Y459124D01*
X236893D01*
X237222Y458998D01*
X237285Y458946D01*
G03X239575I1145J1392D01*
G01X239638Y458998D01*
X239967Y459124D01*
X241885D01*
X242224Y458988D01*
X242288Y458933D01*
G03X244654I1183J1359D01*
G01X244718Y458988D01*
X245057Y459124D01*
X251386D01*
X251433Y459115D01*
G03X252127I347J1768D01*
G01X252174Y459124D01*
X274334D01*
G02X274771Y458867I0J-500D01*
G03X277923I1576J874D01*
G02X278360Y459124I437J-243D01*
G01X282913D01*
X283870Y460081D01*
Y470832D01*
X284351Y471322D01*
X284523Y471344D01*
G03X284777Y471399I-190J1490D01*
G02X286070Y470526I297J-955D01*
G03X286079Y470442I1497J118D01*
G03X286378Y469731I1488J207D01*
G02Y468567I-813J-582D01*
G03X288500Y466472I1189J-918D01*
G02X289983Y466140I599J-801D01*
G03X290394Y467988I1344J671D01*
G02X288911Y468320I-599J801D01*
G03X288756Y468567I-1344J-671D01*
G02Y469731I813J582D01*
G03X288820Y471476I-1189J917D01*
G03X287122Y472084I-1254J-827D01*
G02X285829Y472957I-297J955D01*
G03X284523Y474324I-1497J-123D01*
G01X284351Y474346D01*
X283870Y474836D01*
Y479590D01*
X283850D01*
Y482695D01*
X283923Y482815D01*
G03X284200Y483803I-1624J988D01*
G01Y486040D01*
X284205Y486074D01*
G03X283666Y487681I-1884J262D01*
G01X282992Y488355D01*
G02X282845Y488708I353J354D01*
G01Y490968D01*
X283379Y491502D01*
X292354D01*
X292566Y491290D01*
Y487225D01*
X294788Y485003D01*
X298568D01*
X298604Y485040D01*
X302766D01*
X303850Y483956D01*
Y477589D01*
G02X303420Y477094I-500J0D01*
G03X302442Y474689I211J-1487D01*
G02Y473525I-813J-582D01*
G03X302199Y473060I1189J-917D01*
G02X301248Y472387I-945J327D01*
G03X300012Y470020I-8J-1502D01*
G03X302731Y470706I1228J865D01*
G02X303328Y471136I497J-60D01*
G37*
G36*
G01X110880Y622655D02*
Y611192D01*
G02X110380Y610692I-500J0D01*
G01X105080D01*
G02X104580Y611192I0J500D01*
G01Y622655D01*
G02X105080Y623155I500J0D01*
G01X110380D01*
G02X110880Y622655I0J-500D01*
G37*
G36*
G01X104760Y650652D02*
X110765D01*
X111120Y650297D01*
Y643023D01*
X110744Y642647D01*
X104690D01*
X104450Y642887D01*
Y650342D01*
X104760Y650652D01*
G37*
G36*
G01X123787Y411332D02*
X146470D01*
X146488Y411313D01*
X148112D01*
X149190Y412391D01*
Y423368D01*
X135200Y437358D01*
Y441638D01*
X135730Y442168D01*
X144102D01*
X147465Y438805D01*
X154630D01*
X156670Y436765D01*
Y411096D01*
X150256Y404682D01*
X137750Y392176D01*
X131734D01*
X129233Y394677D01*
Y399452D01*
X127953Y400732D01*
X124204D01*
X123741Y401195D01*
Y411286D01*
X123787Y411332D01*
G37*
G36*
G01X135518Y492420D02*
X134451Y491353D01*
X130792D01*
X129051Y493094D01*
Y499514D01*
X129184Y499647D01*
X135165D01*
G02X135665Y499147I0J-500D01*
G01Y492773D01*
G02X135518Y492420I-500J1D01*
G37*
G36*
G01X229638Y539296D02*
G02Y538554I-929J-371D01*
G03X229120Y537911I837J-1205D01*
G03X229637Y536146I1356J-561D01*
G02Y535405I-928J-371D01*
G03X229021Y534391I839J-1204D01*
G03X229789Y532905I1455J-190D01*
G03X230437Y532721I686J1182D01*
G03X231165Y532906I40J1366D01*
G03X231381Y533047I-691J1294D01*
G03X231680Y533363I-904J1155D01*
G02X232422I371J-929D01*
G03X232944Y532902I1204J838D01*
G03X234308I682J1185D01*
G03X234830Y533363I-682J1299D01*
G02X235572I371J-929D01*
G03X235871Y533047I1203J839D01*
G03X236087Y532906I907J1153D01*
G03X236815Y532721I688J1181D01*
G03X237463Y532905I-38J1366D01*
G03X238231Y534391I-687J1296D01*
G03X237615Y535405I-1455J-190D01*
G02Y536146I928J371D01*
G03X238145Y536823I-839J1203D01*
G01X238111Y536857D01*
X238136Y537094D01*
G03X237569Y538350I-1360J142D01*
G01X237470Y538420D01*
X237359Y538635D01*
Y538750D01*
G02X237583Y539167I500J0D01*
G03X237705Y539257I-806J1220D01*
G01X238190D01*
X238616Y538831D01*
X240373D01*
X241609Y537595D01*
X243710D01*
X244209Y537096D01*
Y530996D01*
X243909Y530696D01*
X242325D01*
Y530697D01*
X239480D01*
X239250Y530927D01*
X237367D01*
X237134Y531158D01*
X236998Y531294D01*
X236824Y531469D01*
X223794D01*
X223620Y531294D01*
X223253Y530927D01*
X202874D01*
X195709Y523763D01*
Y495267D01*
X193709Y493267D01*
X177251D01*
X172653Y488669D01*
G02X171169Y488747I-707J707D01*
G03X168645Y486223I-1441J-1083D01*
G02X168723Y484739I-629J-777D01*
G01X166368Y482384D01*
X142646D01*
X137180Y487850D01*
Y499984D01*
X134220Y502944D01*
X128701D01*
X128330Y503315D01*
Y506009D01*
X126837Y507502D01*
X125270D01*
X125254Y507486D01*
X120984D01*
X120330Y508140D01*
Y511358D01*
G02X120830Y511858I500J0D01*
G01X123411D01*
X127330Y515777D01*
Y565207D01*
X131390Y569267D01*
X137844D01*
G02X137941Y569262I-3J-1000D01*
G01X142726D01*
G02X142824Y569267I100J-995D01*
G01X155934D01*
G02X156931Y568335I-1J-1000D01*
G03X156985Y568027I1499J104D01*
G02X156054Y566754I-962J-273D01*
G01X155938D01*
X155869Y566774D01*
G03X154749I-560J-1921D01*
G01X154680Y566754D01*
X153208D01*
Y562952D01*
X153308D01*
Y562031D01*
X153268Y561937D01*
G03X156524Y559738I1841J-783D01*
G01X157310Y560524D01*
Y562952D01*
X157410D01*
Y565967D01*
G02X158418Y566935I1000J-32D01*
G03X159912Y568684I12J1502D01*
G01X159905Y568725D01*
Y568767D01*
G02X160405Y569267I500J0D01*
G01X160791D01*
G02X161291Y568767I0J-500D01*
G01Y568746D01*
X161289Y568725D01*
G03X162752Y567097I1497J-126D01*
G03X163995Y567708I34J1502D01*
G02X165488Y567806I790J-613D01*
G03X167212Y567305I1298J1250D01*
G03X168574Y568830I-426J1751D01*
G02X169070Y569267I496J-63D01*
G01X169319D01*
X169579Y569080D01*
X169631Y568928D01*
G03X172475I1422J483D01*
G01X172527Y569080D01*
X172787Y569267D01*
X173560D01*
G02X174016Y568973I0J-500D01*
G01Y568972D01*
G03X176756I1370J617D01*
G01Y568973D01*
G02X177212Y569267I456J-206D01*
G01X177746D01*
G02X178244Y568813I0J-500D01*
G03X181236I1496J138D01*
G02X181734Y569267I498J-46D01*
G01X182609D01*
X182659Y569217D01*
X195290D01*
G02X196056Y568861I1J-1000D01*
G02X196115Y568305I-383J-322D01*
G03X199303I1594J-841D01*
G02X199362Y568861I442J234D01*
G02X200128Y569217I765J-644D01*
G01X205602D01*
G02X205955Y569071I0J-500D01*
G01X208657Y566369D01*
X208694Y566254D01*
G03X210118Y564830I2096J672D01*
G01X210233Y564793D01*
X218976Y556049D01*
Y548378D01*
X219028Y548327D01*
Y547647D01*
X223311Y543364D01*
X224606D01*
X224609Y543367D01*
X227309D01*
X229133Y541543D01*
Y541098D01*
X229101Y541013D01*
G03X229327Y539587I1375J-513D01*
G03X229638Y539296I1147J915D01*
G37*
G36*
G01X153363Y36983D02*
X153256Y36876D01*
X146467D01*
X146325Y37018D01*
Y43630D01*
X146538Y43843D01*
X153185D01*
X153363Y43665D01*
Y36983D01*
G37*
G36*
G01X147188Y382165D02*
X146690Y382663D01*
Y384178D01*
X152084Y389697D01*
X159175Y395914D01*
X159981Y396005D01*
X187811D01*
X190400Y393416D01*
Y382762D01*
X189803Y382165D01*
X185512D01*
X185450Y382181D01*
G03X184698I-376J-1455D01*
G01X184636Y382165D01*
X180169D01*
X177007Y385327D01*
X176953Y385638D01*
X177021Y385782D01*
G03X176703Y387508I-1358J642D01*
G02X176554Y388770I692J722D01*
G03X174250Y388498I-1264J812D01*
G02X174399Y387236I-692J-722D01*
G03X174289Y385817I1264J-812D01*
G03X174387Y385631I1374J605D01*
G01X174462Y385511D01*
X174461Y385311D01*
G02X174096Y384830I-500J0D01*
G03X173004Y383252I404J-1447D01*
G02X172008Y382165I-996J-87D01*
G01X163053D01*
G02X162116Y383516I-1J1000D01*
G03X159248Y384387I-1406J529D01*
G01X159215Y384248D01*
X157132Y382165D01*
X155243D01*
X154795Y382613D01*
X154762Y382752D01*
Y382753D01*
G03X154006Y383735I-1462J-344D01*
G03X153946Y383765I-702J-1328D01*
G03X153321Y383911I-646J-1356D01*
G03X152462Y383656I-21J-1502D01*
G01X152404Y383617D01*
X152115Y383523D01*
X151725Y383717D01*
X151659Y383793D01*
G03X149037Y383022I-1135J-984D01*
G02X148048Y382165I-990J143D01*
G01X147188D01*
G37*
G36*
G01X142949Y443610D02*
X142696Y443863D01*
Y451180D01*
X142870Y451355D01*
X158028D01*
X158135Y451248D01*
Y448783D01*
Y444491D01*
X157254Y443610D01*
X152168D01*
X151990D01*
G03X151101Y443831I-890J-1681D01*
G01X147820D01*
G03X147024Y443656I1J-1902D01*
G01X146924Y443610D01*
X142949D01*
G37*
G36*
G01X142930Y609285D02*
Y616915D01*
Y628575D01*
X142932Y628578D01*
Y630942D01*
X143930Y631940D01*
X146903D01*
X148540Y630303D01*
Y628635D01*
Y619975D01*
X148640Y619875D01*
Y610355D01*
X147040Y608755D01*
X143460D01*
X142930Y609285D01*
G37*
G36*
G01X148618Y602509D02*
G03X150608Y601097I1762J375D01*
G03X151523Y601492I-229J1788D01*
G02X152156Y601493I317J-387D01*
G03X154837Y601628I1266J1550D01*
G01X155663Y602453D01*
X156343Y603133D01*
X157355D01*
G03X157413Y603134I-6J2002D01*
G02X157928Y602634I15J-500D01*
G01Y593633D01*
X156330Y592035D01*
X153137D01*
X153011Y592119D01*
G03X150789I-1111J-1665D01*
G01X150663Y592035D01*
X150130D01*
X149730Y592435D01*
Y597264D01*
G03X147883Y600374I-2075J871D01*
G01X146355Y601902D01*
Y606994D01*
X146968Y607607D01*
G02X147321Y607754I354J-353D01*
G01X147455D01*
X148578Y608877D01*
X148650Y608913D01*
G03X148954Y609101I-896J1789D01*
G01X149154Y609252D01*
Y609262D01*
X149274Y609402D01*
G03X149541Y609804I-1521J1300D01*
G01X149577Y609876D01*
X149642Y609940D01*
Y610036D01*
X149664Y610108D01*
G03X149735Y610981I-1911J595D01*
G01X149730Y611016D01*
Y615530D01*
X149755Y615607D01*
Y615608D01*
G03Y616862I-1900J627D01*
G01Y616863D01*
X149730Y616940D01*
Y618721D01*
X149735Y618756D01*
G03X149754Y619035I-1982J275D01*
G01Y619901D01*
X149775Y619970D01*
G03X149856Y620535I-1920J564D01*
G01Y626610D01*
G03X149775Y627175I-2001J1D01*
G01X149754Y627244D01*
Y627557D01*
G03X149735Y627836I-2001J4D01*
G01X149730Y627871D01*
Y632472D01*
X153159Y635901D01*
X155415D01*
G02X156324Y634485I0J-1000D01*
G03X158177Y631946I1639J-750D01*
G03X159390Y634835I-214J1789D01*
G01X159308Y634941D01*
X159272Y635204D01*
X159322Y635327D01*
X159426Y635587D01*
G02X159890Y635901I464J-186D01*
G01X160615D01*
X160856Y635752D01*
X160920Y635626D01*
G03X164140I1610J809D01*
G01X164204Y635752D01*
X164445Y635901D01*
X167161D01*
G02X168149Y635054I0J-1000D01*
G03X168589Y634125I1781J275D01*
G03X171152Y634005I1341J1204D01*
G02X171844Y633991I339J-368D01*
G01X172255Y633580D01*
Y630370D01*
X173656Y628969D01*
Y627395D01*
X173313Y627052D01*
X158530D01*
X157928Y626450D01*
Y607636D01*
G02X157413Y607136I-500J0D01*
G03X157355Y607137I-64J-2001D01*
G01X154685D01*
X153476Y605927D01*
X152003Y604454D01*
X151647Y604306D01*
X151377Y604388D01*
X151322Y604421D01*
G03X148618Y602509I-942J-1536D01*
G37*
G36*
G01X165563Y663880D02*
G03X163311Y662634I-751J-1301D01*
G02X162312Y661670I-999J36D01*
G01X154312D01*
X151041Y658399D01*
X145000D01*
G02X144500Y658899I0J500D01*
G01Y669956D01*
X146542Y671998D01*
X146286Y672254D01*
Y681719D01*
X147055Y682488D01*
X149049D01*
X150135Y683574D01*
Y690863D01*
X150961Y691689D01*
X153163D01*
X153325Y691851D01*
X161616D01*
X162398Y692632D01*
X167770D01*
X168640Y691763D01*
X170811D01*
X171090Y691484D01*
Y686723D01*
X167063Y682696D01*
Y669938D01*
X166941Y669715D01*
X166834Y669646D01*
G03Y666616I976J-1515D01*
G01X166941Y666547D01*
X167063Y666324D01*
Y664746D01*
G02X165563Y663880I-1000J0D01*
G37*
G36*
G01X141197Y693634D02*
X139908Y694923D01*
X139902Y695326D01*
X140041Y695475D01*
G03X137494Y698022I-1315J1232D01*
G01X137345Y697883D01*
X136942Y697889D01*
X135250Y699581D01*
Y721363D01*
X135202Y721412D01*
Y722598D01*
X134238Y723561D01*
G02X134153Y724155I354J354D01*
G02X134919Y724668I877J-481D01*
G03X136204Y725771I-166J1493D01*
G02X137130Y726511I966J-259D01*
G03X138067Y729136I-60J1501D01*
G03X135571Y728106I-997J-1124D01*
G02X134992Y727644I-499J32D01*
G03X134919Y727654I-240J-1483D01*
G02X134030Y728648I111J994D01*
G01Y732237D01*
G02X134907Y733230I1000J0D01*
G03X135679Y735927I-130J1496D01*
G02X135662Y737512I601J799D01*
G03X135769Y739854I-885J1214D01*
G02X135744Y741283I687J727D01*
G03X136099Y741787I-1024J1098D01*
G03X135722Y743501I-1379J595D01*
G02X135555Y743874I333J373D01*
G01Y746861D01*
X135602Y746961D01*
G03X135742Y747621I-1362J634D01*
G01Y747843D01*
X136100Y748201D01*
X169529D01*
G02X170029Y747701I0J-500D01*
G01Y732228D01*
X168498Y730698D01*
Y726902D01*
X170029Y725372D01*
Y722159D01*
X184370Y707818D01*
Y696324D01*
X181680Y693634D01*
X171455D01*
G02X170996Y693934I-1J500D01*
G03X168242I-1377J-599D01*
G02X167783Y693634I-458J200D01*
G01X141197D01*
G37*
G36*
G01X161143Y11337D02*
Y14754D01*
X162088Y15699D01*
X166226D01*
X166276Y15749D01*
X169590D01*
X175400D01*
X190772D01*
X192165D01*
X192595Y15319D01*
Y5926D01*
X192425Y5756D01*
X163060D01*
X161143Y7673D01*
Y11337D01*
G37*
G36*
G01X159847Y40526D02*
Y41632D01*
X162186Y43971D01*
X164228D01*
X169927Y38272D01*
Y26358D01*
X169226Y25657D01*
X164647D01*
X164398Y25906D01*
Y35975D01*
X159847Y40526D01*
G37*
G36*
G01X154728Y290982D02*
X153802Y291908D01*
Y298490D01*
G02X154302Y298990I500J0D01*
G01X169006D01*
X171820Y296176D01*
Y295881D01*
X180852D01*
X181246Y295487D01*
Y294617D01*
X177934Y291305D01*
X159925D01*
X159696Y291436D01*
X159628Y291551D01*
G03X156400Y291298I-1552J-916D01*
G02X155935Y290982I-465J184D01*
G01X154728D01*
G37*
G36*
G01X166775Y290130D02*
Y283567D01*
X166381Y283173D01*
X158385D01*
X156807Y284751D01*
Y286221D01*
X160716Y290130D01*
X166775D01*
G37*
G36*
G01X192060Y294547D02*
G03X194965Y294952I1497J-119D01*
G01X194933Y295036D01*
Y295126D01*
G02X195433Y295626I500J0D01*
G01X196239D01*
X197300Y294565D01*
Y291933D01*
X195320Y289953D01*
Y283236D01*
X194133Y282049D01*
X193869Y281981D01*
X193739Y282018D01*
G03X191445Y280194I-494J-1733D01*
G02X190635Y279162I-999J-50D01*
G03X189420Y277580I283J-1475D01*
G01Y277579D01*
G02X189275Y277191I-499J-35D01*
G01X188750Y276666D01*
X188081D01*
G02X187246Y278216I0J1000D01*
G03X184702Y279813I-1255J825D01*
G01X184273Y279569D01*
X184040Y279627D01*
G03X182925Y279815I-842J-1593D01*
G02X182496Y279956I-75J494D01*
G01X182248Y280204D01*
Y283232D01*
G02X183428Y284215I1000J0D01*
G03Y287171I270J1478D01*
G02X182248Y288154I-180J983D01*
G01Y295902D01*
X182247D01*
Y296286D01*
X181651Y296882D01*
X181267D01*
Y296883D01*
X173408D01*
X169353Y300938D01*
X164410D01*
G02X163519Y302392I0J1000D01*
G03X160843I-1338J683D01*
G02X159952Y300938I-891J-454D01*
G01X155228D01*
G02X154728Y301438I0J500D01*
G01Y306558D01*
G02X155086Y307038I500J1D01*
G01X155087D01*
G03X156364Y309029I-506J1729D01*
G02X157353Y310175I989J146D01*
G01X159962D01*
X160220Y309993D01*
X160274Y309845D01*
G03X162177Y308935I1413J510D01*
G03X162944Y309533I-490J1420D01*
G01X163014Y309639D01*
X163235Y309759D01*
X174288D01*
X174553Y309563D01*
X174601Y309405D01*
G03X177473I1436J440D01*
G01X177521Y309563D01*
X177786Y309759D01*
X178827D01*
G02X179184Y309609I0J-500D01*
G03X179431Y309406I1072J1052D01*
G03X180794Y309261I823J1257D01*
G01X180834Y309277D01*
X180933Y309297D01*
G02X181384Y309160I97J-491D01*
G01X181776Y308768D01*
X186780D01*
X187880Y309868D01*
Y312298D01*
X188340Y312758D01*
X189140D01*
G02X189574Y312506I0J-500D01*
G01X189604Y312454D01*
Y312386D01*
X189730Y312167D01*
Y309490D01*
X189653Y309306D01*
X189604Y309257D01*
Y306780D01*
X189730Y306646D01*
Y303211D01*
X190632D01*
X191368Y302475D01*
X191968Y302453D01*
G02X192415Y302006I-19J-466D01*
G01X192437Y301406D01*
X192550Y301293D01*
Y301036D01*
X190140Y298626D01*
Y296747D01*
X191286Y295601D01*
G02X192060Y294547I-223J-975D01*
G37*
G36*
G01X191388Y627877D02*
G02X191528Y627446I-354J-353D01*
G03X191605Y626507I1977J-311D01*
G01X191630Y626430D01*
Y623642D01*
X191611Y623575D01*
G03Y622491I1927J-542D01*
G01X191630Y622424D01*
Y615440D01*
X191605Y615363D01*
G03Y614107I1900J-628D01*
G01X191630Y614030D01*
Y608540D01*
X191605Y608463D01*
G03Y607207I1900J-628D01*
G01X191630Y607130D01*
Y604442D01*
X191611Y604375D01*
G03Y603291I1927J-542D01*
G01X191630Y603224D01*
Y599542D01*
X191611Y599475D01*
G03Y598391I1927J-542D01*
G01X191630Y598324D01*
Y595440D01*
X191605Y595363D01*
G03Y594107I1900J-628D01*
G01X191630Y594030D01*
Y593735D01*
X190030Y592135D01*
X160730D01*
X158930Y593935D01*
Y603891D01*
X159015Y604017D01*
G03Y606253I-1660J1118D01*
G01X158930Y606379D01*
Y609647D01*
X159022Y609777D01*
G03Y612089I-1634J1156D01*
G01X158930Y612219D01*
Y615382D01*
G03X159456Y616734I-1475J1352D01*
G01Y621695D01*
Y624824D01*
X160623Y625991D01*
X179535D01*
X180079Y626535D01*
X181725D01*
X181802Y626510D01*
X181803D01*
G03X183057I627J1900D01*
G01X183058D01*
X183135Y626535D01*
X185130D01*
X186660Y628065D01*
X187180D01*
X191200D01*
X191388Y627877D01*
G37*
G36*
G01X184730Y659636D02*
Y647224D01*
G02X184230Y646724I-500J0D01*
G01X158710D01*
G02X158210Y647224I0J500D01*
G01Y659636D01*
G02X158710Y660136I500J0D01*
G01X184230D01*
G02X184730Y659636I0J-500D01*
G37*
G36*
G01X181102Y29240D02*
X189673D01*
X200928D01*
X204024D01*
X205280Y27984D01*
Y18744D01*
X204173Y17637D01*
X200605D01*
X189436D01*
X178647D01*
X172169D01*
X171323D01*
X170382Y18578D01*
Y22713D01*
X170426Y22757D01*
Y23516D01*
X172360Y25450D01*
Y27615D01*
X173985Y29240D01*
X176910D01*
X181102D01*
G37*
G36*
G01X178147Y45077D02*
X171109D01*
X170927Y45258D01*
Y52900D01*
Y54729D01*
Y66673D01*
X171657Y67403D01*
X188199D01*
X190222D01*
X190271Y67354D01*
Y51625D01*
X189785Y51139D01*
X188444D01*
X179991D01*
X178700Y49848D01*
Y45630D01*
X178147Y45077D01*
G37*
G36*
G01X177344Y429642D02*
X177213Y429773D01*
Y436153D01*
X177267Y436207D01*
X183873D01*
X183877Y436203D01*
Y428835D01*
X186089Y426623D01*
Y424903D01*
X186134Y424858D01*
Y420624D01*
X186062Y420552D01*
X182394D01*
X181615Y421331D01*
Y425071D01*
X181109Y425577D01*
Y429405D01*
X180872Y429642D01*
X177344D01*
G37*
G36*
G01X181130Y437249D02*
X183867D01*
X183934Y437316D01*
Y439872D01*
Y440008D01*
X186231Y442305D01*
X186843Y442917D01*
Y443952D01*
Y446333D01*
Y453605D01*
X186824Y453624D01*
X185533D01*
X181130D01*
X177651D01*
X176809D01*
X176673Y453488D01*
Y450738D01*
X176792Y450619D01*
X176845Y450566D01*
X177268D01*
X180787D01*
X181130Y450223D01*
Y444666D01*
Y437249D01*
G37*
G36*
G01X193207Y609814D02*
X193169Y609809D01*
X193132D01*
G02X192632Y610309I0J500D01*
G01Y620565D01*
G02X193132Y621065I500J0D01*
G01X193173D01*
X193214Y621058D01*
G03X193538Y621031I328J1975D01*
G01X194857D01*
X196522Y622697D01*
X198545Y624720D01*
G03X199031Y625509I-1415J1416D01*
G03X199129Y626241I-1901J627D01*
G02X200217Y627290I998J53D01*
G03X201617Y630396I163J1795D01*
G03X199128Y630381I-1237J-1311D01*
G03X198643Y629565I1252J-1296D01*
G02X196972Y629124I-964J266D01*
G01X196959Y629137D01*
X193505D01*
G03X192721Y628976I3J-2002D01*
G01X192720D01*
X192625Y628936D01*
X191745D01*
X191615Y629066D01*
X186245D01*
X186115Y628936D01*
X185439D01*
X184040Y627537D01*
X176662D01*
X175982Y628217D01*
Y629428D01*
X173257Y632153D01*
Y632894D01*
X174418Y634055D01*
X175632D01*
X178258Y636681D01*
G02X178966I354J-353D01*
G01X179323Y636323D01*
X179777D01*
G02X180747Y635077I0J-1000D01*
G03X184213I1733J-492D01*
G02X185183Y636323I970J246D01*
G01X199637D01*
X199770Y636223D01*
G03X201932I1081J1442D01*
G01X202065Y636323D01*
X209550D01*
X212082Y633791D01*
Y621974D01*
Y620719D01*
X209979Y618616D01*
X208467D01*
X207748Y617897D01*
G03X207229Y617179I1156J-1382D01*
G01X207191Y617083D01*
X204433Y614325D01*
Y611436D01*
G02X203953Y610936I-500J0D01*
G03Y607334I71J-1801D01*
G02X204433Y606834I-20J-500D01*
G01Y606436D01*
G02X203953Y605936I-500J0D01*
G03Y602334I71J-1801D01*
G02X204433Y601834I-20J-500D01*
G01Y585589D01*
X204350Y585505D01*
Y579185D01*
X204115Y578950D01*
X195570D01*
G02X194681Y580409I0J1000D01*
G03X191479I-1601J826D01*
G02X190590Y578950I-889J-459D01*
G01X177293D01*
X177043Y579114D01*
X176984Y579251D01*
G03X173676I-1654J-716D01*
G01X173617Y579114D01*
X173367Y578950D01*
X169816D01*
X167747Y581019D01*
G02X167839Y582514I707J707D01*
G03X166630Y585734I-1109J1421D01*
G02X165574Y586733I-56J999D01*
G01Y590509D01*
G02X166074Y591009I500J0D01*
G01X173262D01*
G02X174262Y590009I0J-1000D01*
G03X174650Y588773I2001J-51D01*
G01X174674Y588741D01*
X174813Y588556D01*
X174824D01*
X174965Y588436D01*
G03X175088Y588338I1307J1515D01*
G01X175120Y588315D01*
X177001Y586434D01*
G03X177274Y586205I1418J1413D01*
G01X177369Y586139D01*
X177448Y585998D01*
G02X177417Y585461I-436J-244D01*
G01X177267Y585253D01*
X177136Y585198D01*
G03X177568Y581752I694J-1663D01*
G03X179226Y584674I262J1783D01*
G02X179457Y586140I778J629D01*
G03X179835Y589260I-1041J1709D01*
G01X179831Y589264D01*
X179811Y589285D01*
X179794Y589302D01*
G02X180501Y591009I707J707D01*
G01X182384D01*
X182489Y590904D01*
X191510D01*
X192616Y592010D01*
Y593305D01*
X192632Y593320D01*
Y596465D01*
G02X193132Y596965I500J0D01*
G01X193168D01*
G03X193538Y596930I373J1968D01*
G01X195825D01*
X195885Y596892D01*
G03X198446Y599951I1145J1643D01*
G01X197461Y600936D01*
X196846D01*
G02X196514Y601788I22J499D01*
G01X197330Y602605D01*
X198322Y603597D01*
G03Y606427I-1415J1415D01*
G01X196452Y608297D01*
X194913Y609837D01*
X193505D01*
G03X193228Y609817I5J-2002D01*
G03X193210Y609815I212J-1989D01*
G01X193207Y609814D01*
G37*
G36*
G01X194450Y6788D02*
X194036Y7202D01*
Y15969D01*
G02X194536Y16469I500J0D01*
G01X205703D01*
X206410Y15762D01*
Y7569D01*
X205629Y6788D01*
X194450D01*
G37*
G36*
G01X186852Y172023D02*
X185488Y173387D01*
Y215894D01*
X185596Y216002D01*
Y229205D01*
X185652Y229313D01*
G03Y230965I-1602J826D01*
G01X185596Y231073D01*
Y234572D01*
X186605Y235581D01*
G02X187946Y235647I707J-707D01*
G03X190060Y237761I953J1161D01*
G02X190126Y239102I773J634D01*
G01X191850Y240826D01*
Y244540D01*
X194020Y246710D01*
X196151Y248842D01*
X196255Y248964D01*
X196257Y248967D01*
G03X195846Y251273I-1131J988D01*
G02X196020Y252452I882J472D01*
G01X196211Y252644D01*
G02X196566Y252791I354J-353D01*
G01X196800D01*
X198217Y254208D01*
X198395Y254386D01*
X198596Y254587D01*
Y254994D01*
G02X199117Y255404I844J-536D01*
G01X199556Y255191D01*
X199623Y255115D01*
G03X202617Y255557I1354J1190D01*
G03X202698Y255771I-1642J744D01*
G02X203176Y256123I478J-148D01*
G01X203255D01*
X204187Y257055D01*
Y269656D01*
X203581Y270262D01*
G02X203935Y271116I354J354D01*
G01X204285D01*
X205190Y272021D01*
G02X206659Y271926I691J-723D01*
G03X207940Y271212I1442J1081D01*
G02X208816Y270340I-117J-993D01*
G01X209201Y269955D01*
G02X209211Y269258I-354J-354D01*
G03X209323Y267089I1092J-1031D01*
G03X209856Y266793I980J1138D01*
G03X211801Y268341I447J1434D01*
G02X212959Y269403I997J75D01*
G03X213434Y269386I305J1877D01*
G02X214523Y268390I89J-996D01*
G01Y257955D01*
X215073Y257405D01*
X215092Y257381D01*
G03X215403Y257070I1420J1109D01*
G01X215427Y257051D01*
X216536Y255942D01*
X216886D01*
X217073Y255849D01*
G02X217203Y255048I-224J-447D01*
G01X216350Y254195D01*
Y251644D01*
X216062Y251356D01*
Y248552D01*
X217020D01*
X217096Y248527D01*
G03X218032I468J1427D01*
G01X218108Y248552D01*
X219066D01*
Y249332D01*
X219354Y249620D01*
Y252951D01*
X219485Y253082D01*
X221035D01*
X221829Y253876D01*
G02X223536Y253169I707J-707D01*
G01Y250050D01*
X222606Y249120D01*
Y248297D01*
X222466Y248157D01*
Y244827D01*
X222966Y244327D01*
Y236162D01*
X222680Y235876D01*
X222403Y235600D01*
X219479D01*
G02X218561Y236913I31J999D01*
G03X218637Y237376I-1426J472D01*
G03X218344Y238277I-1502J10D01*
G02X218439Y239541I819J574D01*
G03X215831I-1304J1244D01*
G02X215926Y238277I-724J-690D01*
G03X215633Y237376I1209J-891D01*
G03X215709Y236913I1502J9D01*
G02X214791Y235600I-949J-314D01*
G01X214279D01*
G02X213361Y236913I31J999D01*
G03X213037Y238406I-1426J472D01*
G02Y239764I734J679D01*
G03X210833I-1102J1021D01*
G02Y238406I-734J-679D01*
G03X210509Y236913I1102J-1021D01*
G02X209591Y235600I-949J-314D01*
G01X207928D01*
X207918Y235599D01*
X207188D01*
G02X206829Y235751I0J500D01*
G03X204241I-1294J-1254D01*
G02X203882Y235599I-359J348D01*
G01X203786D01*
Y234934D01*
X203774Y234881D01*
G03Y234113I1761J-384D01*
G01X203786Y234060D01*
Y229119D01*
X203774Y229066D01*
G03Y228298I1761J-384D01*
G01X203786Y228245D01*
Y226607D01*
X205467Y224926D01*
Y218725D01*
X205730Y218462D01*
Y214579D01*
X208580Y211729D01*
Y174159D01*
X206444Y172023D01*
X186852D01*
G37*
G36*
G01X193457Y301850D02*
X193450Y302045D01*
G03X192007Y303488I-1501J-58D01*
G01X191812Y303495D01*
X190912Y304395D01*
X190864Y304722D01*
X190943Y304868D01*
G03X190640Y307190I-1761J951D01*
G01Y308828D01*
X190956Y309144D01*
Y311603D01*
G03X190706Y312547I-1901J2D01*
G01X190640Y312662D01*
Y314352D01*
G02X190787Y314707I500J1D01*
G01X190931Y314850D01*
X195655D01*
X195660Y314855D01*
X197235D01*
X197841Y314249D01*
Y311848D01*
X195119Y309126D01*
Y307255D01*
X196747Y305627D01*
X204343D01*
X204710Y305260D01*
Y301946D01*
X204614D01*
Y301504D01*
X204536Y301382D01*
G03X204399Y301120I1478J-940D01*
G02X203938Y300813I-461J193D01*
G01X202902D01*
X202849Y300825D01*
G03X202201I-324J-1467D01*
G01X202148Y300813D01*
X201125D01*
X199855Y299543D01*
X193986D01*
X193682Y299847D01*
Y301625D01*
X193457Y301850D01*
G37*
G36*
G01X188374Y453941D02*
X198212D01*
X198960D01*
X201256Y451645D01*
Y444119D01*
X200236Y443099D01*
X197789D01*
X188215D01*
Y453782D01*
X188374Y453941D01*
G37*
G36*
G01X180470Y575287D02*
X180703Y575520D01*
X189295D01*
X189760Y575055D01*
Y570940D01*
X189258Y570438D01*
X181050D01*
X180470Y571018D01*
Y575287D01*
G37*
G36*
G01X210710Y25920D02*
X253252D01*
X254270Y24902D01*
Y7737D01*
X252630Y6097D01*
X210087D01*
X209140Y7044D01*
Y24350D01*
X210710Y25920D01*
G37*
G36*
G01X221560Y58321D02*
X255486D01*
X255760Y58047D01*
Y35714D01*
X253540Y33494D01*
Y29399D01*
X252138Y27997D01*
X210825D01*
X208986Y29836D01*
X202950Y35872D01*
Y51851D01*
X205188Y54089D01*
X217328D01*
X221560Y58321D01*
G37*
G36*
G01X210545Y234074D02*
G03X210587Y233908I1475J285D01*
G03X210897Y233361I1433J451D01*
G02X210771Y231961I-771J-636D01*
G03X211864Y228784I1163J-1376D01*
G03X213565Y231354I71J1801D01*
G03X213141Y231924I-1630J-769D01*
G02X213101Y233316I698J717D01*
G03X213157Y233377I-1078J1046D01*
G03X213333Y233629I-1137J982D01*
G03X213509Y234163I-1313J729D01*
G01X213534Y234350D01*
X213816Y234598D01*
X222818D01*
X223526Y235306D01*
G03X223546Y235326I-1052J1072D01*
G01X223629Y235409D01*
X223968Y235747D01*
Y238068D01*
G02X225347Y238994I1000J0D01*
G03X225912Y238843I663J1348D01*
G02X226794Y237926I-116J-995D01*
G01Y236259D01*
G02X225871Y235339I-998J78D01*
G03Y231745I139J-1797D01*
G02X226794Y230825I-75J-998D01*
G01Y222738D01*
X226458Y222402D01*
X225446D01*
Y217403D01*
X225445D01*
Y215399D01*
X231399D01*
Y218403D01*
X231398D01*
Y222402D01*
X230997D01*
G02X230546Y222848I48J500D01*
G01Y231699D01*
G02X232008Y232510I999J-77D01*
G03Y235584I940J1537D01*
G02X230546Y236395I-463J888D01*
G01Y237521D01*
G02X231605Y238443I998J-77D01*
G03X233014Y241486I105J1799D01*
G02X232919Y242750I724J690D01*
G03X233038Y242940I-1210J890D01*
G03X232982Y244441I-1328J702D01*
G03X230700Y244754I-1272J-798D01*
G03X230313Y244194I1010J-1112D01*
G01X230275Y244097D01*
X229996Y243818D01*
X228878D01*
X226862Y241802D01*
X226592Y241735D01*
X226459Y241776D01*
G03X226402Y241792I-434J-1438D01*
G03X226296Y241817I-398J-1448D01*
G03X225764Y241824I-285J-1475D01*
G03X225621Y241793I246J-1482D01*
G03X225471Y241744I391J-1450D01*
G03X225347Y241690I537J-1403D01*
G02X223968Y242616I-379J926D01*
G01Y243940D01*
X224299Y244272D01*
Y245518D01*
G02X224799Y246018I500J0D01*
G01X229632D01*
X230876Y247261D01*
X231820Y248205D01*
Y248420D01*
X231885Y248535D01*
G03Y250315I-1567J890D01*
G01X231820Y250430D01*
Y252974D01*
X233084Y254239D01*
Y258315D01*
X233141Y258424D01*
G03X233168Y258478I-1386J727D01*
G01X233228Y258608D01*
X233585Y258841D01*
X235211D01*
X235256Y258795D01*
Y255851D01*
X235851Y255256D01*
X236319Y254789D01*
X236371Y254737D01*
G02X236631Y253907I-729J-684D01*
G03X236308Y253531I962J-1153D01*
G03X236111Y252994I1286J-776D01*
G03X236475Y251753I1483J-239D01*
G02X236439Y251050I-373J-333D01*
G03X235872Y249450I1215J-1331D01*
G03X236501Y248334I1782J269D01*
G03X237777Y247921I1153J1385D01*
G02X238810Y246921I33J-1000D01*
G01Y246242D01*
X239310Y245742D01*
X239570D01*
G02X240070Y245242I0J-500D01*
G01Y245215D01*
X240162D01*
G02X240662Y244715I0J-500D01*
G01Y240726D01*
X246616D01*
Y246048D01*
X246810Y246242D01*
Y251485D01*
G02X247310Y251985I500J0D01*
G01X248970D01*
G02X249470Y251485I0J-500D01*
G01Y248430D01*
X249436D01*
Y247017D01*
X249435Y247003D01*
G03Y246851I1402J-76D01*
G01X249436Y246837D01*
Y245428D01*
X252238D01*
Y246348D01*
X252274Y246383D01*
Y247762D01*
G02X253981Y248469I1000J0D01*
G01X254992Y249480D01*
X255039Y249509D01*
G03X255069Y249529I-1040J1592D01*
G01X255197Y249616D01*
X255424D01*
Y249834D01*
G03X255545Y249978I-1394J1294D01*
G03X255566Y250007I-1529J1130D01*
G03X255610Y250071I-1545J1109D01*
G03X255625Y250094I-1585J1050D01*
G01X255655Y250143D01*
X255924Y250412D01*
Y254330D01*
X255964Y254370D01*
Y254597D01*
G02X256463Y255382I998J-84D01*
G03X257967Y257388I90J1499D01*
G02X258144Y257963I470J170D01*
G03X258171Y260412I-891J1234D01*
G02X258146Y260880I958J286D01*
G01X258252Y261131D01*
X258635Y261287D01*
X258986Y261141D01*
X259051Y261081D01*
G03X259152Y260996I1017J1106D01*
G03X260990Y261001I916J1191D01*
G03X261132Y261127I-924J1184D01*
G01X261311Y261195D01*
X261769D01*
G02X262269Y260695I0J-500D01*
G01Y260581D01*
X262172Y260377D01*
X262084Y260306D01*
G03X262080Y257975I945J-1167D01*
G01X262221Y257860D01*
X262290Y257501D01*
X262200Y257341D01*
G03X262112Y257161I1572J-880D01*
G03X262030Y256009I1662J-697D01*
G03X264123Y254696I1744J455D01*
G03X265218Y255385I-348J1768D01*
G02X266419Y255703I801J-599D01*
G03X265755Y257888I601J1376D01*
G02X264995Y257790I-421J270D01*
G03X264762Y257972I-1222J-1325D01*
G01X264662Y258037D01*
X264426Y258444D01*
X264463Y258690D01*
X264479Y258748D01*
X264487Y258778D01*
G03X264222Y260052I-1458J361D01*
G02X264332Y261309I828J561D01*
G03X264511Y261526I-1064J1060D01*
G03X264742Y262080I-1243J843D01*
G03X264636Y262991I-1474J290D01*
G03X264435Y263316I-1368J-621D01*
G02X264470Y263985I388J315D01*
G01X265997Y265512D01*
X266018Y265529D01*
G03X266522Y266300I-945J1168D01*
G03X265966Y267904I-1449J396D01*
G03X264983Y268196I-893J-1207D01*
G02X264472Y268556I-31J499D01*
G03X264410Y268730I-1443J-416D01*
G01X264395Y268764D01*
G03X263958Y269319I-1365J-626D01*
G02Y269959I947J320D01*
G03X264129Y270116I-927J1182D01*
G02X265254Y270355I732J-681D01*
G03X265568Y270250I631J1364D01*
G03X266002Y270220I319J1468D01*
G01X266111Y270228D01*
X266317Y270152D01*
X269733Y266735D01*
X271122D01*
G02X271569Y266630I1J-1000D01*
G01X271763Y266357D01*
X271742Y266144D01*
X271739Y266125D01*
G03X271742Y265559I1782J-274D01*
G02X271225Y264516I-987J-160D01*
G03X270638Y262355I673J-1343D01*
G03X270825Y262121I1261J816D01*
G02X270935Y260918I-738J-674D01*
G03X270930Y259018I1529J-954D01*
G02X270771Y257771I-851J-525D01*
G03X273187Y257290I1040J-1084D01*
G02X273518Y258502I916J401D01*
G03X273871Y258838I-1054J1461D01*
G03X274250Y260203I-1407J1126D01*
G03X273556Y261398I-1786J-238D01*
G02X273264Y262547I635J773D01*
G03X273371Y262877I-1366J625D01*
G03X273396Y263059I-1473J295D01*
G01Y263062D01*
X273397Y263078D01*
G03X273389Y263355I-1499J95D01*
G01X273376Y263460D01*
X273437Y263661D01*
X273779Y264058D01*
X273936Y264095D01*
G03X274016Y264116I-417J1753D01*
G03X274147Y264159I-496J1732D01*
G03X274166Y264166I-613J1694D01*
G01X274253Y264204D01*
X274673D01*
X274984Y264012D01*
X275047Y263902D01*
G03X275050Y263897I1289J770D01*
G03X275069Y263867I1278J789D01*
G03X277420Y263655I1259J820D01*
G02X278275Y263464I232J-973D01*
G01X278632D01*
X278729Y263421D01*
G03X279395Y263294I607J1374D01*
G02X280405Y262539I40J-999D01*
G03X280434Y262424I1761J383D01*
G03X280489Y262262I1732J498D01*
G03X280765Y261789I1676J661D01*
G01X280875Y261653D01*
X280877Y261299D01*
X280766Y261161D01*
G03X280742Y261130I1175J-935D01*
G02X279527Y260789I-817J576D01*
G03X277096Y258581I-716J-1654D01*
G03X280413Y258309I1715J554D01*
G02X281548Y258782I871J-491D01*
G03X283283Y260914I397J1449D01*
G01X283258Y260963D01*
X283196Y261201D01*
X283362Y261570D01*
X283429Y261636D01*
G03X283531Y261745I-1264J1285D01*
G03X283591Y261819I-1369J1172D01*
G03X283618Y261854I-1413J1118D01*
G02X285106Y261937I781J-624D01*
G01X285859Y261184D01*
G02X285715Y259650I-707J-707D01*
G03X285196Y259124I777J-1285D01*
G03X285009Y258127I1296J-759D01*
G03X286258Y256880I1483J237D01*
G03X286326Y256871I231J1484D01*
G02X287215Y255877I-111J-994D01*
G01Y252182D01*
G02X286715Y251682I-500J0D01*
G01X285644D01*
X284722Y252604D01*
G03X282598Y250480I-1062J-1062D01*
G01X284400Y248678D01*
X284433D01*
X285049Y248062D01*
X285858D01*
G02X286012Y248038I1J-500D01*
G01X287684D01*
X287900Y247822D01*
Y245982D01*
X287352Y245434D01*
X285877D01*
G03X284792Y244910I57J-1503D01*
G02X283325Y244975I-703J711D01*
G03X282771Y245385I-1147J-970D01*
G03X282669Y245424I-587J-1382D01*
G01X282636Y245435D01*
G03X282395Y245491I-459J-1430D01*
G01X282210Y245518D01*
X281968Y245799D01*
Y247678D01*
G03X281468Y248963I-1901J0D01*
G01Y249180D01*
X281243D01*
X281118Y249263D01*
G03X279016I-1051J-1585D01*
G01X278891Y249180D01*
X278666D01*
Y248963D01*
G03X278166Y247678I1401J-1285D01*
G01Y246783D01*
X277009Y245626D01*
G03X279699Y242936I1345J-1345D01*
G01X279703Y242941D01*
G02X281104Y242955I708J-707D01*
G03X281130Y242929I1075J1049D01*
G03X281179Y242883I1052J1072D01*
G03X281501Y242664I999J1122D01*
G03X283291Y242996I677J1341D01*
G02X284756I733J-681D01*
G03X286776Y242685I1178J935D01*
G01X286903Y242771D01*
X289291D01*
X289407Y242704D01*
G03X289800Y242547I748J1302D01*
G03X290323Y242514I355J1460D01*
G03X291008Y242771I-169J1493D01*
G03X291108Y242846I-851J1238D01*
G01X291109Y242847D01*
G02X291779Y242813I316J-387D01*
G01X295001Y239591D01*
Y174174D01*
X292918Y172091D01*
X272259Y170857D01*
X231820Y159626D01*
X216923D01*
X211020Y165529D01*
Y172272D01*
X211070Y172322D01*
Y213135D01*
X207467Y216738D01*
Y234098D01*
G02X207967Y234598I500J0D01*
G01X210229D01*
X210515Y234338D01*
X210533Y234146D01*
G03X210535Y234131I1487J191D01*
G03X210545Y234074I1484J231D01*
G37*
G36*
G01X200399Y274018D02*
Y275377D01*
X201065Y276043D01*
X201410Y276083D01*
X201558Y275992D01*
G03X203608Y276024I1000J1617D01*
G01X203734Y276107D01*
X204006D01*
G02X204506Y275607I0J-500D01*
G01Y274736D01*
X203289Y273518D01*
X200899D01*
G02X200399Y274018I0J500D01*
G37*
G36*
G01X219294Y295157D02*
X219141Y295004D01*
X216533D01*
X216292Y295245D01*
X214910D01*
X213982Y294317D01*
Y290587D01*
X212922Y289527D01*
X211705D01*
X211344Y289888D01*
Y294800D01*
X210970Y295174D01*
X208672D01*
X208581Y295265D01*
Y302309D01*
X208109Y302781D01*
Y304766D01*
X208670Y305327D01*
X209676D01*
Y305307D01*
X210725Y304258D01*
X212757D01*
X214222Y302793D01*
X216331D01*
X217375Y301749D01*
Y299338D01*
X219294Y297419D01*
Y295157D01*
G37*
G36*
G01X211210Y280930D02*
Y281608D01*
X210010Y282808D01*
X207928D01*
X207545Y283191D01*
Y284785D01*
G02X208045Y285285I500J0D01*
G01X212703D01*
X212916Y285072D01*
Y282172D01*
X213716Y281372D01*
Y280572D01*
G02X213696Y280430I-500J-2D01*
G01X211710D01*
G02X211210Y280930I0J500D01*
G37*
G36*
G01X229763Y279892D02*
X229702Y279953D01*
Y282879D01*
X229331Y283250D01*
X224434D01*
X224146Y282962D01*
X221529D01*
X221018Y283473D01*
Y288146D01*
G02X221688Y289090I1000J0D01*
G03X222813Y289255I361J1458D01*
G01X222837Y289269D01*
X223177Y289423D01*
X223332Y289766D01*
X223346Y289789D01*
G03X221973Y292049I-1296J759D01*
G01X221952Y292047D01*
X221946D01*
G03X220586Y290889I103J-1499D01*
G02X219483Y290124I-974J226D01*
G03X217532Y289027I-283J-1780D01*
G01X217494Y288935D01*
X217275Y288716D01*
X216822D01*
X216739Y288730D01*
G02X216306Y288793I-76J997D01*
G03X215868Y288895I-556J-1395D01*
G03X214815Y288574I-119J-1497D01*
G01X214680Y288467D01*
X214573Y288332D01*
G03X214478Y288198I1176J-934D01*
G03X214347Y287938I1270J-803D01*
G03X216026Y285922I1401J-540D01*
G03X216645Y286192I-276J1477D01*
G03X216966Y286517I-896J1206D01*
G02X218284Y286792I810J-586D01*
G03X218325Y286762I1078J1430D01*
G02X218536Y286354I-289J-408D01*
G01Y283452D01*
X217560Y282476D01*
X216354D01*
X216270Y282507D01*
G03X214833Y282288I-520J-1409D01*
G01X214683Y282173D01*
X214308Y282197D01*
X213918Y282587D01*
Y285487D01*
X213118Y286287D01*
X206718D01*
X206318Y285887D01*
Y283587D01*
X206118Y283387D01*
X204291D01*
X201718Y285960D01*
Y287987D01*
X202418Y288687D01*
X207518D01*
X208018Y289187D01*
Y290209D01*
X208025Y290251D01*
G03Y290845I-1726J297D01*
G01X208018Y290887D01*
Y293359D01*
X208025Y293401D01*
G03X208040Y293510I-1727J293D01*
G01X208059Y293687D01*
X208550Y294172D01*
X209842D01*
G02X210342Y293672I0J-500D01*
G01Y289473D01*
X211290Y288525D01*
X213337D01*
X213845Y289033D01*
X213864D01*
X214918Y290087D01*
Y290107D01*
X214984Y290172D01*
Y291353D01*
X215218Y291587D01*
X215918D01*
X216032Y291701D01*
X216330Y291760D01*
X216748Y291586D01*
X217241D01*
X217349Y291531D01*
G03X218951I801J1557D01*
G01X219059Y291586D01*
X219552D01*
Y292028D01*
X219630Y292151D01*
G03X219896Y292953I-1480J936D01*
G01X219911Y293149D01*
X220199Y293415D01*
X220318D01*
Y294887D01*
X220296Y294909D01*
Y297834D01*
X220082Y298047D01*
G02X219935Y298402I353J354D01*
G01Y298645D01*
X220519Y299229D01*
Y300643D01*
X221009Y301133D01*
X222873D01*
G02X223227Y300986I0J-500D01*
G01X223596Y300616D01*
Y299292D01*
X224473Y298416D01*
X226022D01*
X226715Y299109D01*
Y300207D01*
G02X226862Y300561I500J0D01*
G01X227136Y300834D01*
X227141D01*
X227197Y300891D01*
X229148D01*
Y301003D01*
X231933D01*
X232626Y300310D01*
X232658Y300169D01*
G03X232696Y300030I1948J458D01*
G01X232719Y299957D01*
Y298734D01*
X233219Y298234D01*
X237085D01*
X237166Y298205D01*
G03X237640Y298103I634J1793D01*
G02X238098Y297605I-42J-498D01*
G01Y294546D01*
X238490Y294153D01*
Y293221D01*
X237937Y292668D01*
X232713D01*
X232530Y292485D01*
Y289936D01*
X232325Y289731D01*
X230810D01*
X230396Y290145D01*
Y292788D01*
X229897Y293287D01*
X227148D01*
X226340Y292479D01*
Y289875D01*
X225963Y289498D01*
X224518D01*
X224512Y289493D01*
Y289481D01*
X224253Y289222D01*
X224193Y289188D01*
G03X224047Y289098I976J-1747D01*
G01X223815Y288941D01*
X223663Y288788D01*
X223508Y288557D01*
G03X223423Y288419I1660J-1118D01*
G01X223389Y288358D01*
X223018Y287987D01*
Y286887D01*
X223679Y286226D01*
X224062Y285841D01*
X231664D01*
X232418Y285087D01*
Y280221D01*
X232089Y279892D01*
X229763D01*
G37*
G36*
G01X204952Y307701D02*
X204692Y307442D01*
X203951Y306701D01*
X197089D01*
X196120Y307670D01*
Y308711D01*
X198842Y311433D01*
Y314904D01*
X199275Y315337D01*
X201088D01*
G02X201588Y314837I0J-500D01*
G01Y312014D01*
X202551Y311051D01*
X208620D01*
X208720Y311006D01*
G03X210178I729J1592D01*
G01X210278Y311051D01*
X210719D01*
X211082Y311414D01*
Y311959D01*
X211108Y312037D01*
G03X211200Y312598I-1659J560D01*
G01Y314024D01*
X211372Y314195D01*
X213487D01*
X213708Y313974D01*
Y308241D01*
X214861Y307088D01*
X216617D01*
X216818Y306887D01*
Y304387D01*
X216618Y304187D01*
X214244D01*
X213172Y305260D01*
X212046D01*
X210918Y306387D01*
X208377D01*
X206848Y307916D01*
X206260D01*
X206249Y307927D01*
X205178D01*
X204952Y307701D01*
G37*
G36*
G01X223260Y312842D02*
Y311215D01*
X224033Y310442D01*
X231760D01*
G02X232113Y310295I-1J-500D01*
G01X232552Y309856D01*
Y308828D01*
X232165Y308440D01*
G02X231811Y308293I-354J353D01*
G01X230116D01*
Y308275D01*
X215491D01*
X214794Y308972D01*
G02X214718Y309237I424J265D01*
G01Y314245D01*
X214710Y314253D01*
Y314389D01*
X214624Y314476D01*
Y316253D01*
X208588Y322289D01*
G02X208479Y322831I354J353D01*
G01X208514Y322918D01*
X208571Y322983D01*
X208572Y322984D01*
G03X208949Y323668I-1307J1166D01*
G03X209522Y326164I-949J1532D01*
G02X209634Y326824I422J268D01*
G03X209865Y327052I-933J1177D01*
G02X210253Y327236I387J-316D01*
G01X210714D01*
X211396Y327917D01*
X217511D01*
X217790Y327640D01*
X217866Y327455D01*
Y326227D01*
X218249Y325844D01*
Y325413D01*
X218577Y325085D01*
X222054D01*
X222360Y324779D01*
Y322970D01*
G02X221860Y322470I-500J0D01*
G01X220922D01*
X220532Y322080D01*
Y314973D01*
X221320Y314184D01*
Y314116D01*
X221389D01*
X221618Y313886D01*
X222215D01*
X222386Y313716D01*
X222388Y313714D01*
G03X222405Y313697I1070J1053D01*
G01X223260Y312842D01*
G37*
G36*
G01X224080Y321940D02*
X223680Y322340D01*
Y325730D01*
X223323Y326087D01*
X223322D01*
X223134Y326275D01*
X219442D01*
G02X219087Y326422I-1J500D01*
G01X218868Y326642D01*
Y327979D01*
X218677Y328168D01*
G02X218530Y328523I353J354D01*
G01Y328718D01*
X218326Y328922D01*
X215294D01*
X215243Y328919D01*
X211390D01*
X210810Y329499D01*
Y335942D01*
X210010Y336742D01*
X206730D01*
X206680Y336752D01*
G03X205956I-362J-1765D01*
G01X205906Y336742D01*
X204567D01*
X203023Y338286D01*
Y344392D01*
X204744Y346113D01*
X215330D01*
G02X215830Y345613I0J-500D01*
G01Y340404D01*
X215764Y340289D01*
G03X215642Y339069I1303J-746D01*
G01X215667Y338992D01*
Y336555D01*
X215657Y336506D01*
G03Y335908I1472J-299D01*
G01X215667Y335859D01*
Y333555D01*
X215657Y333506D01*
G03Y332908I1472J-299D01*
G01X215667Y332859D01*
Y332502D01*
X215683Y332486D01*
Y332284D01*
X216191Y331776D01*
X216668D01*
X216733Y331758D01*
G03X217525I396J1449D01*
G01X217590Y331776D01*
X218097D01*
X218136Y331816D01*
X222223D01*
X222317Y331775D01*
G03X223505I594J1380D01*
G01X223599Y331816D01*
X225414D01*
X226016Y331214D01*
Y326111D01*
X226311Y325815D01*
Y322354D01*
X225897Y321940D01*
X224080D01*
G37*
G36*
G01X215514Y354356D02*
X216119Y353751D01*
Y348512D01*
X215470Y347863D01*
X206546D01*
X205110Y349299D01*
Y353780D01*
X205686Y354356D01*
X215514D01*
G37*
G36*
G01X207930Y381448D02*
X207270Y382108D01*
Y383832D01*
X206588Y384514D01*
Y385260D01*
X205232Y386617D01*
G03X204372Y387111I-1345J-1345D01*
G01X204321Y387124D01*
X204216Y387176D01*
G02X203940Y387624I224J447D01*
G01Y401954D01*
X205660Y403674D01*
X217464D01*
X218300Y402838D01*
Y393175D01*
X217871Y392688D01*
X217710Y392653D01*
G03X216313Y391188I381J-1761D01*
G02X215133Y390371I-987J164D01*
G03X213142Y387866I-347J-1768D01*
G02X212842Y386667I-913J-409D01*
G03X212663Y386510I1162J-1505D01*
G01X210786Y384632D01*
Y382271D01*
G03X210803Y382024I1901J7D01*
G01X210807Y381991D01*
Y381948D01*
G02X210307Y381448I-500J0D01*
G01X207930D01*
G37*
G36*
G01X215225Y460037D02*
X215209Y460053D01*
X206509D01*
G02X206009Y460553I0J500D01*
G01Y461365D01*
X206091Y461490D01*
G03Y463466I-1507J988D01*
G01X206009Y463591D01*
Y471953D01*
G02X206509Y472453I500J0D01*
G01X216895D01*
X217023Y472366D01*
G03X219057I1017J1487D01*
G01X219185Y472453D01*
X220809D01*
G02X221309Y471953I0J-500D01*
G01Y460335D01*
X221011Y460037D01*
X215225D01*
G37*
G36*
G01X217209Y485353D02*
X207709D01*
X207209Y485853D01*
Y494065D01*
X207575Y494431D01*
X210639D01*
X215231D01*
X216207Y493455D01*
Y490085D01*
Y489938D01*
X217709Y488437D01*
Y485853D01*
G02X217209Y485353I-500J0D01*
G37*
G36*
G01X198258Y494323D02*
X204328D01*
X204648Y494003D01*
Y486193D01*
X203978Y485523D01*
X196608D01*
X196328Y485803D01*
Y492393D01*
X198258Y494323D01*
G37*
G36*
G01X207013Y496890D02*
X202574Y501329D01*
Y511209D01*
X203218Y511853D01*
X217707D01*
G02X218207Y511353I0J-500D01*
G01Y501268D01*
X217844Y500905D01*
X212476D01*
X211844D01*
X210908Y499968D01*
Y499337D01*
X208461Y496890D01*
X207013D01*
G37*
G36*
G01X255680Y59882D02*
X255156Y59358D01*
X220994D01*
X219370Y60982D01*
Y67652D01*
G02X219870Y68152I500J0D01*
G01X254897D01*
X255680Y67369D01*
Y59882D01*
G37*
G36*
G01X341559Y69947D02*
G02X340852Y71654I0J1000D01*
G01X341165Y71968D01*
G03X338335Y74798I-1415J1415D01*
G01X335371Y71834D01*
X264632D01*
G02X264279Y71981I1J500D01*
G01X262831Y73429D01*
G02X262823Y74835I707J707D01*
G03X260699Y76959I-1073J1051D01*
G02X259293Y76967I-699J715D01*
G01X257546Y78714D01*
X222276D01*
X222003Y78987D01*
X221387D01*
X217910Y82464D01*
Y86585D01*
X218087Y86842D01*
X218477Y86991D01*
G02X219009Y86877I178J-467D01*
G01X219588Y86297D01*
Y84629D01*
G03X220188Y83201I2002J1D01*
G01Y83127D01*
X220257D01*
X220390Y83027D01*
G03X222790I1200J1602D01*
G01X222923Y83127D01*
X226142D01*
Y86131D01*
X225942Y86332D01*
Y87007D01*
X226510Y87576D01*
X226704Y87585D01*
G03X227491Y87807I-83J1800D01*
G02X228674Y87646I483J-875D01*
G03X231183Y89080I1051J1073D01*
G02X231698Y90210I971J240D01*
G03X232485Y91844I-685J1337D01*
G02X233329Y93032I981J197D01*
G03X233553Y93076I-235J1787D01*
G01X233688Y93028D01*
X233884Y92959D01*
X234063Y92585D01*
X233946Y92255D01*
X233902Y92195D01*
G03X234638Y89882I1211J-888D01*
G02X235317Y88839I-317J-949D01*
G03X237287Y90123I1495J-141D01*
G02X236608Y91166I317J949D01*
G03X236592Y91570I-1495J143D01*
G02X236947Y92522I985J175D01*
G02X237762Y92121I315J-389D01*
G03X239023Y93796I1801J-44D01*
G02X237779Y94423I-299J954D01*
G03X237084Y95247I-1419J-492D01*
G02X236617Y96435I483J876D01*
G03X235968Y98190I-1427J470D01*
G02X235589Y99489I517J856D01*
G03X233465Y98871I-1346J667D01*
G02X233844Y97572I-517J-856D01*
G03X233720Y97214I1346J-667D01*
G01X233686Y97054D01*
X233208Y96624D01*
X233025Y96618D01*
G03X231364Y94276I58J-1801D01*
G02X230651Y93005I-954J-301D01*
G03X229668Y90879I362J-1458D01*
G02X229346Y90172I-448J-223D01*
G03X229206Y90129I370J-1456D01*
G02X228061Y90467I-345J938D01*
G03X225874Y91025I-1441J-1082D01*
G02X224470Y91796I-414J911D01*
G03X222964Y93089I-1487J-209D01*
G02X221970Y93900I-12J1000D01*
G03X219370Y95161I-1770J-339D01*
G02X217910Y96048I-460J888D01*
G01Y98601D01*
G02X219124Y99578I1000J0D01*
G03X219102Y103093I386J1760D01*
G02X218502Y103465I-113J487D01*
G03X218073Y104211I-1462J-344D01*
G01X218069Y104215D01*
X217910Y104374D01*
Y106794D01*
G02X218410Y107294I500J0D01*
G01X218501D01*
X218585Y107263D01*
G03X218690Y107229I515J1411D01*
G01X218839Y107187D01*
X219206Y106747D01*
Y106474D01*
X219201Y106438D01*
G03X221371Y107934I1782J-264D01*
G02X220590Y108816I215J977D01*
G03X218984Y110173I-1495J-141D01*
G02X217910Y111170I-74J997D01*
G01Y132051D01*
X219748Y133889D01*
Y136645D01*
X226850Y143747D01*
X286950Y158062D01*
X419471D01*
G02X419971Y157562I0J-500D01*
G01Y157559D01*
G03X422975I1502J-3D01*
G01Y157562D01*
G02X423475Y158062I500J0D01*
G01X426290D01*
X428480Y155872D01*
Y152685D01*
X438800D01*
X445134Y146351D01*
X445171Y146275D01*
G03X445865Y145581I1351J657D01*
G01X445941Y145544D01*
X469430Y122055D01*
Y108797D01*
X462756Y102123D01*
X456743D01*
X454970Y103896D01*
Y107513D01*
X454550Y107933D01*
X447046D01*
X446570Y107457D01*
Y102623D01*
G02X446070Y102123I-500J0D01*
G01X424127D01*
X420533Y98529D01*
G02X418833Y99111I-708J707D01*
G03X414473Y94750I-3872J-489D01*
G02X415054Y93050I-126J-992D01*
G01X410212Y88208D01*
G02X408504Y88915I-708J707D01*
G01Y89633D01*
G02X409327Y90617I1000J0D01*
G03X409462Y93542I-267J1478D01*
G02X408760Y94750I268J963D01*
G03X405890Y95626I-1456J368D01*
G02X405268Y95318I-471J169D01*
G03X403840Y95031I-455J-1431D01*
G02X402584Y94999I-648J762D01*
G03X401436Y95291I-914J-1192D01*
G02X400297Y96096I-156J988D01*
G03X400252Y96275I-1476J-276D01*
G02X400834Y97504I954J301D01*
G03X398523Y98430I-671J1673D01*
G02X398096Y97139I-910J-415D01*
G03X399054Y94339I724J-1316D01*
G02X400193Y93534I156J-988D01*
G03X402598Y92626I1477J273D01*
G02X403923Y92547I618J-786D01*
G01X405056Y91413D01*
Y90704D01*
G02X404556Y90204I-500J0D01*
G01X404541D01*
G03Y87200I-13J-1502D01*
G01X404556D01*
G02X405056Y86700I0J-500D01*
G01Y83052D01*
X395915Y73911D01*
G02X394474Y73939I-707J707D01*
G03X393228Y74414I-1102J-1020D01*
G02X392142Y75540I-95J995D01*
G03X390687Y74004I-1787J235D01*
G02X391870Y72980I184J-983D01*
G03X391927Y72505I1501J-61D01*
G02X390966Y71229I-961J-276D01*
G01X358265D01*
X356983Y69947D01*
X341559D01*
G37*
G36*
G01X224084Y265414D02*
G03X224708Y263777I1889J-217D01*
G02X224775Y263102I-332J-374D01*
G03X224501Y261898I1198J-906D01*
G02X223521Y260698I-980J-200D01*
G01X223015D01*
X222600Y260283D01*
X221120D01*
X220596Y259759D01*
X217985D01*
G02X217665Y259875I0J500D01*
G03X217478Y260011I-1151J-1386D01*
G01X217431Y260041D01*
X217180Y260292D01*
Y261072D01*
X217288Y261208D01*
G03Y263070I-1179J931D01*
G01X217180Y263206D01*
Y264072D01*
X217288Y264208D01*
G03Y266070I-1179J931D01*
G01X217180Y266206D01*
Y267168D01*
X218149Y268137D01*
X218316Y268160D01*
G03X219031Y268479I-191J1389D01*
G01X219171Y268598D01*
X224128D01*
X224228Y268498D01*
Y265959D01*
X224195Y265873D01*
G03X224084Y265414I1779J-673D01*
G37*
G36*
G01X223624Y278309D02*
Y281553D01*
X224018Y281947D01*
X225716D01*
G02X225862Y281925I-1J-500D01*
G01X228239D01*
X228640Y281524D01*
Y280077D01*
X228416Y279853D01*
X226570D01*
X226492D01*
X226216Y279577D01*
Y276190D01*
X225799Y275772D01*
X224339D01*
X224055D01*
X223192Y276635D01*
Y277877D01*
X223624Y278309D01*
G37*
G36*
G01X233477Y285945D02*
X232578Y286843D01*
X224686D01*
G02X224331Y286990I-1J500D01*
G01X224204Y287118D01*
X224182Y287287D01*
G03X224180Y287299I-1481J-241D01*
G02X224289Y287916I990J143D01*
G01X224295Y287927D01*
X224297Y287930D01*
G02X224342Y288002I869J-493D01*
G03X224344Y288006I-1331J668D01*
G02X224587Y288255I826J-563D01*
G03X224606Y288268I-838J1246D01*
G02X224682Y288315I563J-826D01*
G01X224685Y288316D01*
X224705Y288327D01*
G02X225170Y288442I466J-885D01*
G01X226359D01*
X227464Y289547D01*
Y292040D01*
X227669Y292245D01*
X228894D01*
G02X229394Y291745I0J-500D01*
G01Y289730D01*
X230395Y288730D01*
X232740D01*
X233532Y289521D01*
Y290956D01*
G02X234032Y291456I500J0D01*
G01X238735D01*
G02X239232Y291017I1J-500D01*
G01X239236Y290982D01*
Y289557D01*
X239159Y289373D01*
X239157Y289371D01*
X237869D01*
G03X237844Y289370I47J-1500D01*
G01X237247D01*
X237222Y289345D01*
X236772Y288896D01*
X236658Y288781D01*
X236138Y288261D01*
Y286239D01*
X235981Y286082D01*
G02X235583Y285937I-354J353D01*
G03X235417Y285945I-179J-1993D01*
G01X233477D01*
G37*
G36*
G01X232337Y304489D02*
X232537Y304289D01*
Y303226D01*
X232415Y303104D01*
Y302112D01*
X232308Y302005D01*
X228146D01*
Y301893D01*
X226777D01*
X226721Y301836D01*
X223794D01*
X223496Y302135D01*
X221074D01*
X221071Y302138D01*
Y303810D01*
X221515Y304254D01*
X229694D01*
X229818Y304130D01*
X230560D01*
X230919Y304489D01*
X232337D01*
G37*
G36*
G01X241899Y308120D02*
G02X241411Y307992I-354J354D01*
G03X240121Y307870I-487J-1735D01*
G01X240015Y307817D01*
X236710D01*
X233847Y304954D01*
X233288D01*
X233109Y305134D01*
X232752Y305491D01*
X230504D01*
X230416Y305403D01*
G02X230062Y305256I-354J353D01*
G01X221100D01*
X220799Y304954D01*
X218445D01*
X217932Y305467D01*
Y307079D01*
X218126Y307273D01*
X231118D01*
Y307291D01*
X232433D01*
X233179Y308037D01*
X233554Y308413D01*
Y310271D01*
X232382Y311444D01*
X224772D01*
X224262Y311953D01*
Y313257D01*
X223875Y313643D01*
G02Y314351I353J354D01*
G02X224471Y314434I353J-354D01*
G03X223885Y315020I728J1314D01*
G01X223967Y314873D01*
X223920Y314543D01*
X223802Y314424D01*
G02X223094I-354J353D01*
G01X222630Y314888D01*
X222033D01*
X221534Y315387D01*
Y320591D01*
X221535Y320592D01*
Y321145D01*
X221841Y321451D01*
X223153D01*
X223665Y320938D01*
X225875D01*
G02X226052Y320557I-323J-382D01*
G01Y319136D01*
X227050Y318137D01*
X228618D01*
X229118Y317637D01*
Y314487D01*
X229613Y313992D01*
X241856D01*
X242111Y313737D01*
Y310702D01*
X242066Y310657D01*
Y308494D01*
G02X241919Y308140I-500J0D01*
G01X241899Y308120D01*
G37*
G36*
G01X214567Y381948D02*
Y381982D01*
X214571Y382015D01*
G03X214588Y382271I-1884J254D01*
G01Y383056D01*
X215353Y383820D01*
G03X215707Y386019I-1345J1345D01*
G02X215953Y387230I894J449D01*
G03X216563Y388306I-1167J1373D01*
G02X217743Y389123I987J-164D01*
G03X217863Y389103I356J1766D01*
G01X218051Y389079D01*
X218300Y388797D01*
Y381687D01*
X218061Y381448D01*
X215067D01*
G02X214567Y381948I0J500D01*
G37*
G36*
G01X234117Y415319D02*
X216842Y415623D01*
G02X216351Y416123I9J500D01*
G01Y444335D01*
X216941Y444925D01*
X233942D01*
X234037Y444830D01*
X235100D01*
X235714Y444216D01*
Y442421D01*
G02X235569Y442069I-500J0D01*
G03X235134Y441012I1067J-1057D01*
G01Y416319D01*
G02X234117Y415319I-1000J0D01*
G37*
G36*
G01X220709Y494353D02*
X221209Y493853D01*
Y491853D01*
X223709Y489353D01*
Y485253D01*
G02X223209Y484753I-500J0D01*
G01X220987D01*
G03X219850Y485268I-1353J-1475D01*
G01X219675Y485287D01*
X219209Y485753D01*
Y488353D01*
X217209Y490353D01*
Y493853D01*
X217709Y494353D01*
X220709D01*
G37*
G36*
G01X228332Y484853D02*
X225709D01*
X225209Y485353D01*
Y489353D01*
X223209Y491353D01*
Y492353D01*
X223709Y492853D01*
X225883D01*
X226688Y492048D01*
X229249D01*
X229376Y491921D01*
Y485677D01*
X228552Y484853D01*
X228332D01*
G37*
G36*
G01X220709Y496353D02*
X212709D01*
X211909Y497153D01*
Y499553D01*
X212259Y499903D01*
X218259D01*
X219209Y500853D01*
Y511853D01*
X219709Y512353D01*
X222209D01*
X222709Y511853D01*
Y510353D01*
X224709Y508353D01*
Y503353D01*
X222209Y500853D01*
Y497853D01*
X220709Y496353D01*
G37*
G36*
G01X218789Y522320D02*
G03X219152Y522340I76J1918D01*
G03X220179Y522837I-285J1898D01*
G01X220368D01*
Y523042D01*
G03X220445Y523145I-1498J1200D01*
G02X221613Y522948I450J-893D01*
G03X221865Y522340I1763J374D01*
G03X222596Y524946I1511J982D01*
G02X221709Y525940I113J994D01*
G01Y527853D01*
X224209Y530353D01*
X236409D01*
X236700Y530062D01*
G02Y529354I-353J-354D01*
G01X236598Y529252D01*
X236456Y529220D01*
G03X235572Y528626I320J-1432D01*
G02X234830I-371J929D01*
G03X232422I-1204J-838D01*
G02X231680I-371J929D01*
G03X229637Y526584I-1204J-838D01*
G02Y525843I-928J-370D01*
G03X229638Y523435I839J-1204D01*
G02Y522693I-929J-371D01*
G03Y520285I838J-1204D01*
G02Y519543I-929J-371D01*
G03X229013Y518441I838J-1204D01*
G02X228514Y517975I-499J34D01*
G01X227832D01*
X227785Y517928D01*
X227726Y517870D01*
X227211Y517355D01*
X225543D01*
X225435Y517410D01*
G03X223833I-801J-1557D01*
G01X223725Y517355D01*
X223232D01*
Y517353D01*
X219355D01*
G02X218976Y517527I0J500D01*
G03X216369Y517661I-1367J-1174D01*
G01X216303Y517599D01*
X215949Y517448D01*
X215617Y517577D01*
X215556Y517627D01*
G03X214716Y517956I-929J-1135D01*
G01X214526Y517968D01*
X213671Y518823D01*
Y522117D01*
X214071Y522517D01*
X218010D01*
X218105Y522476D01*
G03X218789Y522320I762J1762D01*
G37*
G36*
G01X227978Y548363D02*
Y546044D01*
X227080Y545146D01*
X223511D01*
X219978Y548679D01*
Y563843D01*
X220778Y564643D01*
X225083D01*
X225750Y563975D01*
Y550591D01*
X227978Y548363D01*
G37*
G36*
G01X243744Y575422D02*
G03X243090Y575515I-533J-1404D01*
G02X242038Y576280I-79J997D01*
G01X241324D01*
X240690Y576913D01*
X230580D01*
X229637Y575970D01*
X222867D01*
X222064Y576773D01*
Y578990D01*
X223754Y580681D01*
G02X225403Y580310I707J-707D01*
G03X227706Y582613I1697J606D01*
G02X227335Y584262I336J942D01*
G01X228088Y585015D01*
X245741D01*
X245800Y584956D01*
X249887D01*
X250605Y584238D01*
G02X250608Y583534I-353J-354D01*
G03X250034Y582131I1428J-1403D01*
G01Y581771D01*
X248274Y580010D01*
X248208D01*
Y579944D01*
X248108Y579844D01*
Y579368D01*
X245063Y576323D01*
X245023Y576296D01*
G03X244613Y575886I837J-1247D01*
G01X244586Y575846D01*
X244275Y575535D01*
G02X243744Y575422I-353J354D01*
G37*
G36*
G01X261010Y273441D02*
G02X261986Y272219I1J-1000D01*
G03X262100Y269959I1043J-1080D01*
G02Y269319I-947J-320D01*
G03Y266959I929J-1180D01*
G02Y266319I-947J-320D01*
G03Y263959I929J-1180D01*
G02X262098Y263312I-947J-321D01*
G03X262016Y263200I1170J-942D01*
G02X261217Y263154I-417J276D01*
G03X258937Y263175I-1149J-967D01*
G02X258292Y263212I-268J963D01*
G03X255511Y263139I-1376J-603D01*
G02X255043Y262816I-468J177D01*
G01X254503D01*
G02X254065Y263075I0J500D01*
G03X253984Y263209I-1667J-916D01*
G01X253900Y263335D01*
Y263560D01*
X253684D01*
G03X251793Y263960I-1284J-1402D01*
G02X250867Y264145I-290J957D01*
G03X247968Y264029I-1434J-448D01*
G02X247458Y263639I-488J110D01*
G03X247237Y263633I-70J-1500D01*
G02X246151Y264454I-101J995D01*
G01X243114D01*
G02X241925Y263666I-982J190D01*
G03X241560Y263698I-313J-1469D01*
G01X241384Y263692D01*
X241049Y263941D01*
X241000Y264094D01*
G03X240732Y264590I-1432J-453D01*
G01X240619Y264728D01*
Y265550D01*
X240732Y265688D01*
G03X241022Y266260I-1164J950D01*
G01X241065Y266422D01*
X241413Y266698D01*
X241591Y266695D01*
G03X243109Y268063I22J1502D01*
G02X244105Y268974I996J-89D01*
G01X244892D01*
G02X245890Y268040I0J-1000D01*
G03X248875Y268356I1499J99D01*
G01X248858Y268473D01*
X248932Y268697D01*
X249350Y269116D01*
X250547D01*
X251667Y270235D01*
X255162D01*
X255322Y270395D01*
X255866D01*
X256031Y270324D01*
G03X256258Y270072I1222J873D01*
G02Y269322I-331J-375D01*
G03X255776Y268468I995J-1125D01*
G02X255303Y268058I-492J90D01*
G03X256836Y266286I56J-1501D01*
G02X257309Y266696I492J-90D01*
G03X258182Y269377I-56J1501D01*
G02Y270017I947J320D01*
G03X258280Y272293I-929J1180D01*
G02X258268Y273011I342J365D01*
G01X258698Y273441D01*
X261010D01*
G37*
G36*
G01X251855Y279109D02*
X251979Y278985D01*
Y276810D01*
X251212Y276043D01*
Y274950D01*
X249066Y272804D01*
X243258D01*
X242428Y273634D01*
X241690D01*
X240181D01*
X240162Y273653D01*
Y274542D01*
G03X239889Y275480I-1752J-1D01*
G01X239812Y275602D01*
Y275843D01*
X239788D01*
X239128Y276503D01*
X237106D01*
X236712Y276897D01*
Y278568D01*
X237252Y279108D01*
X240113D01*
X240115Y279109D01*
X251855D01*
G37*
G36*
G01X252742Y279638D02*
X252270Y280111D01*
X239879D01*
X239877Y280110D01*
X236837D01*
X236515Y279787D01*
X236318D01*
X235918Y279387D01*
Y279298D01*
X235841Y279114D01*
X235710Y278983D01*
Y276887D01*
G02X235210Y276387I-500J0D01*
G01X233818D01*
X233468Y276737D01*
X233518Y276787D01*
Y284487D01*
X233618Y284587D01*
X235518D01*
X235818Y284287D01*
Y282987D01*
X236218Y282587D01*
X243395D01*
X243478Y282556D01*
G03X244720I621J1692D01*
G01X244803Y282587D01*
X249583D01*
X249935Y282235D01*
X252943D01*
G03X253880Y282507I-1J1752D01*
G01X254002Y282585D01*
X254516D01*
X254818Y282887D01*
Y284787D01*
X255118Y285087D01*
X257118D01*
X257418Y284787D01*
Y282387D01*
X257443Y282362D01*
Y281606D01*
G02X256969Y281107I-500J0D01*
G03X255545Y279647I77J-1500D01*
G01X255539Y279448D01*
X255260Y279169D01*
Y276513D01*
X254792Y276046D01*
X253431D01*
G02X252980Y276521I49J498D01*
G01Y279400D01*
X252742Y279638D01*
G37*
G36*
G01X249050Y291955D02*
G02X249122Y291338I-353J-354D01*
G03X251881Y290791I1277J-790D01*
G02X252796Y291387I915J-404D01*
G01X254545D01*
X254596Y291336D01*
Y291230D01*
X254701D01*
X255024Y290907D01*
X255098D01*
X255118Y290887D01*
X258018D01*
X258140Y290765D01*
Y286687D01*
G02X257640Y286187I-500J0D01*
G01X248818D01*
X248518Y286487D01*
X247900D01*
X247797Y286536D01*
G03X247018Y286714I-781J-1624D01*
G01X244017D01*
X243790Y286487D01*
X237318D01*
X237140Y286665D01*
Y287846D01*
X237481Y288188D01*
X237653Y288360D01*
X237881Y288369D01*
X239568D01*
X240238Y289030D01*
Y290956D01*
G03X240235Y291043I-1501J-8D01*
G03X240227Y291129I-1498J-96D01*
G01X240224Y291158D01*
Y291187D01*
G02X240724Y291687I500J0D01*
G01X241918D01*
X242822Y292591D01*
X242848Y292594D01*
G02X243198Y292496I49J-498D01*
G03X243528Y295087I901J1202D01*
G02X242718Y296070I190J982D01*
G01Y297587D01*
X243218Y298087D01*
X245118D01*
X245818Y298787D01*
Y299667D01*
X246498Y300346D01*
X248272D01*
X248428Y300191D01*
Y296675D01*
X248412Y296659D01*
Y292795D01*
X248818Y292389D01*
Y292187D01*
X249050Y291955D01*
G37*
G36*
G01X266171Y324699D02*
X266265Y324770D01*
G03X266820Y325861I-847J1117D01*
G02X267820Y326842I1000J-19D01*
G01X268367D01*
X268667Y326542D01*
Y324263D01*
X268967Y323963D01*
X279900D01*
X280736Y323127D01*
X280742Y323121D01*
G03X280798Y323065I877J821D01*
G01X280804Y323059D01*
X281121Y322742D01*
X281568D01*
X281581Y322741D01*
G03X281619Y322740I51J1200D01*
G01X282000D01*
X283001Y321739D01*
Y320999D01*
X283995Y320005D01*
X285303D01*
X285308Y320000D01*
X286531D01*
X290257Y323726D01*
X301286D01*
X302507Y324946D01*
X309996D01*
X310955Y323987D01*
X310972D01*
X311831Y323128D01*
X320215D01*
X321017Y323930D01*
X322029D01*
G02X322529Y323430I0J-500D01*
G01Y320902D01*
X321087Y319460D01*
X300665D01*
X298824Y317619D01*
X298543D01*
X298484Y317560D01*
X285119D01*
X285117Y317558D01*
X282251D01*
X282249Y317560D01*
X255885D01*
X255850Y317525D01*
X254942D01*
X254685Y317782D01*
X252463D01*
X252206Y317525D01*
X249276D01*
X248450Y316699D01*
Y315557D01*
G02X247950Y315057I-500J0D01*
G01X241636D01*
X241572Y314994D01*
X230282D01*
X230120Y315156D01*
Y317514D01*
X230312Y317707D01*
G02X230667Y317854I354J-353D01*
G01X236868D01*
X237318Y318304D01*
Y318328D01*
X237368Y318377D01*
Y324636D01*
X237641Y324911D01*
X237826Y324987D01*
X238722D01*
X239544Y324164D01*
Y324155D01*
X240669Y323030D01*
X240670D01*
X240903Y322797D01*
X246046D01*
X246309Y322606D01*
X246359Y322450D01*
G03X249174Y322328I1430J460D01*
G01X249228Y322456D01*
X249695Y322797D01*
X254488D01*
X254766Y322565D01*
X254798Y322386D01*
G03X257777Y322601I1478J267D01*
G02X258775Y323534I998J-67D01*
G01X261090D01*
G02X261540Y323641I450J-893D01*
G01X262868D01*
X262881Y323628D01*
X265353D01*
X266067Y324342D01*
Y324489D01*
X266171Y324699D01*
G37*
G36*
G01X232219Y328210D02*
X233994D01*
X234016Y328188D01*
Y328010D01*
X234194D01*
X236366Y325839D01*
Y319498D01*
X235892Y319024D01*
X232049D01*
X230519Y320554D01*
Y322813D01*
X231986Y324280D01*
Y324407D01*
X232097Y324545D01*
G03X231970Y326894I-1372J1104D01*
G01X231818Y327046D01*
Y327715D01*
X231869Y327820D01*
G03X231910Y327907I-1609J811D01*
G01X231969Y328046D01*
X232219Y328210D01*
G37*
G36*
G01X253571Y325780D02*
G03X253134Y324589I1060J-1065D01*
G02X252990Y324194I-498J-42D01*
G01X252828Y324032D01*
X248801D01*
X248669Y324127D01*
G03X246909I-880J-1217D01*
G01X246777Y324032D01*
X241084D01*
X240546Y324570D01*
Y324579D01*
X239618Y325507D01*
Y325538D01*
G02X239769Y325896I500J0D01*
G03X239783Y328387I-1224J1252D01*
G01X239618Y328553D01*
Y331502D01*
X242812Y334696D01*
X243064Y334766D01*
X243192Y334735D01*
G03X244550Y334956I420J1700D01*
G01X244672Y335034D01*
X245114D01*
Y335525D01*
X245169Y335633D01*
G03X245242Y335793I-1555J806D01*
G02X245951Y336046I465J-183D01*
G03X248153Y337039I734J1311D01*
G02X248642Y337433I489J-106D01*
G01X253170D01*
Y330265D01*
X253503Y329932D01*
G03X253811Y328858I1494J-153D01*
G02X253788Y328217I-395J-307D01*
G03X253640Y326404I1117J-1004D01*
G02X253571Y325780I-422J-269D01*
G37*
G36*
G01X236136Y416396D02*
Y441012D01*
G02X236636Y441512I500J0D01*
G01X243255D01*
X245727Y439040D01*
Y416356D01*
X244671Y415300D01*
X237232D01*
X236136Y416396D01*
G37*
G36*
G01X237247Y510282D02*
X237180Y510301D01*
G03X237079Y510326I-403J-1410D01*
G01X236934Y510357D01*
X236398Y510893D01*
Y512555D01*
X237978Y514135D01*
Y514157D01*
X238023Y514203D01*
Y514297D01*
X238309Y514582D01*
Y516182D01*
X238609Y516482D01*
X239177D01*
G03X239211Y516481I61J1500D01*
G01X240710D01*
X241109Y516082D01*
Y510582D01*
X240809Y510282D01*
X240396D01*
X240329Y510301D01*
G03X239521I-404J-1410D01*
G01X239454Y510282D01*
X237247D01*
G37*
G36*
G01X244309Y518782D02*
X243409Y517882D01*
X241709D01*
X241311Y517483D01*
X239211D01*
G02X238711Y517983I0J500D01*
G01Y522081D01*
G02X239211Y522581I500J0D01*
G01X241224D01*
X241425Y522782D01*
X241509D01*
X242109Y523382D01*
Y523466D01*
X242311Y523667D01*
Y524682D01*
G02X242811Y525182I500J0D01*
G01X244009D01*
X244309Y524882D01*
Y518782D01*
G37*
G36*
G01X237077Y522925D02*
G03X235572Y522327I-301J-1436D01*
G02X234830I-371J929D01*
G03X234505Y522664I-1205J-837D01*
G02Y523464I299J400D01*
G03X234465Y525843I-879J1175D01*
G02Y526584I928J371D01*
G03X234801Y526909I-839J1204D01*
G02X235601I400J-299D01*
G03X237077Y526352I1175J879D01*
G02X237709Y525422I-368J-930D01*
G01Y523855D01*
G02X237077Y522925I-1000J0D01*
G37*
G36*
G01X244309Y526782D02*
X244009Y526482D01*
X241909D01*
X241309Y525882D01*
Y524082D01*
X240809Y523582D01*
X238809D01*
X238711Y523681D01*
Y529081D01*
G02X239211Y529581I500J0D01*
G01X241910D01*
X242309Y529182D01*
X244009D01*
X244309Y528882D01*
Y526782D01*
G37*
G36*
G01X243060Y548499D02*
X243296Y548263D01*
Y542266D01*
X243609Y541953D01*
X244309Y541253D01*
Y538882D01*
X244058Y538630D01*
G02X243704Y538483I-354J353D01*
G01X242024D01*
X241224Y539283D01*
X240918Y539589D01*
X239271D01*
X238823Y540037D01*
X238577Y540402D01*
X238456Y540522D01*
G02X238309Y540877I353J354D01*
G01Y547526D01*
Y550302D01*
X239043Y551036D01*
X241729D01*
X243060Y549705D01*
Y548499D01*
G37*
G36*
G01X250689Y626610D02*
X250862Y626438D01*
G02X251009Y626085I-353J-354D01*
G01Y601688D01*
X250007Y600686D01*
X242633D01*
X241945Y601374D01*
Y624806D01*
X243749Y626610D01*
X250689D01*
G37*
G36*
G01X244020Y646053D02*
X244201Y646234D01*
X251003D01*
X258563D01*
X259777Y645020D01*
Y643651D01*
Y635110D01*
X259566Y634899D01*
X259483D01*
X256483D01*
X256028Y635354D01*
X255785D01*
X255114Y636026D01*
X242882D01*
X242712Y636196D01*
X242711D01*
X242245Y636662D01*
Y638138D01*
X242304Y638197D01*
X243057D01*
X244020Y639160D01*
Y646053D01*
G37*
G36*
G01X305339Y62517D02*
G03X308047I1354J650D01*
G02X308498Y62801I451J-216D01*
G01X308823D01*
X309066Y62648D01*
X309129Y62517D01*
G03X311837I1354J650D01*
G02X312288Y62801I451J-216D01*
G01X312980D01*
X313223Y62648D01*
X313286Y62517D01*
G03X315994I1354J650D01*
G02X316445Y62801I451J-216D01*
G01X316883D01*
X317126Y62648D01*
X317189Y62517D01*
G03X319897I1354J650D01*
G02X320348Y62801I451J-216D01*
G01X320908D01*
G02X321359Y62517I0J-500D01*
G03X324067I1354J650D01*
G02X324518Y62801I451J-216D01*
G01X324548D01*
G02X324999Y62517I0J-500D01*
G03X327707I1354J650D01*
G02X328158Y62801I451J-216D01*
G01X341144D01*
X354368Y49577D01*
X373980D01*
X377660Y45897D01*
Y15066D01*
X376922Y14328D01*
X369228D01*
X368680Y14875D01*
Y37775D01*
X365035Y41420D01*
X356348D01*
X356056Y41712D01*
Y41839D01*
G03X352662Y41851I-1709J-3285D01*
G01Y41712D01*
X352370Y41420D01*
X349076D01*
X333702Y56794D01*
X272638D01*
X268092Y52248D01*
X263960D01*
X263397Y51685D01*
X257700D01*
X256762Y52624D01*
Y58462D01*
X256696Y58527D01*
Y60897D01*
X258600Y62801D01*
X267988D01*
G02X268439Y62517I0J-500D01*
G03X271147I1354J650D01*
G02X271598Y62801I451J-216D01*
G01X272068D01*
G02X272519Y62517I0J-500D01*
G03X275227I1354J650D01*
G02X275678Y62801I451J-216D01*
G01X276048D01*
G02X276499Y62517I0J-500D01*
G03X279207I1354J650D01*
G02X279658Y62801I451J-216D01*
G01X280218D01*
G02X280669Y62517I0J-500D01*
G03X283377I1354J650D01*
G02X283828Y62801I451J-216D01*
G01X289018D01*
G02X289469Y62517I0J-500D01*
G03X292177I1354J650D01*
G02X292628Y62801I451J-216D01*
G01X293098D01*
G02X293549Y62517I0J-500D01*
G03X296257I1354J650D01*
G02X296708Y62801I451J-216D01*
G01X297223D01*
X297466Y62648D01*
X297529Y62517D01*
G03X300237I1354J650D01*
G02X300688Y62801I451J-216D01*
G01X301393D01*
X301636Y62648D01*
X301699Y62517D01*
G03X304407I1354J650D01*
G02X304858Y62801I451J-216D01*
G01X304888D01*
G02X305339Y62517I0J-500D01*
G37*
G36*
G01X255292Y292056D02*
X254960Y292388D01*
X254800Y292548D01*
G02X254687Y292535I-113J487D01*
G01X254532D01*
G02X254177Y292682I-1J500D01*
G01X254111Y292749D01*
X249874D01*
X249414Y293210D01*
Y296244D01*
X249430Y296260D01*
Y300166D01*
X249610Y300346D01*
X254254D01*
X254710Y299891D01*
Y294855D01*
X256018Y293547D01*
X256726D01*
X256979Y293294D01*
Y292020D01*
X256868Y291909D01*
X255646D01*
G02X255292Y292056I0J500D01*
G37*
G36*
G01X243481Y310544D02*
X243584Y310542D01*
G03X243612Y310541I68J1500D01*
G01X245618D01*
X246064Y310987D01*
X253218D01*
X253618Y310587D01*
Y308887D01*
X253318Y308587D01*
X248818D01*
X248173Y307942D01*
X244667D01*
X243467D01*
X243068Y308341D01*
Y310242D01*
X243293Y310468D01*
X243481Y310544D01*
G37*
G36*
G01X266955Y310802D02*
X266546Y311211D01*
X263755D01*
X262820Y312146D01*
X262782Y312241D01*
G03X261940Y313083I-1396J-554D01*
G01X261845Y313121D01*
X261761Y313205D01*
X260361D01*
X258622Y311466D01*
X257379D01*
X257340Y311472D01*
G03X256794I-273J-1730D01*
G01X256755Y311466D01*
X254155D01*
X253633Y311988D01*
X245649D01*
X245242Y311581D01*
X243909D01*
G02X243409Y312081I0J500D01*
G01Y313457D01*
X243964Y314012D01*
X251615D01*
X252570Y314967D01*
Y316473D01*
X252878Y316781D01*
X254270D01*
X254740Y316311D01*
X256736D01*
X256832Y316407D01*
X300105D01*
X301637Y317939D01*
X322063D01*
G02X322416Y317792I-1J-500D01*
G01X323734Y316474D01*
Y313148D01*
X323051Y312464D01*
X322903Y312316D01*
X310452D01*
X308946Y313822D01*
X308530D01*
X308529Y313824D01*
X291029D01*
X291028Y313822D01*
X279189D01*
X277644Y312277D01*
Y311451D01*
X277275Y311082D01*
X277193Y311045D01*
G03X277055Y310973I625J-1366D01*
G03X277050Y310970I770J-1289D01*
G03X277047Y310968I831J-1249D01*
G03X276979Y310925I768J-1290D01*
G01X276852Y310840D01*
X276353D01*
X276196Y310997D01*
X276192Y311001D01*
G03X273736Y311252I-1375J-1314D01*
G01X273607Y311163D01*
X268349D01*
X267988Y310802D01*
X266955D01*
G37*
G36*
G01X260113Y513228D02*
Y511539D01*
X257385D01*
X256228Y510382D01*
X251909D01*
X251511Y510781D01*
Y511667D01*
X251553Y511709D01*
Y512253D01*
X253281Y513981D01*
Y517425D01*
X253509Y517653D01*
X259123D01*
X259709Y517067D01*
X260113Y516663D01*
Y513228D01*
G37*
G36*
G01X250509Y512553D02*
Y512082D01*
Y511182D01*
X250109Y510782D01*
X245509D01*
X245109Y511182D01*
Y514082D01*
X247509Y516482D01*
Y516748D01*
X248432Y517671D01*
X251210D01*
X252009Y516872D01*
Y514553D01*
X250509Y513053D01*
Y512553D01*
G37*
G36*
G01X278415Y516669D02*
X278393Y516671D01*
G03X278210Y516679I-174J-1894D01*
G01X276887D01*
X276107Y517459D01*
X268815D01*
X268733Y517540D01*
X267646D01*
X267462Y517617D01*
X267424Y517655D01*
X264494D01*
X264456Y517617D01*
X264272Y517540D01*
X263609D01*
X263196Y517953D01*
X263125D01*
X263010Y518069D01*
X261193D01*
X260873Y518389D01*
X260011D01*
G02X259646Y518547I0J500D01*
G01X259616Y518576D01*
X259538Y518655D01*
X252870D01*
X252706Y518818D01*
X248314D01*
X248209Y518923D01*
X246127D01*
G02X245627Y519423I0J500D01*
G01Y541535D01*
X244433Y542729D01*
Y544835D01*
X244629Y545031D01*
X247267D01*
X247509Y544789D01*
X250945D01*
X252109Y545953D01*
Y547152D01*
G02X252609Y547652I500J0D01*
G01X253308D01*
G02X253808Y547152I-1J-501D01*
G01Y545530D01*
X253807Y545529D01*
Y542038D01*
X254694Y541151D01*
X257524D01*
X257525Y541153D01*
X257809D01*
X258609Y541953D01*
Y547853D01*
X258909Y548153D01*
X260286D01*
G02X260640Y548006I0J-500D01*
G01X260894Y547751D01*
X260917D01*
X261209Y547459D01*
Y545577D01*
G02X261062Y545222I-500J-1D01*
G01X261007Y545168D01*
Y542138D01*
X262094Y541051D01*
X264524D01*
X265611Y542138D01*
Y542255D01*
X266109Y542753D01*
Y543953D01*
X266463Y544307D01*
X267688D01*
X267733Y544351D01*
X268124D01*
X269811Y546038D01*
Y547567D01*
X269977Y547734D01*
G02X270332Y547881I354J-353D01*
G01X272929D01*
X272966Y547843D01*
Y544208D01*
X272419Y543661D01*
Y543308D01*
X272156Y543045D01*
X272107Y542997D01*
Y528367D01*
X272108D01*
Y526910D01*
Y525850D01*
X272044Y525736D01*
X272204Y525576D01*
Y521288D01*
X273905Y519587D01*
X276563D01*
G02X276916Y519440I-1J-500D01*
G01X277146Y519210D01*
X279596D01*
X279946Y518860D01*
Y516900D01*
X279715Y516669D01*
X278415D01*
G37*
G36*
G01X251311Y550897D02*
X251156Y551051D01*
G02X251009Y551406I353J354D01*
G01Y552509D01*
X251024Y552569D01*
G03X251075Y553006I-1650J414D01*
G02X251222Y553366I500J6D01*
G01X251668Y553812D01*
X253368D01*
X254196Y552984D01*
X254215Y552807D01*
Y552806D01*
G03X254714Y551874I1394J147D01*
G03X255569Y551521I959J1110D01*
G01X255755Y551507D01*
X257409Y549853D01*
Y542453D01*
X257109Y542153D01*
X255109D01*
X254809Y542453D01*
Y548253D01*
X254409Y548653D01*
X252209D01*
X251509Y549353D01*
Y550553D01*
X251311Y550751D01*
Y550897D01*
G37*
G36*
G01X249512Y551279D02*
X250008Y550783D01*
Y550782D01*
X250162Y550628D01*
G02X250309Y550274I-353J-354D01*
G01Y548553D01*
X250909Y547953D01*
Y546253D01*
X250473Y545817D01*
X248009D01*
X247793Y546033D01*
X245899D01*
X244888Y547044D01*
Y549632D01*
X245009Y549753D01*
Y551453D01*
X245109Y551553D01*
X248415D01*
X248527Y551492D01*
G03X249311Y551283I818J1492D01*
G01X249512Y551279D01*
G37*
G36*
G01X246209Y573236D02*
G02X246497Y573689I500J0D01*
G03X246858Y573927I-638J1360D01*
G02X247190Y574053I332J-374D01*
G01X252209D01*
X252224Y574039D01*
X253968Y575783D01*
X256698D01*
X257538Y574943D01*
Y572683D01*
X254628Y569773D01*
X250923D01*
X250791Y569868D01*
G03X249785Y567156I-882J-1215D01*
G03X249969Y567152I125J1496D01*
G02X251009Y566153I40J-999D01*
G01Y560738D01*
X251490Y560257D01*
X252022D01*
X252147Y560176D01*
G03X252536Y559979I1093J1676D01*
G03X253239Y559851I704J1874D01*
G01X253432D01*
G02X253932Y559351I0J-500D01*
G01Y558785D01*
X253522Y558375D01*
X250031D01*
X250009Y558353D01*
X248509D01*
X247709Y559153D01*
Y560602D01*
X247840Y560937D01*
X247895Y561001D01*
G03X248426Y562434I-1671J1434D01*
G01Y564463D01*
X247076Y565812D01*
X246209Y566679D01*
Y573236D01*
G37*
G36*
G01X276537Y21800D02*
X276300Y22037D01*
X272772D01*
X272641Y22168D01*
Y28548D01*
X272695Y28602D01*
X279301D01*
X279305Y28598D01*
Y21230D01*
X281517Y19018D01*
Y17298D01*
X281562Y17253D01*
Y13019D01*
X281490Y12947D01*
X277822D01*
X277043Y13726D01*
Y17466D01*
X276537Y17972D01*
Y21800D01*
G37*
G36*
G01X276558Y30144D02*
Y42295D01*
Y43400D01*
X273080Y46878D01*
Y54062D01*
X273763Y54745D01*
X282135D01*
X282271Y54610D01*
Y48537D01*
Y35312D01*
X279362Y32403D01*
Y29711D01*
X279295Y29644D01*
X277058D01*
G02X276558Y30144I0J500D01*
G37*
G36*
G01X310333Y431738D02*
G03X310420Y431612I1278J789D01*
G02X310377Y430953I-396J-305D01*
G01X297072Y417648D01*
X279334D01*
X264794Y417575D01*
G02X264293Y418028I-3J500D01*
G03X262457Y419349I-1495J-142D01*
G02X261230Y420323I-227J974D01*
G01Y437255D01*
X262450Y438475D01*
X292776D01*
X306296Y451995D01*
Y465408D01*
G02X307497Y466388I1000J0D01*
G03Y469330I303J1471D01*
G02X306296Y470310I-201J980D01*
G01Y471131D01*
G02X307445Y472120I1000J0D01*
G03X308822Y472641I225J1485D01*
G02X309499Y472726I384J-320D01*
G03X309228Y474906I881J1216D01*
G02X308551Y474821I-384J320D01*
G03X308136Y475033I-882J-1215D01*
G02X307557Y476440I311J950D01*
G03X306652Y478563I-1337J685D01*
G02X306296Y479042I144J479D01*
G01Y482506D01*
X309586Y485796D01*
Y524563D01*
X319174Y534150D01*
X321987D01*
G03X323114Y534521I-1J1902D01*
G01X323246Y534618D01*
X326554D01*
G02X327551Y533541I0J-1000D01*
G03X331079Y533902I1797J-138D01*
G01X331041Y534034D01*
X331109Y534297D01*
X337390Y540578D01*
Y551645D01*
G02X337805Y552138I500J0D01*
G03X338723Y554556I-255J1480D01*
G02Y555180I391J312D01*
G03Y557056I-1173J938D01*
G02Y557680I391J312D01*
G03X337805Y560098I-1173J938D01*
G01X337625Y560129D01*
X337390Y560408D01*
Y574433D01*
X337492Y574567D01*
G03Y576747I-1435J1090D01*
G01X337390Y576881D01*
Y586392D01*
X348083Y597085D01*
X347501Y597667D01*
Y623804D01*
X348625Y624928D01*
X365180D01*
X366028Y624080D01*
Y590954D01*
X351110Y576036D01*
Y550934D01*
X350911Y550516D01*
X350783Y534468D01*
X350866Y533752D01*
G02X350554Y533230I-497J-57D01*
G03X350735Y530381I556J-1395D01*
G02X351110Y529896I-125J-484D01*
G01Y523015D01*
X350818Y522723D01*
X350770D01*
X347222Y519175D01*
G02X346756Y519042I-353J354D01*
G03X344594Y516880I-406J-1756D01*
G02X344461Y516414I-487J-113D01*
G01X342369Y514322D01*
G02X341906Y514187I-354J353D01*
G03X341174Y510659I-394J-1758D01*
G02X341580Y510168I-94J-491D01*
G01Y506525D01*
G02X340695Y505532I-1000J0D01*
G03Y501952I207J-1790D01*
G02X341580Y500959I-115J-993D01*
G01Y499790D01*
X342080Y499290D01*
Y499171D01*
G03X341980Y496883I1340J-1205D01*
G01X342080Y496750D01*
Y494155D01*
X335349Y487424D01*
X334100D01*
X332840Y486164D01*
Y457919D01*
X322810Y447889D01*
Y443386D01*
X319576Y440152D01*
X317143Y439455D01*
X317036Y439384D01*
X316761Y439369D01*
X316639Y439433D01*
G03X314529Y438619I-699J-1329D01*
G02X313566Y437962I-939J343D01*
G03X312579Y435297I-36J-1502D01*
G01X312707Y435193D01*
X312788Y434875D01*
X312547Y434284D01*
G02X311965Y433987I-463J189D01*
G03X310600Y433640I-356J-1459D01*
G02X309245Y433650I-672J740D01*
G03X309486Y431744I-1025J-1098D01*
G02X310333Y431738I422J-269D01*
G37*
G36*
G01X276278Y502283D02*
G03X276602Y501636I1433J313D01*
G01X276614Y501623D01*
X276616Y501620D01*
X276718Y501500D01*
X276722D01*
X276853Y501405D01*
G03X278571I859J1190D01*
G01X278702Y501500D01*
X279884D01*
X280015Y501405D01*
G03X280801Y501130I858J1190D01*
G01X280994Y501120D01*
X282549Y499565D01*
X282559Y499372D01*
G03X283951Y497980I1465J73D01*
G01X284144Y497970D01*
X284603Y497511D01*
X285109D01*
X285708Y496913D01*
Y496911D01*
X285974Y496645D01*
G02X286109Y496304I-365J-342D01*
G01Y493702D01*
X285009Y492602D01*
X281421D01*
X280872Y492053D01*
X275140D01*
X275041Y492098D01*
G03X274209Y492279I-832J-1820D01*
G01X271038D01*
X270338Y492979D01*
X269820D01*
G02X269320Y493479I0J500D01*
G01Y497657D01*
G02X269467Y498012I500J1D01*
G01X269611Y498155D01*
Y498927D01*
Y500843D01*
X272418Y503650D01*
X275615D01*
X276200Y503065D01*
Y502361D01*
X276278Y502283D01*
G37*
G36*
G01X277241Y510450D02*
X277209Y510482D01*
X267823D01*
G02X267323Y510982I0J500D01*
G01Y512550D01*
X268411Y513638D01*
Y513841D01*
X269109Y514539D01*
Y515653D01*
X269573Y516117D01*
X274174D01*
X274223Y516067D01*
X275095D01*
X275509Y515653D01*
X279009D01*
X279209Y515453D01*
Y510853D01*
X278709Y510353D01*
X278081D01*
X278030Y510364D01*
G03X277567Y510387I-303J-1435D01*
G01X277454Y510375D01*
X277241Y510450D01*
G37*
G36*
G01X267209Y550682D02*
X267970Y551443D01*
X268156Y551519D01*
X268257Y551518D01*
G03X268858Y551640I15J1467D01*
G01X268954Y551682D01*
X270739D01*
X270835Y551640D01*
G03X272007I586J1345D01*
G01X272103Y551682D01*
X273889D01*
X273985Y551640D01*
G03X275157I586J1345D01*
G01X275253Y551682D01*
X277051D01*
X277145Y551641D01*
G03X278391Y551682I579J1348D01*
G01X278509D01*
X279409Y550782D01*
Y549917D01*
X279408Y549906D01*
G03Y549774I1466J-66D01*
G01X279409Y549763D01*
Y546767D01*
X279408Y546756D01*
G03Y546624I1466J-66D01*
G01X279409Y546613D01*
Y543618D01*
X279408Y543607D01*
G03Y543475I1466J-66D01*
G01X279409Y543464D01*
Y540726D01*
X279400Y540678D01*
G03Y540104I1474J-287D01*
G01X279409Y540056D01*
Y537318D01*
X279408Y537307D01*
G03Y537175I1466J-66D01*
G01X279409Y537164D01*
Y534169D01*
X279408Y534158D01*
G03Y534026I1466J-66D01*
G01X279409Y534015D01*
Y532991D01*
X279735Y532665D01*
X280530D01*
X280580Y532655D01*
G03X281168I294J1437D01*
G01X281218Y532665D01*
X283680D01*
X283730Y532655D01*
G03X284318I294J1437D01*
G01X284368Y532665D01*
X285457D01*
X286157Y531965D01*
Y531001D01*
X284756Y529600D01*
X281466D01*
X281186D01*
X278168Y526582D01*
X273852D01*
X273109Y527325D01*
Y542582D01*
X274309Y543782D01*
Y548182D01*
X274078Y548413D01*
Y548903D01*
X269730D01*
X269580Y548753D01*
X269309D01*
X268809Y548253D01*
Y546453D01*
X267709Y545353D01*
X266009D01*
X265611Y545751D01*
Y547838D01*
X267011Y549238D01*
Y549255D01*
X267209Y549453D01*
Y550682D01*
G37*
G36*
G01X324327Y555429D02*
G03X324589Y555924I-1173J938D01*
G02X325067Y556277I478J-147D01*
G01X327853D01*
X330339Y553791D01*
Y540840D01*
X329438Y539940D01*
X323957D01*
G02X323488Y540408I31J500D01*
G01Y540604D01*
X322532D01*
X322456Y540628D01*
G03X321518I-469J-1426D01*
G01X321442Y540604D01*
X320486D01*
Y540536D01*
X320048Y540099D01*
X320010D01*
X319610Y539699D01*
X318110D01*
X314590Y536179D01*
Y533301D01*
X307590Y526301D01*
Y525854D01*
X297992Y516256D01*
X297708Y516194D01*
X297570Y516244D01*
G03X295573Y515809I-657J-1784D01*
G01X283557D01*
X280948Y518418D01*
Y519275D01*
X280011Y520211D01*
X277768D01*
G02X277414Y520358I0J500D01*
G01X277185Y520588D01*
X276596D01*
X276590D01*
G03X276564Y520589I-71J-1499D01*
G01X274319D01*
X273206Y521703D01*
Y525454D01*
X273222Y525471D01*
X278015D01*
X278029Y525485D01*
X279041D01*
X282154Y528598D01*
X285171D01*
X287158Y530586D01*
X288330Y531758D01*
Y531834D01*
G02X289733Y532749I1000J0D01*
G03X291260Y532963I590J1343D01*
G02X292536I638J-770D01*
G03X292298Y534971I937J1129D01*
G02X291498I-400J299D01*
G03X291404Y535084I-1174J-881D01*
G02X291433Y536467I736J676D01*
G01X293976Y539010D01*
X294062Y539047D01*
G03X294817Y539802I-589J1344D01*
G01X294854Y539888D01*
X304120Y549154D01*
Y555777D01*
G02X304620Y556277I500J0D01*
G01X311264D01*
X311716Y555977D01*
X311775Y555862D01*
G03X311970Y555575I1332J695D01*
G01X312024Y555512D01*
X312161Y555172D01*
X312017Y554825D01*
X311960Y554761D01*
G03X311675Y554300I1114J-1007D01*
G03X311891Y552830I1400J-545D01*
G02X311921Y551697I-809J-588D01*
G03X313166Y549319I1220J-876D01*
G03X314325Y551746I-24J1502D01*
G02X314295Y552879I809J588D01*
G03X314542Y553432I-1220J876D01*
G03X314577Y553782I-1467J323D01*
G03X314213Y554736I-1502J-27D01*
G01X314159Y554799D01*
X314022Y555139D01*
X314166Y555486D01*
X314223Y555550D01*
G03X314359Y555724I-1112J1009D01*
G03X314441Y555863I-1251J832D01*
G01X314500Y555978D01*
X314952Y556277D01*
X321406D01*
X321670Y556082D01*
X321719Y555924D01*
G03X321981Y555429I1435J443D01*
G02Y554805I-391J-312D01*
G03X324327I1173J-938D01*
G02Y555429I391J312D01*
G37*
G36*
G01X265409Y551053D02*
X266009Y550453D01*
Y549653D01*
X264609Y548253D01*
Y542553D01*
X264109Y542053D01*
X262509D01*
X262009Y542553D01*
Y544753D01*
X262409Y545153D01*
Y548453D01*
X262109Y548753D01*
X261309D01*
X260659Y549403D01*
Y550403D01*
X261309Y551053D01*
X265409D01*
G37*
G36*
G01X258385Y628108D02*
X259562Y629285D01*
X260146D01*
X262045Y631184D01*
Y631768D01*
X263367Y633090D01*
Y643997D01*
G02X263867Y644497I500J0D01*
G01X278384D01*
G02X278884Y643997I0J-500D01*
G01Y635250D01*
X281289Y632845D01*
Y593794D01*
X279103Y591608D01*
X258885D01*
G02X258385Y592108I0J500D01*
G01Y628108D01*
G37*
G36*
G01X296653Y35494D02*
X293217D01*
X283643D01*
Y46177D01*
Y55068D01*
X283988Y55414D01*
X297609D01*
X297859Y55164D01*
X300080Y52943D01*
Y37405D01*
X298169Y35494D01*
X296653D01*
G37*
G36*
G01X295209Y490853D02*
X293209Y492853D01*
X292419D01*
X292374Y492898D01*
X288638D01*
X287111Y494425D01*
Y496926D01*
X286856Y497180D01*
G02X286709Y497534I353J354D01*
G01Y498353D01*
X286209Y498853D01*
Y500353D01*
X286709Y500853D01*
X289858D01*
X289914Y500840D01*
G03X290732I409J1755D01*
G01X290788Y500853D01*
X291302D01*
X291578Y500577D01*
X293307D01*
Y500477D01*
X296111D01*
Y500577D01*
X296901D01*
X297177Y500853D01*
X301709D01*
X304209Y498353D01*
Y492684D01*
X302378Y490853D01*
X301278D01*
G03X301252Y490854I-90J-1999D01*
G03X301209Y490855I-68J-2000D01*
G01X296933D01*
X296931Y490853D01*
X295209D01*
G37*
G36*
G01X302499Y588257D02*
X292661D01*
X287484D01*
X286793Y588948D01*
Y598312D01*
X287580Y599099D01*
X293084D01*
X302658D01*
Y588416D01*
X302499Y588257D01*
G37*
G36*
G01X336630Y350589D02*
Y346346D01*
X333452Y343168D01*
X328435D01*
X327258Y341991D01*
Y341747D01*
G02X326758Y341247I-500J0D01*
G01X320580D01*
G02X320080Y341747I0J500D01*
G01Y343391D01*
G02X320580Y343891I500J0D01*
G01X321931D01*
X322340Y344300D01*
Y348391D01*
X322025Y348706D01*
X322009D01*
G02X321038Y349945I0J1000D01*
G03X320527Y351685I-1750J431D01*
G02X320596Y353196I688J726D01*
G03X320715Y353301I-933J1177D01*
G02X322063Y353344I698J-716D01*
G03X323331Y355959I977J1141D01*
G02X322575Y357256I193J981D01*
G03X319770Y357137I-1425J474D01*
G02X319177Y355796I-919J-395D01*
G03X318532Y353391I489J-1420D01*
G02X318316Y351893I-755J-656D01*
G03X317538Y349945I972J-1517D01*
G02X316567Y348706I-971J-239D01*
G01X313692D01*
X311018Y351380D01*
X306930D01*
X305160Y353150D01*
Y357459D01*
G02X305607Y357957I500J1D01*
G03Y360943I-161J1493D01*
G02X305160Y361441I53J497D01*
G01Y361953D01*
X311492Y368285D01*
X312115D01*
X312155Y368244D01*
X312403D01*
X312435Y368242D01*
X312437D01*
X312450Y368241D01*
G03X312627Y368243I73J1400D01*
G01X312645Y368244D01*
X312859D01*
G02X313359Y367744I0J-500D01*
G01Y367676D01*
G03X316132Y368456I1502J-20D01*
G01X316039Y368604D01*
X316078Y368952D01*
X317732Y370606D01*
Y373181D01*
G02X318232Y373659I500J-23D01*
G01X329578D01*
X333718Y369519D01*
G02X333727Y368821I-354J-354D01*
G03X335740Y366603I1090J-1033D01*
G02X336365Y366596I308J-394D01*
G03X336426Y366548I959J1156D01*
G01X336522Y366477D01*
X336630Y366263D01*
Y355075D01*
X335707Y354151D01*
G03X336328Y350899I1415J-1415D01*
G01X336466Y350839D01*
X336630Y350589D01*
G37*
G36*
G01X300103Y374596D02*
G02X301103Y375609I1000J13D01*
G01X305932D01*
X306381Y375160D01*
Y371351D01*
X306226Y371196D01*
X300339D01*
X299804Y371731D01*
Y373549D01*
G03X300103Y374596I-1602J1024D01*
G37*
G36*
G01X300379Y392463D02*
X308074D01*
X308593Y391944D01*
Y379308D01*
X308489Y379204D01*
X298431D01*
G02X297931Y379704I0J500D01*
G01Y391875D01*
X298519Y392463D01*
X298691D01*
G03X300280Y392418I840J1593D01*
G01X300379Y392463D01*
G37*
G36*
G01X304030Y599281D02*
X306939Y602190D01*
Y604882D01*
X307006Y604949D01*
X310862D01*
X312265Y603546D01*
Y600550D01*
X313063Y599752D01*
X313294Y599521D01*
X313333Y599482D01*
Y595552D01*
X314353Y594532D01*
Y589704D01*
X313223Y588574D01*
X304049D01*
X304030Y588593D01*
Y599281D01*
G37*
G36*
G01X313529Y612556D02*
X313660Y612425D01*
Y606045D01*
X313606Y605991D01*
X307000D01*
X306996Y605995D01*
Y613363D01*
X304784Y615575D01*
Y617295D01*
X304739Y617340D01*
Y621574D01*
X304811Y621646D01*
X308479D01*
X309258Y620867D01*
Y617127D01*
X309764Y616621D01*
Y612793D01*
X310001Y612556D01*
X313529D01*
G37*
G36*
G01X300870Y698256D02*
X299565Y699560D01*
Y704196D01*
X298338Y705423D01*
Y708073D01*
X298638Y708373D01*
X304597D01*
X305272Y707698D01*
Y703347D01*
X305017Y702915D01*
X304914Y702851D01*
G03X303984Y700996I1065J-1695D01*
G02X303839Y700602I-498J-40D01*
G01X301492Y698256D01*
X300870D01*
G37*
G36*
G01X313127Y6615D02*
X312279Y7463D01*
Y32128D01*
X312953Y32802D01*
X330357D01*
X330806Y32353D01*
Y7739D01*
X329682Y6615D01*
X313127D01*
G37*
G36*
G01X321609Y335319D02*
G03X321910Y335224I600J1377D01*
G02X322310Y334734I-100J-490D01*
G01Y329343D01*
X322169Y329107D01*
X322049Y329041D01*
G03X321673Y326689I716J-1320D01*
G02X321663Y325992I-363J-343D01*
G01X319800Y324129D01*
X317976D01*
G02X317476Y324629I0J500D01*
G01Y327888D01*
X314674D01*
Y327880D01*
X314382Y327588D01*
X312179D01*
X312126Y327599D01*
G03X310535Y327179I-386J-1760D01*
G02X309159Y327216I-669J744D01*
G01X308030Y328345D01*
Y331624D01*
X308974Y332568D01*
X309043Y332604D01*
G03X309321Y332779I-924J1776D01*
G01X309454Y332878D01*
X309522D01*
Y332939D01*
X309641Y333080D01*
G03X309896Y333457I-1519J1302D01*
G01X309932Y333526D01*
X311870Y335464D01*
Y336808D01*
X312263Y337202D01*
X313190D01*
G03X314618Y337801I0J2002D01*
G01X314692D01*
Y337870D01*
X314792Y338003D01*
G03Y340403I-1602J1200D01*
G01X314692Y340536D01*
Y341020D01*
X314792Y341153D01*
G03Y343553I-1602J1200D01*
G01X314692Y343686D01*
Y343755D01*
X314618D01*
G03X314294Y344023I-1431J-1400D01*
G02X314138Y345564I551J834D01*
G01X316240Y347666D01*
X321118D01*
X321338Y347446D01*
Y345392D01*
G02X320838Y344892I-500J0D01*
G01X319078D01*
Y343990D01*
X318220Y343131D01*
Y341553D01*
X319078Y340694D01*
Y340025D01*
X318907Y339771D01*
X318764Y339714D01*
G03X317923Y337775I559J-1394D01*
G02X317523Y336566I-932J-362D01*
G03X320235Y334630I957J-1527D01*
G02X321609Y335319I974J-227D01*
G37*
G36*
G01X331849Y7462D02*
Y31753D01*
X333048Y32952D01*
X341093D01*
X342150Y31895D01*
Y7950D01*
X340973Y6773D01*
X332538D01*
X331849Y7462D01*
G37*
G36*
G01X328850Y342166D02*
X336310D01*
X336690Y341786D01*
Y325056D01*
X336420Y324786D01*
X328680D01*
X328260Y325206D01*
Y341576D01*
X328850Y342166D01*
G37*
G36*
G01X354425Y488074D02*
G03X354610Y485356I725J-1316D01*
G02X354930Y484924I-179J-467D01*
G01X354959Y484497D01*
X354902Y483553D01*
X354786Y481671D01*
X348018Y453976D01*
X347879Y453486D01*
G02X347261Y453142I-481J137D01*
G01X347150Y453173D01*
X346980Y453326D01*
X346936Y453432D01*
G03X345642Y450982I-1666J-687D01*
G02X346811Y449730I207J-978D01*
G01X345984Y446822D01*
X340494Y441332D01*
X333411D01*
X333197Y441118D01*
X327333D01*
X326833Y441618D01*
X325086D01*
X323772Y442932D01*
X323812Y442971D01*
Y447474D01*
X333842Y457504D01*
Y458270D01*
X336250Y460679D01*
Y484987D01*
G02X336396Y485340I500J0D01*
G01X344120Y493063D01*
Y496133D01*
X344247Y496360D01*
X344359Y496428D01*
G03Y499504I-939J1538D01*
G01X344247Y499572D01*
X344120Y499799D01*
Y514657D01*
X345131Y515668D01*
X345441Y515722D01*
X345585Y515655D01*
G03X347969Y516495I765J1631D01*
G01X348032Y516624D01*
X348274Y516775D01*
X348891D01*
X349180Y516500D01*
X349190Y516300D01*
G03X349660Y515282I1500J75D01*
G02X349663Y513828I-685J-728D01*
G03X351970Y511069I1239J-1308D01*
G02X353556Y510377I592J-806D01*
G01X354535Y501872D01*
X355126Y497328D01*
X354532Y490759D01*
X354683Y488546D01*
G02X354425Y488074I-499J-34D01*
G37*
G36*
G01X346458Y624081D02*
Y598136D01*
G02X345958Y597636I-500J0D01*
G01X340214D01*
X336342Y601508D01*
Y607898D01*
X336137Y608103D01*
Y623924D01*
X336983Y624770D01*
X345769D01*
X346458Y624081D01*
G37*
G36*
G01X350448Y319238D02*
X354303D01*
X359571Y313970D01*
Y313117D01*
X359041Y312587D01*
X350448D01*
X350065Y312970D01*
Y318855D01*
X350448Y319238D01*
G37*
G36*
G01X361380Y279006D02*
X360850Y279536D01*
Y300496D01*
X358805Y302541D01*
X356138D01*
X353577Y305102D01*
X350374D01*
X350014Y305462D01*
Y306686D01*
G02X350514Y307186I500J0D01*
G01X353393D01*
X353513Y307139D01*
X353554Y307125D01*
G03X354786I616J1799D01*
G01X354865Y307152D01*
X355779D01*
X356014Y307012D01*
X356080Y306891D01*
G03X358877Y307336I1320J717D01*
G02X359369Y307746I492J-90D01*
G01X376170D01*
X376700Y307216D01*
Y283203D01*
X372503Y279006D01*
X361380D01*
G37*
G36*
G01X349970Y335122D02*
X360562D01*
X361181Y334503D01*
G02X361328Y334150I-353J-354D01*
G01Y328138D01*
X360110Y326920D01*
X350485D01*
X349190Y328215D01*
Y334342D01*
X349970Y335122D01*
G37*
G36*
G01X340749Y331109D02*
G03X339474Y333573I-1149J967D01*
G02X338390Y334569I-84J996D01*
G01Y335026D01*
X338880Y335516D01*
X346670D01*
G02X347170Y335016I0J-500D01*
G01Y326306D01*
X343472Y322608D01*
X338518D01*
X338470Y322656D01*
Y324536D01*
X338390Y324616D01*
Y326674D01*
G02X339382Y327674I1000J0D01*
G03X340657Y329950I-12J1502D01*
G02X340749Y331109I857J515D01*
G37*
G36*
G01X391202Y472546D02*
G03X390565Y469988I874J-1576D01*
G02X390499Y469362I-419J-272D01*
G01X386626Y465489D01*
Y429699D01*
X382901Y425974D01*
X366198D01*
X364570Y427602D01*
Y458586D01*
X366090Y460106D01*
Y474089D01*
X367359Y477496D01*
X367297Y479243D01*
X366090Y513022D01*
Y520450D01*
G02X367549Y521338I1000J0D01*
G03Y524008I689J1335D01*
G02X366090Y524896I-459J888D01*
G01Y525727D01*
G02X366549Y526225I500J0D01*
G03X367599Y528660I-123J1497D01*
G02Y529284I391J312D01*
G03Y531160I-1173J938D01*
G02Y531784I391J312D01*
G03X367478Y533794I-1173J938D01*
G01X367477Y533795D01*
X367475Y533797D01*
G02Y534504I354J354D01*
G01X369225Y536254D01*
Y537988D01*
X369247Y538024D01*
G03X369530Y541435I-422J1752D01*
G01X369391Y541494D01*
X369225Y541744D01*
Y544442D01*
G02X369467Y544871I500J1D01*
G03X370132Y545724I-773J1288D01*
G03X370164Y545851I-1439J430D01*
G01X370195Y545997D01*
X370851Y546653D01*
X388259D01*
X391460Y543452D01*
Y499319D01*
G02X389933Y498470I-1000J1D01*
G03Y495408I-951J-1531D01*
G02X391460Y494559I527J-850D01*
G01Y494202D01*
G02X389919Y493360I-1000J-1D01*
G03Y490834I-812J-1263D01*
G02X391460Y489992I541J-841D01*
G01Y478793D01*
G02X390960Y478293I-500J0D01*
G01X390777D01*
X390638Y478411D01*
G03X390540Y478487I-969J-1148D01*
G02X390228Y479756I579J815D01*
G03X388600Y481913I-1338J683D01*
G02X387421Y482728I-193J981D01*
G03X386230Y481004I-1481J-250D01*
G02X387409Y480189I193J-981D01*
G03X387592Y479684I1481J251D01*
G02X386972Y478969I-432J-251D01*
G03X387280Y476351I-562J-1393D01*
G02X388583Y476226I579J-815D01*
G03X390144Y475837I1087J1036D01*
G02X391460Y474888I316J-949D01*
G01Y472983D01*
G02X391202Y472546I-500J1D01*
G37*
G36*
G01X363020Y652293D02*
X362857Y652248D01*
G03X362902Y648764I483J-1736D01*
G01X363069Y648722D01*
X363280Y648451D01*
Y642603D01*
X363083Y642406D01*
X363175Y642336D01*
X363280Y642126D01*
Y640374D01*
X363202Y640296D01*
X358696D01*
G02X358196Y640796I0J500D01*
G01Y661871D01*
G02X358696Y662371I500J0D01*
G01X362786D01*
X363050Y662107D01*
Y657666D01*
X363158Y657597D01*
X363280Y657374D01*
Y655866D01*
X363258Y655794D01*
G03X363213Y654910I1722J-531D01*
G01X363223Y654861D01*
Y652561D01*
X363020Y652293D01*
G37*
G36*
G01X364196Y670330D02*
G02X363867Y670207I-328J377D01*
G01X361947D01*
X361920Y670210D01*
G03X361600I-160J-1494D01*
G01X361573Y670207D01*
X360914D01*
X360563Y670367D01*
G03X360506Y670431I-1457J-1240D01*
G01Y670630D01*
X360302D01*
X360176Y670715D01*
G03X360093Y670767I-1057J-1596D01*
G03X358485Y670939I-988J-1639D01*
G01X358349Y670892D01*
X358071Y670957D01*
X357792Y671236D01*
Y703772D01*
X358700Y704680D01*
X364579D01*
X366060Y703199D01*
Y702776D01*
X365958Y702609D01*
X365928Y702552D01*
G03Y700868I1592J-842D01*
G01X365958Y700811D01*
X366060Y700644D01*
Y700202D01*
G02X365560Y699702I-500J0D01*
G01X365468D01*
X365381Y699735D01*
G03X364219Y699698I-537J-1403D01*
G02X362997Y700016I-416J910D01*
G03X360863Y697943I-1211J-888D01*
G02X360836Y696344I-614J-789D01*
G03X361486Y693644I881J-1216D01*
G02X362326Y692775I-153J-988D01*
G03X364829Y691336I1789J215D01*
G01X364873Y691355D01*
X364968Y691376D01*
G02X365570Y690816I107J-489D01*
G01X365564Y690772D01*
X365554Y690731D01*
X365553Y690727D01*
X365550Y690716D01*
G03X365523Y690587I1945J-474D01*
G02X364619Y689759I-986J169D01*
G03X364115Y689644I145J-1796D01*
G02X362911Y690037I-362J932D01*
G03X361990Y687766I-1265J-809D01*
G02X363128Y687210I229J-973D01*
G03X363587Y686599I1638J752D01*
G02X363619Y685115I-654J-756D01*
G03X363512Y683040I1030J-1093D01*
G02X363381Y681606I-757J-654D01*
G03X363383Y679260I939J-1172D01*
G02X363591Y677923I-624J-782D01*
G03X363321Y677266I1499J-1000D01*
G02X362128Y676479I-982J190D01*
G03X362327Y673601I-318J-1468D01*
G02X363666Y672766I344J-939D01*
G03X364491Y671577I1494J156D01*
G01X364610Y671518D01*
X364734Y671335D01*
G02X364740Y670785I-415J-280D01*
G01X364631Y670616D01*
X364518Y670555D01*
G03X364196Y670330I865J-1581D01*
G37*
G36*
G01X395092Y588393D02*
X385254D01*
X381896D01*
X380892Y589397D01*
Y598506D01*
X381621Y599235D01*
X385677D01*
X395251D01*
Y588552D01*
X395092Y588393D01*
G37*
G36*
G01X433071Y357480D02*
G02X393701I-19685J0D01*
G01Y377165D01*
G02X433071I19685J0D01*
G01Y357480D01*
G37*
G36*
G01X404920Y463441D02*
X404960Y463401D01*
Y450560D01*
X408040Y447480D01*
X412177D01*
X412650Y447007D01*
Y410408D01*
X411110Y408868D01*
X399170D01*
X397050Y410988D01*
Y462318D01*
X398173Y463441D01*
X404920D01*
G37*
G36*
G01X402336Y605085D02*
X399599D01*
X399532Y605018D01*
Y602462D01*
Y602326D01*
X397235Y600029D01*
X396623Y599417D01*
Y598382D01*
Y596001D01*
Y588729D01*
Y586004D01*
X397457Y585170D01*
X401552D01*
X402336Y585954D01*
Y589954D01*
Y592111D01*
Y597668D01*
Y605085D01*
G37*
G36*
G01X406122Y612692D02*
X406253Y612561D01*
Y606181D01*
X406199Y606127D01*
X399593D01*
X399589Y606131D01*
Y613499D01*
X397377Y615711D01*
Y617431D01*
X397332Y617476D01*
Y621710D01*
X397404Y621782D01*
X401072D01*
X401851Y621003D01*
Y617263D01*
X402357Y616757D01*
Y612929D01*
X402594Y612692D01*
X406122D01*
G37*
G36*
G01X450150Y456390D02*
Y412293D01*
X446499Y408642D01*
X417150D01*
X415380Y410412D01*
Y447301D01*
X413724Y448957D01*
X408880D01*
X408110Y449727D01*
Y463025D01*
X408880Y463795D01*
X413371D01*
X417982Y459184D01*
X447356D01*
X450150Y456390D01*
G37*
G36*
G01X419072Y488852D02*
X407248D01*
X403343D01*
X402834D01*
X402512Y489174D01*
Y500910D01*
X402875Y501273D01*
X403523Y501921D01*
X407186D01*
X419196D01*
X419632Y501485D01*
Y489412D01*
X419072Y488852D01*
G37*
G36*
G01X406916Y530978D02*
G03Y534026I-962J1524D01*
G02X406683Y534448I267J423D01*
G01Y534649D01*
G02X407970Y535607I1000J0D01*
G03Y539059I516J1726D01*
G02X406683Y540017I-287J958D01*
G01Y548419D01*
X407651Y549387D01*
X412377D01*
X415160Y552170D01*
X426280D01*
X427270Y551180D01*
Y549913D01*
X427152Y549692D01*
X427046Y549622D01*
G03Y546616I993J-1503D01*
G01X427152Y546546D01*
X427270Y546325D01*
Y545817D01*
X426436Y544983D01*
Y539095D01*
X426278Y538937D01*
X415712D01*
X414872Y538097D01*
Y523454D01*
X416516Y521810D01*
Y509076D01*
X414872Y507432D01*
Y504229D01*
X414763Y504120D01*
X407404D01*
X406683Y504841D01*
Y505619D01*
X406725Y505715D01*
G03Y506917I-1377J601D01*
G01X406683Y507013D01*
Y513831D01*
G02X407732Y514830I1000J0D01*
G03X409277Y515507I133J1797D01*
G02X410606Y515706I774J-633D01*
G03X412855Y517456I833J1250D01*
G03X411436Y518458I-1416J-500D01*
G03X410392Y518033I3J-1502D01*
G02X409056Y517980I-697J716D01*
G03X407732Y518424I-1190J-1353D01*
G02X406683Y519423I-49J999D01*
G01Y524626D01*
G02X407715Y525625I1000J0D01*
G03Y529227I61J1801D01*
G02X406683Y530226I-32J999D01*
G01Y530556D01*
G02X406916Y530978I500J-1D01*
G37*
G36*
G01X439024Y504476D02*
X437041Y506459D01*
Y507683D01*
X437192Y508038D01*
X437252Y508102D01*
G03Y510152I-1098J1025D01*
G01X437192Y510216D01*
X437041Y510571D01*
Y513329D01*
G02X438655Y514118I1000J0D01*
G03Y516962I1107J1422D01*
G02X437041Y517751I-614J789D01*
G01Y521546D01*
G02X438655Y522335I1000J0D01*
G03Y525179I1107J1422D01*
G02X437041Y525968I-614J789D01*
G01Y537604D01*
X437648Y538210D01*
Y543552D01*
X437020Y544179D01*
Y551931D01*
X435686Y553265D01*
X415604D01*
X415510Y553172D01*
X414745D01*
X411962Y550388D01*
X407930D01*
G02X407430Y550888I0J500D01*
G01Y559494D01*
G02X407930Y559994I500J0D01*
G01X447860D01*
X452045Y555809D01*
X452117Y555566D01*
X452091Y555442D01*
G03X454227Y553306I1763J-373D01*
G02X454684Y553170I103J-489D01*
G01X455461Y552393D01*
G02Y551685I-353J-354D01*
G02X454849Y551611I-353J354D01*
G03X454481Y548358I-932J-1542D01*
G02X455794Y547408I313J-950D01*
G01Y547038D01*
G02X455490Y546578I-500J0D01*
G01X455226Y546466D01*
G02X454741Y546518I-196J460D01*
G03X454404Y543388I-1041J-1471D01*
G02X455794Y542467I390J-921D01*
G01Y531227D01*
X455694Y531021D01*
X455604Y530949D01*
G03Y528123I1118J-1413D01*
G01X455694Y528051D01*
X455794Y527845D01*
Y524385D01*
X453365Y521956D01*
G02X452715Y521665I-707J707D01*
G02X452220Y521983I-29J499D01*
G03X449888Y519651I-1680J-652D01*
G02X450206Y519156I-181J-466D01*
G02X449915Y518506I-998J57D01*
G01X446046Y514637D01*
Y508276D01*
X442246Y504476D01*
X439024D01*
G37*
G36*
G01X425886Y520148D02*
X428575D01*
X429028Y519695D01*
Y513864D01*
X428006Y512842D01*
X424485D01*
X423804Y513523D01*
Y515264D01*
X425356Y516816D01*
Y519618D01*
X425886Y520148D01*
G37*
G36*
G01X424711Y521493D02*
X422046Y524158D01*
X416580D01*
X416323Y524415D01*
Y537922D01*
X416336Y537935D01*
X426693D01*
X426776Y538019D01*
X429859D01*
X429941Y537937D01*
Y522370D01*
X429064Y521493D01*
X424711D01*
G37*
G36*
G01X428664Y542886D02*
X429737Y543959D01*
X435824D01*
X436646Y543137D01*
Y538625D01*
X436162Y538141D01*
X434087D01*
X432489Y539739D01*
X428859D01*
X428664D01*
Y542886D01*
G37*
G36*
G01X526890Y94519D02*
X542483Y78927D01*
G02X542630Y78573I-353J-354D01*
G01Y78338D01*
X542865D01*
G02X543219Y78191I0J-500D01*
G01X564098Y57311D01*
Y26219D01*
X569274Y21044D01*
G02X569420Y20691I-354J-353D01*
G01Y8126D01*
X569140Y7846D01*
X443230D01*
G02X442730Y8346I0J500D01*
G01Y55131D01*
X456640Y69041D01*
Y82835D01*
X457442Y83637D01*
X467291D01*
X471097Y87443D01*
Y108616D01*
X480750Y118269D01*
X486792D01*
X486825Y118265D01*
G03X487215I195J1489D01*
G01X487248Y118269D01*
X518733D01*
X520922Y116080D01*
G02X520899Y114644I-707J-707D01*
G03X523445Y112098I1212J-1334D01*
G02X524881Y112121I729J-684D01*
G01X525928Y111074D01*
Y110019D01*
X525826Y109812D01*
X525734Y109740D01*
X525733Y109739D01*
G03X525734Y106888I1102J-1425D01*
G02X525928Y106492I-306J-395D01*
G01Y102826D01*
X526890Y101864D01*
Y94519D01*
G37*
G36*
G01X464410Y90599D02*
Y88797D01*
Y85324D01*
X463742Y84656D01*
X436028D01*
X435460Y85224D01*
Y93108D01*
X436556Y94204D01*
X447020D01*
X463786D01*
X464410Y93580D01*
Y90599D01*
G37*
G36*
G01X461399Y181755D02*
G03X463241Y181744I930J1544D01*
G03X463409Y181797I-457J1743D01*
G01X463492Y181827D01*
X464531D01*
G02X465031Y181327I0J-500D01*
G01Y153327D01*
G02X464531Y152827I-500J0D01*
G01X444531D01*
G02X444031Y153327I0J500D01*
G01Y181327D01*
G02X444531Y181827I500J0D01*
G01X445122D01*
X445130Y181820D01*
X445137Y181827D01*
X461280D01*
X461399Y181755D01*
G37*
G36*
G01X437741Y487878D02*
Y485121D01*
G02X437241Y484621I-500J0D01*
G01X435014D01*
X434769Y484866D01*
Y500863D01*
X435377Y501470D01*
X437607D01*
X437946Y501809D01*
X443495D01*
X455194D01*
X464321D01*
X468225D01*
X468802Y501232D01*
Y489334D01*
X468369Y488901D01*
X465243D01*
X465242Y488900D01*
X455194D01*
X452137D01*
X451852Y488615D01*
X449645D01*
X438478D01*
X437741Y487878D01*
G37*
G36*
G01X453000Y97059D02*
X452426Y97633D01*
X452402Y97794D01*
G03X452367Y97957I-1484J-233D01*
G01X452350Y98021D01*
Y98311D01*
X451018Y99644D01*
X448000Y102662D01*
Y106432D01*
G02X448500Y106932I500J0D01*
G01X453468D01*
G02X453968Y106432I0J-500D01*
G01Y103481D01*
X454340Y103110D01*
Y102095D01*
X455920Y100515D01*
Y97537D01*
X455442Y97059D01*
X453000D01*
G37*
G36*
G01X476003Y453096D02*
X476370Y452729D01*
Y407907D01*
X475368Y406905D01*
X459620D01*
X453310Y413215D01*
Y447750D01*
X458656Y453096D01*
X476003D01*
G37*
G36*
G01X449755Y487183D02*
X449859Y487287D01*
X468657D01*
X469090Y486854D01*
Y474787D01*
X468585Y474282D01*
X450275D01*
X449755Y474802D01*
Y487183D01*
G37*
G36*
G01X468894Y516115D02*
Y508978D01*
Y505743D01*
X468312Y505161D01*
X460860D01*
X459262Y506759D01*
Y508448D01*
Y515068D01*
X461423Y517229D01*
X467780D01*
X468894Y516115D01*
G37*
G36*
G01X474672Y135001D02*
X482898D01*
Y126187D01*
X482868Y126157D01*
Y124869D01*
X482585Y124586D01*
X481395D01*
X481346Y124635D01*
X473647D01*
X472903Y125380D01*
Y133232D01*
X474672Y135001D01*
G37*
G36*
G01X496242Y136248D02*
X496700Y135790D01*
Y132755D01*
X495890Y131945D01*
X494050D01*
X493424Y131319D01*
Y122471D01*
X492123Y121170D01*
X487832D01*
X484212Y124790D01*
Y135570D01*
X484890Y136248D01*
X496242D01*
G37*
G36*
G01X525272Y437634D02*
G03X521999Y439134I-1605J818D01*
G02X521536Y438823I-463J189D01*
G01X521052D01*
X520659Y438430D01*
X520223D01*
G02X519723Y438930I0J500D01*
G01Y438937D01*
G03X519690Y439292I-1802J12D01*
G03X516160Y439330I-1761J383D01*
G03X516119Y438937I1761J-382D01*
G01Y438930D01*
G02X515619Y438430I-500J0D01*
G01X503082D01*
X503012Y438451D01*
G03X501976I-518J-1726D01*
G01X501906Y438430D01*
X500493D01*
G02X499534Y439716I-1J1000D01*
G03X499190Y441433I-1716J549D01*
G03X496173Y441001I-1372J-1168D01*
G02X494553Y440702I-913J408D01*
G01X493113Y442142D01*
Y456115D01*
X496077Y459079D01*
X503445D01*
G02X503944Y458614I0J-500D01*
G03X506940I1498J105D01*
G02X507439Y459079I499J-35D01*
G01X508669D01*
X509493Y458255D01*
Y452037D01*
X509279Y451766D01*
X509111Y451725D01*
G03X508420Y449185I353J-1460D01*
G03X510508I1044J1080D01*
G02X511890Y449154I675J-738D01*
G01X513023Y448021D01*
X534753D01*
X537940Y451208D01*
Y451507D01*
X538066Y451634D01*
Y462616D01*
X543238Y467788D01*
Y467921D01*
G02X543738Y468421I500J0D01*
G01X543995D01*
X544139Y468285D01*
G03X546928Y471155I1374J1455D01*
G01X546546Y471537D01*
X546232Y471852D01*
X545659Y472425D01*
X543530D01*
X543092Y472863D01*
Y473057D01*
X542447Y473702D01*
X542421Y473862D01*
G03X541177Y475106I-1483J-239D01*
G01X541017Y475132D01*
X533378Y482771D01*
Y484430D01*
X534354Y485406D01*
X544214D01*
X545854Y483766D01*
X545889Y483636D01*
G03X546951Y482574I1451J389D01*
G01X547081Y482539D01*
X552219Y477401D01*
Y448290D01*
G02X551187Y447290I-1000J0D01*
G03Y444288I-47J-1501D01*
G02X552219Y443288I32J-1000D01*
G01Y422932D01*
X550608Y421321D01*
X546265D01*
X544654Y419710D01*
Y416244D01*
X543434Y415024D01*
X528205D01*
X524300Y418929D01*
Y424298D01*
X525353Y425351D01*
Y429577D01*
G02X526377Y430576I1000J-1D01*
G03X526569Y430581I57J1501D01*
G03X526677Y430594I-125J1496D01*
G02X527049Y430505I78J-494D01*
G01X527216Y430384D01*
X527249Y430180D01*
G03X530816Y430243I1779J288D01*
G02X531344Y430679I496J-63D01*
G03X531837Y430729I97J1499D01*
G03X529994Y432584I-397J1449D01*
G02X529407Y432231I-481J136D01*
G03X528499Y432192I-379J-1762D01*
G02X527875Y432522I-146J478D01*
G03X527340Y433279I-1434J-446D01*
G03X526580Y433572I-900J-1202D01*
G03X526377Y433578I-146J-1495D01*
G02X525353Y434577I-24J1000D01*
G01Y437064D01*
X525249Y437168D01*
X525198Y437488D01*
X525272Y437634D01*
G37*
G36*
G01X496531Y486751D02*
Y482456D01*
X495652Y481577D01*
X491968D01*
X491284Y482261D01*
Y486922D01*
X491894Y487532D01*
X495750D01*
X496531Y486751D01*
G37*
G36*
G01X490003Y489653D02*
X488838Y490818D01*
Y498080D01*
X490015Y499257D01*
X502585D01*
X504681Y497161D01*
Y497136D01*
G02X504570Y496822I-500J0D01*
G03Y494938I1170J-942D01*
G01X504681Y494800D01*
Y490339D01*
X503995Y489653D01*
X490003D01*
G37*
G36*
G01X528639Y536398D02*
G02X527641Y535345I-999J-53D01*
G01X525635D01*
G02X524702Y535986I0J1000D01*
G03X524240Y537866I-1964J514D01*
G01Y537902D01*
X524207D01*
G03X524174Y537936I-1474J-1397D01*
G01X524115Y537994D01*
G02X523968Y538349I353J354D01*
G01Y540325D01*
G03X523658Y541404I-2030J1D01*
G01Y542157D01*
X523701Y542254D01*
G03Y543796I-1738J771D01*
G01X523658Y543893D01*
Y545325D01*
X517828Y551155D01*
X504566D01*
X504431Y551258D01*
G03X502245I-1093J-1433D01*
G01X502110Y551155D01*
X501811D01*
G02X501368Y551422I-1J500D01*
G01Y551423D01*
G03X498536Y550714I-1330J-698D01*
G01X498537Y550614D01*
X498461Y550428D01*
X498388Y550355D01*
Y547805D01*
X496638Y546055D01*
X489788D01*
X488698Y547145D01*
Y550495D01*
X492052Y553849D01*
X496299D01*
G03X496338Y553848I68J1900D01*
G01X500651D01*
X500744Y553942D01*
X501383Y554580D01*
G03X501582Y554814I-1345J1345D01*
G01X501652Y554912D01*
X501867Y555023D01*
X506640D01*
Y555163D01*
X506932Y555455D01*
X507944D01*
X508376Y555023D01*
X513838D01*
G03Y558827I0J1902D01*
G01X508236D01*
Y558727D01*
X507944Y558435D01*
X506932D01*
X506540Y558827D01*
X506246D01*
X504648Y560425D01*
X503835D01*
X503651Y560502D01*
X503626Y560527D01*
X503336D01*
X502041Y561822D01*
G02X501902Y562264I353J354D01*
G01X501919Y562356D01*
X501932Y562393D01*
G03X500138Y564927I-1794J632D01*
G01X498936D01*
X498538Y565325D01*
X497438D01*
X496338Y566425D01*
Y568825D01*
X497445Y569932D01*
X497590Y569963D01*
G03X498102Y570158I-378J1762D01*
G01X498217Y570223D01*
X500538D01*
G03X501112Y570317I0J1802D01*
G03X501390Y570438I-577J1707D01*
G01X501500Y570497D01*
X502126D01*
Y570388D01*
X502343D01*
G03X503628Y569888I1285J1401D01*
G01X509081D01*
X509213Y569792D01*
G03X509745Y569518I1126J1532D01*
G03X512001Y570403I593J1807D01*
G02X512438Y570660I437J-243D01*
G01X525343D01*
X530138Y565865D01*
Y541708D01*
X529850Y541261D01*
X529737Y541200D01*
G03X529293Y540870I900J-1675D01*
G01X528636Y540213D01*
Y536500D01*
G03X528639Y536398I1902J5D01*
G37*
G36*
G01X498768Y420120D02*
Y432011D01*
G02X499268Y432511I500J0D01*
G01X508245D01*
X508381Y432406D01*
G03X510591I1105J1423D01*
G01X510727Y432511D01*
X518000D01*
G02X518500Y432011I0J-500D01*
G01Y420120D01*
G02X518000Y419620I-500J0D01*
G01X499268D01*
G02X498768Y420120I0J500D01*
G37*
G36*
G01X502274Y461783D02*
X499764Y464293D01*
Y469271D01*
X499798Y469358D01*
G03X498297Y471804I-1679J653D01*
G02X497846Y472302I49J498D01*
G01Y486187D01*
X498529Y486870D01*
X512685D01*
X515915Y483640D01*
G02X515666Y482044I-707J-707D01*
G03X517854Y480760I687J-1336D01*
G02X518854Y481794I999J34D01*
G01X530450D01*
X531551Y480693D01*
Y477867D01*
X530408Y476725D01*
X513123D01*
X513046Y476647D01*
X507732D01*
X504240Y473155D01*
Y466225D01*
X504160Y466102D01*
G03X507258Y463603I1683J-1084D01*
G01X507733Y464077D01*
X507754D01*
X507949Y464272D01*
X509560D01*
X509707Y464125D01*
Y462466D01*
X509024Y461783D01*
X502274D01*
G37*
G36*
G01X560378Y566374D02*
G02X560159Y565960I-500J0D01*
G03Y562982I1015J-1489D01*
G02X560378Y562568I-281J-414D01*
G01Y549164D01*
G02X559878Y548664I-500J0D01*
G01X559733D01*
X559490Y548817D01*
X559427Y548948D01*
G03X559219Y549286I-1715J-822D01*
G01X559115Y549421D01*
Y549627D01*
X558889D01*
X558763Y549710D01*
G03X556663I-1050J-1585D01*
G01X556537Y549627D01*
X555739D01*
X555613Y549710D01*
G03X554563Y550026I-1050J-1585D01*
G01X554239D01*
G02X553239Y551052I0J1000D01*
G03X551338Y553002I-1901J48D01*
G01X548238D01*
G03X547077Y552606I1J-1902D01*
G01X546942Y552502D01*
X546736D01*
Y552276D01*
X546653Y552150D01*
G03X546431Y550507I1585J-1051D01*
G01X546456Y550431D01*
Y550352D01*
G02X545956Y549852I-500J0D01*
G01X545413D01*
G03Y546048I0J-1902D01*
G01X548238D01*
G03X549005Y546210I-1J1902D01*
G02X549613Y546043I201J-458D01*
G03X552506Y545803I1548J1105D01*
G01X552926Y546224D01*
X554563D01*
G03X554660Y546226I9J1901D01*
G02X555712Y545227I52J-999D01*
G01Y544225D01*
G03X556212Y542940I1901J0D01*
G01Y541610D01*
G03Y539040I1401J-1285D01*
G01Y538824D01*
X556437D01*
X556562Y538740D01*
G03X557613Y538424I1050J1585D01*
G01X559878D01*
G02X560378Y537924I0J-500D01*
G01Y533788D01*
X558281Y531691D01*
G02X556605Y532149I-707J707D01*
G03X554412Y529956I-1745J-448D01*
G02X554870Y528280I-249J-969D01*
G01X552792Y526202D01*
X552158D01*
G02X551658Y526702I0J500D01*
G01Y526761D01*
X551672Y526819D01*
G03X548118Y527216I-1752J422D01*
G02X547118Y526202I-1000J-14D01*
G01X533860D01*
X532580Y527482D01*
Y533728D01*
G02X533876Y534684I1000J1D01*
G03X535723Y535098I563J1816D01*
G01X535940D01*
Y535324D01*
X536023Y535449D01*
G03X536340Y536500I-1584J1051D01*
G01Y538970D01*
X536381Y539065D01*
G03X533945Y541596I-1743J760D01*
G02X532580Y542527I-365J931D01*
G01Y566803D01*
X527413Y571970D01*
X512773D01*
X510738Y574005D01*
X503788D01*
X502039Y575754D01*
X502005Y575813D01*
G03X501828Y576071I-1568J-886D01*
G03X501712Y576199I-1391J-1144D01*
G01X500484Y577427D01*
X497213D01*
G03X497044Y577419I1J-1802D01*
G03X496944Y577406I182J-1792D01*
G02X496516Y577547I-74J495D01*
G01X496238Y577825D01*
Y595305D01*
X496710Y595777D01*
X501811D01*
X502566Y595022D01*
X507471D01*
X507870Y595421D01*
Y596993D01*
X509685Y598808D01*
X517236D01*
G02X517736Y598308I0J-500D01*
G01Y597200D01*
G03X518053Y596149I1901J0D01*
G01X518136Y596024D01*
Y595799D01*
Y595798D01*
X518353D01*
G03X518720Y595535I1283J1403D01*
G01X518840Y595469D01*
X518978Y595234D01*
Y595015D01*
X525064D01*
G02X525564Y594515I0J-500D01*
G01Y594474D01*
X525558Y594437D01*
G03X525543Y594310I1880J-286D01*
G03X525536Y594150I1895J-163D01*
G01Y589737D01*
X526293Y588980D01*
G03X529398Y591044I1345J1344D01*
G03X529382Y591084I-1773J-686D01*
G01X529340Y591179D01*
Y594150D01*
G03X529333Y594310I-1902J-3D01*
G03X529318Y594437I-1895J-159D01*
G01X529312Y594474D01*
Y594515D01*
G02X529812Y595015I500J0D01*
G01X537982D01*
G02X538482Y594515I0J-500D01*
G01Y594466D01*
X538472Y594418D01*
G03X538436Y594050I1866J-368D01*
G01Y589737D01*
X539356Y588817D01*
G03X542315Y591167I1345J1344D01*
G01X542240Y591289D01*
Y594050D01*
G03X542204Y594418I-1902J0D01*
G01X542194Y594466D01*
Y594515D01*
G02X542694Y595015I500J0D01*
G01X544338D01*
X545038Y594315D01*
Y589425D01*
X549228Y585235D01*
X558848D01*
X559769Y584314D01*
G02X559824Y582959I-707J-707D01*
G03X560165Y580317I1374J-1166D01*
G02X560378Y579907I-287J-410D01*
G01Y573294D01*
G02X560254Y572964I-500J0D01*
G03Y570586I1354J-1189D01*
G02X560378Y570256I-376J-330D01*
G01Y566374D01*
G37*
G36*
G01X536938Y469179D02*
Y451623D01*
X534338Y449023D01*
X513438D01*
X510738Y451723D01*
Y472923D01*
X513538Y475723D01*
X533738D01*
X536938Y472523D01*
Y471667D01*
X536853Y471541D01*
G03Y469305I1660J-1118D01*
G01X536938Y469179D01*
G37*
G36*
G01X571270Y98454D02*
X567938Y95123D01*
X567543D01*
G02X567043Y95623I0J500D01*
G01Y95789D01*
X567142Y95922D01*
G03X564495Y96402I-1204J898D01*
G02X563535Y95123I-960J-279D01*
G01X553734D01*
G02X552823Y96535I0J1000D01*
G03X550420Y96064I-1369J619D01*
G01X550489Y95999D01*
X550566Y95834D01*
G02X550112Y95123I-453J-211D01*
G01X549930D01*
G02X548951Y96326I0J1000D01*
G03X546009I-1471J306D01*
G02X545030Y95123I-979J-203D01*
G01X533938D01*
X530326Y98735D01*
X530269Y99037D01*
X530331Y99179D01*
G03X529449Y101200I-1376J602D01*
G01X529310Y101248D01*
X528938Y101724D01*
Y112140D01*
X529042Y112275D01*
G03X529377Y113742I-1429J1098D01*
G01X529351Y113867D01*
X529423Y114108D01*
X532938Y117623D01*
X562938D01*
X562974Y117586D01*
X567793D01*
G02X568146Y117440I0J-500D01*
G01X571476Y114109D01*
Y98661D01*
X571270Y98454D01*
G37*
G36*
G01X544657Y220561D02*
X541074Y224144D01*
Y224208D01*
X537920Y227362D01*
Y234141D01*
X537984Y234255D01*
G03Y235731I-1308J738D01*
G01X537920Y235845D01*
Y238575D01*
X537934Y238634D01*
G03Y239352I-1458J359D01*
G01X537920Y239411D01*
Y241611D01*
G02X538058Y241956I500J0D01*
G03Y244030I-1086J1037D01*
G02X537920Y244375I362J345D01*
G01Y246315D01*
X537959Y246408D01*
G03Y247578I-1383J585D01*
G01X537920Y247671D01*
Y247875D01*
G02X539127Y248854I1000J0D01*
G03X538674Y251616I311J1469D01*
G01X538557Y251547D01*
X538420D01*
G02X537920Y252047I0J500D01*
G01Y252662D01*
X541074Y255816D01*
Y274495D01*
X542374Y275795D01*
G02X543832Y275749I707J-707D01*
G03X546369Y278286I1391J1146D01*
G02X546323Y279744I661J751D01*
G01X549174Y282595D01*
X554708D01*
G02X555606Y281156I0J-1000D01*
G03X558808I1601J-828D01*
G02X559706Y282595I898J439D01*
G01X568874D01*
X572074Y279395D01*
Y271695D01*
G02X571574Y271195I-500J0D01*
G01X559630D01*
G02X559130Y271695I0J500D01*
G01Y271743D01*
X559139Y271790D01*
G03X559142Y271807I-1969J356D01*
G03X559150Y271850I-1963J388D01*
G03X559176Y272170I-1976J322D01*
G01Y274467D01*
X559182Y274506D01*
G03X555792Y276243I-1975J322D01*
G01X555606Y276057D01*
X555452Y275904D01*
X555172Y275624D01*
Y272170D01*
G03X555198Y271850I2002J2D01*
G03X555206Y271807I1971J345D01*
G03X555209Y271790I1972J339D01*
G01X555218Y271743D01*
Y271695D01*
G02X554718Y271195I-500J0D01*
G01X553874D01*
X553174Y270495D01*
Y245896D01*
G02X552674Y245396I-500J0D01*
G01X552649D01*
G03X552599Y245397I-65J-2001D01*
G01X551401D01*
G03X548953Y245610I-1361J-1468D01*
G02X547444Y246191I-543J839D01*
G03X543952Y246151I-1741J-466D01*
G03X546605Y244165I1751J-426D01*
G02X548083Y243509I500J-866D01*
G03X548122Y243356I1957J417D01*
G03X548274Y242987I1917J574D01*
G03X548625Y242514I1765J943D01*
G01X548962Y242177D01*
X549239Y241899D01*
X549745Y241393D01*
X550054D01*
G02X550554Y240893I0J-500D01*
G01Y239501D01*
G03X550592Y239113I2002J0D01*
G03X551054Y238178I1964J389D01*
G01X551058Y238174D01*
X551205Y238000D01*
X551222D01*
X551356Y237899D01*
G03X551690Y237697I1198J1603D01*
G03X552993Y237548I866J1804D01*
G01X553119Y237576D01*
X553364Y237505D01*
X555474Y235395D01*
X567401D01*
G02X567901Y234895I0J-500D01*
G01Y234857D01*
X567895Y234820D01*
G03X567872Y234520I1979J-303D01*
G01Y231795D01*
G03X571876I2002J0D01*
G01Y234520D01*
G03X571853Y234820I-2002J-3D01*
G01X571847Y234857D01*
Y234895D01*
G02X572347Y235395I500J0D01*
G01X588074D01*
X589274Y236595D01*
Y242495D01*
X589974Y243195D01*
X593674D01*
X594572Y242297D01*
Y242295D01*
X594727Y242141D01*
G02X594874Y241787I-353J-354D01*
G01Y238868D01*
G02X594592Y238419I-500J1D01*
G01X594591Y238418D01*
G03Y235172I783J-1623D01*
G01X594592Y235171D01*
G02X594874Y234722I-218J-450D01*
G01Y222385D01*
X594399Y221910D01*
G02X592899Y222009I-707J708D01*
G03X590205Y221069I-1192J-914D01*
G01Y221061D01*
G02X589705Y220561I-500J0D01*
G01X589497D01*
X589219Y220797D01*
X589188Y220978D01*
G03X586226I-1481J-250D01*
G01X586195Y220797D01*
X585917Y220561D01*
X585500D01*
X585220Y220802D01*
X585192Y220986D01*
G03X582222I-1485J-224D01*
G01X582194Y220802D01*
X581914Y220561D01*
X581490D01*
X581214Y220786D01*
X581179Y220961D01*
G03X578235I-1472J-299D01*
G02X577745Y220561I-490J100D01*
G01X549136D01*
X548882Y220734D01*
X548825Y220878D01*
G03X545471I-1677J-658D01*
G01X545414Y220734D01*
X545160Y220561D01*
X544657D01*
G37*
G36*
G01X531219Y399707D02*
X529634Y401292D01*
Y404957D01*
X529621Y404970D01*
Y412096D01*
X530695Y413170D01*
X544459D01*
X545289Y412340D01*
Y408274D01*
X545253Y408227D01*
Y403015D01*
X541945Y399707D01*
X538802D01*
X531219D01*
G37*
G36*
G01X554574Y243720D02*
Y247270D01*
X554579Y247306D01*
G03Y247884I-1980J289D01*
G01X554574Y247920D01*
Y257770D01*
X554579Y257806D01*
G03Y258384I-1980J289D01*
G01X554574Y258420D01*
Y268895D01*
X555774Y270095D01*
X586574D01*
X587974Y268695D01*
Y237495D01*
X587074Y236595D01*
X556874D01*
X554574Y238895D01*
Y243070D01*
X554579Y243106D01*
G03Y243684I-1980J289D01*
G01X554574Y243720D01*
G37*
G36*
G01X547997Y405581D02*
X547247Y406331D01*
X547223Y406495D01*
G03X546992Y407148I-1783J-263D01*
G01X546923Y407266D01*
Y413073D01*
X547289Y413439D01*
X554049D01*
X555099Y412389D01*
Y406581D01*
X554099Y405581D01*
X547997D01*
G37*
G36*
G01X545910Y623191D02*
Y633541D01*
G02X546410Y634041I500J0D01*
G01X559803D01*
X560054Y633790D01*
Y622797D01*
X559947Y622690D01*
X546411D01*
X545910Y623191D01*
G37*
G36*
G01X579941Y155750D02*
G03X582346Y153345I1624J-781D01*
G02X582917Y153248I217J-450D01*
G01X588478Y147687D01*
Y141067D01*
G02X587976Y140567I-500J0D01*
G03Y136963I-8J-1802D01*
G02X588478Y136463I2J-500D01*
G01Y130216D01*
X588118Y129856D01*
X571763D01*
X570914Y130705D01*
Y161129D01*
X571208Y161422D01*
X574742D01*
X579957Y156208D01*
X580010Y155894D01*
X579941Y155750D01*
G37*
G36*
G01X568482Y203099D02*
X573182D01*
X574382Y201899D01*
Y193699D01*
X573482Y192799D01*
X568982D01*
X567982Y193799D01*
Y202599D01*
X568482Y203099D01*
G37*
G36*
G01X573829Y203868D02*
X573597Y204101D01*
X569596D01*
X569594Y204103D01*
X568920D01*
X568462Y204560D01*
G02X568315Y204914I353J354D01*
G01Y216021D01*
X569117Y216823D01*
X604433D01*
G02X605433Y215795I0J-1000D01*
G03X607005Y212346I4300J-123D01*
G02X607188Y211959I-317J-387D01*
G01Y202088D01*
X606600Y201500D01*
X595891D01*
X593670Y203721D01*
X574183D01*
G02X573829Y203868I0J500D01*
G37*
G36*
G01X577392Y189909D02*
X576340Y190961D01*
Y202219D01*
G02X576840Y202719I500J0D01*
G01X592744D01*
X593492Y201972D01*
Y190909D01*
X592492Y189909D01*
X577392D01*
G37*
G36*
G01X575874Y276895D02*
X574674Y278095D01*
Y290595D01*
X575274Y291195D01*
X579274D01*
X579572Y290897D01*
Y277193D01*
X579274Y276895D01*
X575874D01*
G37*
G36*
G01X581074Y273795D02*
X580574Y274295D01*
Y295279D01*
G02X581074Y295779I500J0D01*
G01X583574D01*
G02X584074Y295279I0J-500D01*
G01Y283795D01*
X584374Y283495D01*
X586874D01*
X587674Y282695D01*
Y280795D01*
X587074Y280195D01*
X584574D01*
X584074Y279695D01*
Y274995D01*
X582874Y273795D01*
X581074D01*
G37*
G36*
G01X574626Y295522D02*
X575915Y295779D01*
X578974D01*
G02X579474Y295279I0J-500D01*
G01Y292795D01*
X579074Y292395D01*
X575124D01*
X574224Y293295D01*
Y295031D01*
G02X574626Y295522I500J1D01*
G37*
G36*
G01X609774Y255195D02*
X609974Y254995D01*
Y249995D01*
X609174Y249195D01*
X596174D01*
X595574Y249795D01*
Y254895D01*
X595874Y255195D01*
X609774D01*
G37*
G36*
G01X596074Y239095D02*
X595876Y239293D01*
Y242410D01*
X595574Y242711D01*
Y243595D01*
X595774Y243795D01*
X609774D01*
X610174Y243395D01*
Y239995D01*
X609274Y239095D01*
X596074D01*
G37*
G36*
G01X618574Y245095D02*
X592674D01*
X591874Y245895D01*
Y247695D01*
X592274Y248095D01*
X618474D01*
X618874Y247695D01*
Y245395D01*
X618574Y245095D01*
G37*
G36*
G01X595374Y266066D02*
Y269095D01*
X596074Y269795D01*
X609474D01*
X609974Y269295D01*
Y265595D01*
X609674Y265295D01*
X596145D01*
X595374Y266066D01*
G37*
G36*
G01X593174Y258895D02*
X618174D01*
X618524Y258545D01*
Y256645D01*
X618274Y256395D01*
X595074D01*
X594474Y255795D01*
X593374D01*
X592674Y256495D01*
Y258395D01*
X593174Y258895D01*
G37*
G36*
G01X592974Y261095D02*
X592074Y261995D01*
Y263695D01*
X592474Y264095D01*
X592938D01*
X593071Y263995D01*
G03X593599Y263741I903J1200D01*
G03X594996Y263988I468J1427D01*
G01X595132Y264095D01*
X618174D01*
X618674Y263595D01*
Y261895D01*
X617874Y261095D01*
X592974D01*
G37*
G36*
G01X620709Y635485D02*
G03X624311I1801J59D01*
G02X624811Y635968I500J-17D01*
G01X639846D01*
X641063Y634751D01*
G02X640680Y633098I-707J-707D01*
G03X642517Y630099I583J-1705D01*
G02X643219Y630093I348J-359D01*
G01X643826Y629486D01*
Y629150D01*
G02X643611Y628739I-500J0D01*
G03Y625775I1025J-1482D01*
G01X643713Y625705D01*
X643826Y625488D01*
Y622169D01*
G02X643326Y621669I-500J0D01*
G01X636138D01*
G02X635138Y622669I0J1000D01*
G03X634738Y623921I-2001J51D01*
G01X634638Y624054D01*
Y624122D01*
X634577D01*
X634437Y624242D01*
G03X634312Y624340I-1296J-1525D01*
G01X634280Y624363D01*
X632399Y626244D01*
G03X631983Y626563I-1415J-1415D01*
G03X631909Y626604I-1007J-1730D01*
G02X631447Y627872I462J887D01*
G03X631554Y628879I-1666J686D01*
G03X629620Y630354I-1773J-320D01*
G03X628830Y627028I161J-1795D01*
G02X629196Y625729I-527J-850D01*
G03X628983Y624819I1788J-898D01*
G03X629569Y623414I2001J10D01*
G01X629589Y623393D01*
X629606Y623376D01*
G02X628899Y621669I-707J-707D01*
G01X627016D01*
X626911Y621774D01*
X621830D01*
X621744Y621688D01*
X617804D01*
X616784Y620668D01*
Y616211D01*
G02X616284Y615711I-500J0D01*
G01X616242D01*
X616200Y615718D01*
G03X615862Y615746I-334J-1973D01*
G01X613577D01*
X613453Y615826D01*
G03X610955Y612728I-1082J-1683D01*
G01X611939Y611744D01*
X612533D01*
G02X612886Y610890I0J-500D01*
G01X611078Y609081D01*
G03X613908Y606251I1415J-1415D01*
G01X614501Y606844D01*
X615862D01*
G03X616200Y606872I4J2001D01*
G01X616242Y606879D01*
X616284D01*
G02X616784Y606379I0J-500D01*
G01Y592111D01*
G02X616284Y591611I-500J0D01*
G01X616242D01*
X616200Y591618D01*
G03X616090Y591633I-325J-1975D01*
G03X615862Y591646I-228J-1988D01*
G01X613337D01*
X611654Y589963D01*
X610268Y588578D01*
Y586543D01*
G03X610271Y586437I2002J4D01*
G02X610259Y586221I-998J-53D01*
G01Y585910D01*
X610439Y585730D01*
X610476Y585656D01*
G03X610855Y585128I1794J888D01*
G01X612441Y583542D01*
X615895D01*
G03X616732Y583725I1J2001D01*
G03X616912Y583819I-835J1819D01*
G01X617060Y583906D01*
X617399Y583863D01*
X618155Y583107D01*
X618878D01*
G03X618910Y583106I63J1500D01*
G01X622030D01*
G03X622062Y583107I-31J1501D01*
G01X623325D01*
X625360Y585142D01*
X625593Y585374D01*
X632100D01*
X632102Y585375D01*
X632504D01*
X636143Y581736D01*
Y574120D01*
X635486Y573463D01*
X626865D01*
X626610Y573639D01*
X626554Y573785D01*
G03X623186I-1684J-642D01*
G01X623130Y573639D01*
X622875Y573463D01*
X602370D01*
X602220Y573613D01*
Y598676D01*
X598190Y602706D01*
Y626431D01*
X607727Y635968D01*
X614767D01*
X615020Y635797D01*
X615077Y635655D01*
G03X615384Y635178I1394J560D01*
G02X615393Y634498I-362J-345D01*
G03X617834Y634714I1337J-1208D01*
G02X617723Y635386I306J396D01*
G03X617865Y635655I-1250J832D01*
G02X618328Y635968I464J-187D01*
G01X620412D01*
X620702Y635687D01*
X620709Y635485D01*
G37*
G36*
G01X612274Y240095D02*
X611574Y240795D01*
Y243395D01*
X611974Y243795D01*
X619474D01*
X619974Y244295D01*
Y249095D01*
X619074Y249995D01*
X612374D01*
X611674Y250695D01*
Y254895D01*
X611974Y255195D01*
X619274D01*
X619674Y255595D01*
Y261479D01*
X619676Y261480D01*
Y264010D01*
X619674Y264011D01*
Y264995D01*
X619474Y265195D01*
X611674D01*
X611074Y265795D01*
Y269795D01*
X612074Y270795D01*
X623574D01*
X625174Y269195D01*
Y243595D01*
Y239514D01*
X623412Y237752D01*
X614617D01*
X612274Y240095D01*
G37*
G36*
G01X607820Y332593D02*
X610804Y335577D01*
G02X612220Y335575I707J-707D01*
G03X615642Y336986I1420J1411D01*
G01Y337348D01*
G02X616142Y337848I500J0D01*
G01X643664D01*
X645860Y340044D01*
X658019D01*
X660450Y337613D01*
Y332827D01*
X657235Y329612D01*
X643580D01*
X641640Y327672D01*
Y315387D01*
X641210Y314957D01*
X640535Y314282D01*
X639051D01*
X639006Y314238D01*
X639005D01*
X638084Y313316D01*
Y313314D01*
X638035Y313265D01*
Y305269D01*
X636878Y304112D01*
X634134D01*
X633752D01*
X633731Y304133D01*
X632853D01*
X632850Y304130D01*
X630046D01*
X628837Y302921D01*
X625878D01*
X625396Y303403D01*
Y303726D01*
X610876D01*
X607820Y306782D01*
Y332593D01*
G37*
G36*
G01X650470Y597296D02*
G03X649944Y595944I1475J-1352D01*
G01Y590983D01*
X650470Y590456D01*
Y586643D01*
X650213Y586386D01*
X649967Y586314D01*
X649841Y586342D01*
G03X649409Y586390I-436J-1954D01*
G01X645808D01*
X645745Y586406D01*
X645743D01*
G03X644246Y586209I-507J-1936D01*
G01X644130Y586143D01*
X642214D01*
X642088Y586228D01*
G03X640413Y586490I-1118J-1660D01*
G01X640410Y586489D01*
X640341Y586470D01*
X636870D01*
G03X635882Y586208I2J-2002D01*
G01X635767Y586143D01*
X633673D01*
X633559Y586208D01*
G03X632028Y586395I-989J-1740D01*
G01X631961Y586376D01*
X625178D01*
X624945Y586143D01*
X624270D01*
X622382Y584255D01*
G02X622029Y584108I-354J353D01*
G01X618911D01*
G02X618558Y584255I1J500D01*
G01X618013Y584800D01*
G02X617872Y585232I353J354D01*
G03X617808Y586133I-1977J312D01*
G01X617786Y586205D01*
Y589088D01*
X617801Y589149D01*
G03Y590141I-1939J496D01*
G01X617786Y590202D01*
Y597282D01*
X617808Y597354D01*
G03Y598532I-1913J589D01*
G01X617786Y598604D01*
Y604182D01*
X617808Y604254D01*
G03Y605432I-1913J589D01*
G01X617786Y605504D01*
Y608288D01*
X617801Y608349D01*
G03Y609341I-1939J496D01*
G01X617786Y609402D01*
Y613188D01*
X617801Y613249D01*
G03Y614241I-1939J496D01*
G01X617786Y614302D01*
Y617282D01*
X617808Y617354D01*
G03Y618532I-1913J589D01*
G01X617786Y618604D01*
Y618958D01*
X619224Y620396D01*
G02X619577Y620543I354J-353D01*
G01X648670D01*
X650470Y618743D01*
Y608787D01*
X650385Y608661D01*
G03Y606425I1660J-1118D01*
G01X650470Y606299D01*
Y603031D01*
X650378Y602901D01*
G03Y600589I1634J-1156D01*
G01X650470Y600459D01*
Y597296D01*
G37*
G36*
G01X636260Y293188D02*
Y297525D01*
X636272Y297537D01*
Y301038D01*
X639085Y303851D01*
Y312901D01*
X639420Y313236D01*
X641034D01*
X642860Y315062D01*
Y326486D01*
X643884Y327510D01*
X644212Y327838D01*
X666141D01*
X672492Y321487D01*
Y301458D01*
X670700Y299667D01*
X664351D01*
X663076Y300942D01*
Y308836D01*
X661640Y310272D01*
X657634D01*
X657147Y310760D01*
Y316725D01*
X656548Y317324D01*
X651676D01*
X650702Y316350D01*
Y314776D01*
Y312066D01*
X648830Y310194D01*
X646410D01*
X645755Y309539D01*
Y298498D01*
X646556Y297697D01*
Y293716D01*
X645237Y292397D01*
X637051D01*
X636260Y293188D01*
G37*
G36*
G01X636728Y369907D02*
X633699Y372936D01*
X633678D01*
X630261Y376353D01*
Y400268D01*
X632430Y402437D01*
X632760Y402483D01*
X632907Y402402D01*
G03X633879Y405199I726J1315D01*
G02X633043Y406185I164J986D01*
G01Y408536D01*
G02X633891Y409524I1000J0D01*
G03X634554Y409800I-229J1485D01*
G02X635228Y409726I297J-403D01*
G03X635311Y412183I1358J1184D01*
G02X634634Y412155I-354J354D01*
G03X633891Y412494I-972J-1146D01*
G02X633043Y413482I152J988D01*
G01Y419942D01*
X634969Y421868D01*
X643121D01*
X645097Y419892D01*
Y414081D01*
X641511Y410495D01*
Y406052D01*
X641559Y406004D01*
Y400439D01*
X641120Y400000D01*
Y399487D01*
G02X640620Y398987I-500J0D01*
G01X638632D01*
X638525Y399041D01*
G03X636199Y395844I-910J-1782D01*
G01X637104Y394938D01*
G02Y394231I-353J-354D01*
G01X636323Y393449D01*
G03X635737Y391977I1415J-1416D01*
G02X634657Y390952I-1000J-28D01*
G03X634175Y387386I-146J-1796D01*
G02X634989Y386423I-186J-983D01*
G03X638405Y385049I2001J41D01*
G01X638640Y385283D01*
X640663D01*
G03X641256Y385373I-1J2002D01*
G02X641757Y385249I148J-477D01*
G01X645323Y381683D01*
X646056D01*
X646311Y381428D01*
X653943D01*
X657542Y377829D01*
Y377086D01*
G03X660655Y375422I2001J0D01*
G02X661224Y375412I277J-416D01*
G03X663805Y375624I1166J1627D01*
G01X665940Y377758D01*
Y377767D01*
X666575Y378402D01*
Y380794D01*
X667161Y381380D01*
X671949D01*
G02X672862Y379974I-1J-1000D01*
G03X673958Y377888I1373J-610D01*
G02X674774Y376905I-184J-983D01*
G01Y372467D01*
G02X674274Y371967I-500J0D01*
G01X666358D01*
X664298Y369907D01*
X636728D01*
G37*
G36*
G01X640362Y427502D02*
Y424818D01*
X639678Y424134D01*
X632894D01*
X632430Y424598D01*
Y427404D01*
X633016Y427990D01*
X639874D01*
X640362Y427502D01*
G37*
G36*
G01X625070Y565943D02*
X648671D01*
X650352D01*
X651270Y565025D01*
Y563344D01*
Y553043D01*
G02X650770Y552543I-500J0D01*
G01X625070D01*
G02X624570Y553043I0J500D01*
G01Y565443D01*
G02X625070Y565943I500J0D01*
G37*
G36*
G01X675412Y557658D02*
G03X672488I-1462J-344D01*
G02X672001Y557273I-487J115D01*
G01X663002D01*
X652764Y567511D01*
G02X652658Y568801I707J707D01*
G03X652823Y569097I-1221J875D01*
G02X653877Y569702I922J-386D01*
G03X652673Y573048I264J1985D01*
G02X652307Y572888I-367J340D01*
G01X651924D01*
X648365Y576447D01*
X648332Y576586D01*
Y576587D01*
G03X646527Y574781I-1462J-344D01*
G01X646666Y574748D01*
X650166Y571247D01*
G02X650287Y570736I-354J-354D01*
G01X650235Y570579D01*
X650195Y570521D01*
G03X650305Y568689I1242J-845D01*
G01X650435Y568540D01*
X650421Y568147D01*
X650068Y567794D01*
X649286D01*
G02X648321Y569053I1J1000D01*
G03X645670Y570346I-1451J390D01*
G02X645270Y570146I-400J300D01*
G01X645252D01*
G02X644885Y570306I0J500D01*
G03X642301Y570608I-1469J-1361D01*
G01X642243Y570569D01*
X642089Y570519D01*
G02X641582Y570641I-154J476D01*
G01X637291Y574932D01*
G02X637144Y575286I353J354D01*
G01Y575800D01*
G02X638079Y576047I500J0D01*
G03X638690Y578398I1594J841D01*
G02X637144Y579236I-546J838D01*
G01Y582151D01*
X635007Y584288D01*
G02X635361Y585142I354J354D01*
G01X636030D01*
X636355Y585325D01*
G02X636871Y585468I515J-857D01*
G01X640476D01*
X640701Y585530D01*
X640708Y585533D01*
G02X641528Y585397I261J-965D01*
G01X641908Y585142D01*
X644395D01*
X644741Y585339D01*
G02X645489Y585437I494J-869D01*
G01X645614Y585404D01*
X645620D01*
X645683Y585388D01*
X649408D01*
G02X649623Y585364I-3J-1000D01*
G01X650001Y585280D01*
X650740Y585497D01*
X651472Y586228D01*
Y590870D01*
X650946Y591397D01*
Y595944D01*
G02X651208Y596619I1000J0D01*
G01X651472Y596906D01*
Y600778D01*
X651196Y601167D01*
G02Y602323I816J578D01*
G01X651472Y602712D01*
Y605042D01*
G02X651972Y605542I500J0D01*
G01X654715D01*
X657393Y608220D01*
G03X657441Y608270I-1419J1411D01*
G01X657508Y608342D01*
X657886Y608517D01*
X658121Y608457D01*
X658170Y608433D01*
G03X659247Y608261I809J1610D01*
G01X659284Y608266D01*
X662613D01*
X662913Y607966D01*
X666134D01*
G03X667457Y607466I1324J1502D01*
G01X669167D01*
X672355Y610655D01*
G03X669525Y613485I-1415J1415D01*
G01X667517Y611477D01*
X667329Y611465D01*
G03X666257Y611070I127J-1997D01*
G01X666123Y610970D01*
X662905D01*
Y610962D01*
X662613Y610670D01*
X660987D01*
X660558Y610921D01*
X660493Y611021D01*
G03X657791Y611397I-1513J-978D01*
G01X657727Y611341D01*
X657385Y611203D01*
X657108Y611289D01*
X657051Y611325D01*
G03X654563Y611050I-1072J-1690D01*
G01X653057Y609544D01*
X651972D01*
G02X651472Y610044I0J500D01*
G01Y619078D01*
X653513Y621119D01*
X659123D01*
X660301Y622297D01*
X663947D01*
X666190Y624540D01*
Y634078D01*
X670390Y638278D01*
X724460D01*
X759220Y603518D01*
Y564088D01*
G02X758720Y563588I-500J0D01*
G01X713634D01*
G02X712195Y563943I-559J829D01*
G03X710160Y561908I-1322J-713D01*
G02X710393Y560321I-474J-880D01*
G01X707345Y557273D01*
X680332D01*
G02X679839Y557686I-1J500D01*
G03X676881I-1479J-260D01*
G02X676388Y557273I-492J87D01*
G01X675724D01*
X675452Y557488D01*
X675412Y557658D01*
G37*
G36*
G01X660016Y308540D02*
X661001Y307555D01*
Y301792D01*
Y301053D01*
Y297387D01*
X660110Y296496D01*
X655619D01*
X653207Y298908D01*
X648440D01*
X647470Y299878D01*
Y308348D01*
X648049Y308927D01*
X659629D01*
X660016Y308540D01*
G37*
G36*
G01X645738Y382685D02*
X642638Y385785D01*
Y386958D01*
X642643Y386994D01*
G03Y387576I-1980J291D01*
G01X642638Y387612D01*
Y391758D01*
X642643Y391794D01*
G03Y392376I-1980J291D01*
G01X642638Y392412D01*
Y396658D01*
X642643Y396694D01*
G03Y397276I-1980J291D01*
G01X642638Y397312D01*
Y408385D01*
X646538Y412285D01*
X671038D01*
X673438Y409885D01*
Y383285D01*
X672838Y382685D01*
X645738D01*
G37*
G36*
G01X712599Y85630D02*
G02X665355I-23622J0D01*
G01Y105315D01*
G02X712599I23622J0D01*
G01Y85630D01*
G37*
G36*
G01X672120Y214208D02*
Y189776D01*
Y187640D01*
X672112Y187632D01*
X673010Y186734D01*
Y184368D01*
X670841Y182199D01*
X659680D01*
X657450Y184429D01*
Y187572D01*
Y218597D01*
X658490Y219637D01*
X670421D01*
X672120Y217938D01*
Y214208D01*
G37*
G36*
G01X655038Y353185D02*
Y363849D01*
X655138Y363982D01*
G03Y365788I-1200J903D01*
G01X655038Y365921D01*
Y366985D01*
X656538Y368485D01*
X660943D01*
G02X661903Y367204I0J-1000D01*
G03X664995Y367876I1729J-506D01*
G02X665045Y369238I757J654D01*
G01X666773Y370966D01*
X676921D01*
X677638Y370249D01*
Y353185D01*
G02X677138Y352685I-500J0D01*
G01X655538D01*
G02X655038Y353185I0J500D01*
G37*
G36*
G01X710528Y469978D02*
G02X710937Y470470I500J0D01*
G03X712137Y471853I-266J1443D01*
G02X712637Y472332I500J-21D01*
G01X717626D01*
X717888Y472139D01*
X717938Y471983D01*
G03X720351Y471299I1432J453D01*
G02X721711Y471249I653J-757D01*
G01X722828Y470132D01*
Y450332D01*
X718728Y446232D01*
X683909D01*
X683781Y446319D01*
G03X681747I-1017J-1487D01*
G01X681619Y446232D01*
X678201D01*
X678074Y446317D01*
G03X676066I-1004J-1497D01*
G01X675939Y446232D01*
X669431D01*
G02X669095Y446362I0J500D01*
G03X666805Y446470I-1211J-1335D01*
G01X666448Y446512D01*
X661628Y451332D01*
Y465096D01*
G03Y465228I-1800J66D01*
G01Y469348D01*
G02X661765Y469692I500J0D01*
G03Y472172I-1307J1240D01*
G02X661628Y472516I363J344D01*
G01Y474241D01*
G02X662682Y475240I1000J0D01*
G03X662957Y478832I98J1799D01*
G01X662882Y478840D01*
X662583Y478965D01*
X662525Y479014D01*
G03X661963Y479334I-1158J-1381D01*
G01X661962D01*
G02X661628Y479806I166J472D01*
G01Y484064D01*
G02X661917Y484518I500J1D01*
G03Y487786I-759J1634D01*
G02X661628Y488240I211J453D01*
G01Y489032D01*
X663928Y491332D01*
X674528D01*
X675128Y490732D01*
Y473132D01*
X679128Y469132D01*
Y465927D01*
G02X678768Y465447I-500J0D01*
G01X678767D01*
G03Y462629I408J-1409D01*
G01X678768D01*
G02X679128Y462149I-140J-480D01*
G01Y458532D01*
X681028Y456632D01*
X691200D01*
X694638Y453194D01*
X704090D01*
X710528Y459632D01*
Y469978D01*
G37*
G36*
G01X712599Y699803D02*
G02X665355I-23622J0D01*
G01Y719488D01*
G02X712599I23622J0D01*
G01Y699803D01*
G37*
G36*
G01X762580Y118486D02*
X721753D01*
X708054Y132185D01*
X681017D01*
X676480Y136722D01*
Y153220D01*
X682780Y159520D01*
X758047D01*
X765600Y151967D01*
Y121506D01*
X762580Y118486D01*
G37*
G36*
G01X674730Y196372D02*
X698630D01*
X699470Y195532D01*
Y186973D01*
Y185630D01*
X698446Y184606D01*
X674971D01*
X674210Y185367D01*
Y195852D01*
X674730Y196372D01*
G37*
G36*
G01X718427Y198408D02*
G03X704723I-6852J-3053D01*
G02X704266Y198112I-457J204D01*
G01X677101D01*
X676160Y199053D01*
Y238466D01*
X678351Y240657D01*
X726050D01*
X727370Y239337D01*
Y225918D01*
G03Y218804I6605J-3557D01*
G01Y201302D01*
X724180Y198112D01*
X718884D01*
G02X718427Y198408I0J500D01*
G37*
G36*
G01X694394Y455061D02*
G02X694041Y455208I1J500D01*
G01X691615Y457634D01*
X691286D01*
X690587Y458332D01*
X681728D01*
X680828Y459232D01*
Y461931D01*
G02X682348Y462785I1000J0D01*
G03Y465291I764J1253D01*
G02X680828Y466145I-520J854D01*
G01Y469632D01*
X677528Y472932D01*
Y487632D01*
X679584Y489688D01*
X679721Y489721D01*
G03X681051Y491051I-422J1752D01*
G01X681084Y491188D01*
X686128Y496232D01*
G02X687614Y496152I707J-707D01*
G03X690688Y497957I1403J1131D01*
G03X690373Y499817I-1671J674D01*
G02X690396Y500500I377J329D01*
G01X690690Y500794D01*
X692303D01*
X692395Y500756D01*
G03X692494Y500719I563J1355D01*
G02X693105Y499477I-342J-940D01*
G03X695183Y500698I1718J-545D01*
G02X694397Y501841I200J980D01*
G03X692848Y503575I-1442J271D01*
G02X691803Y504574I-45J999D01*
G01Y504908D01*
G02X692303Y505408I500J0D01*
G01X692330D01*
X692357Y505405D01*
G03X692523Y508400I163J1493D01*
G02X691527Y509464I2J1000D01*
G03X688174Y510490I-1798J116D01*
G02X686622Y510319I-844J536D01*
G01X676700Y520241D01*
Y523863D01*
X676732Y523948D01*
G03Y525214I-1688J633D01*
G01X676700Y525299D01*
Y527120D01*
X677182Y527611D01*
X677359Y527631D01*
G03Y531213I-199J1791D01*
G01X677182Y531233D01*
X676700Y531724D01*
Y538327D01*
G02X677946Y539296I1000J0D01*
G03X679100Y542033I370J1456D01*
G02X678915Y543593I522J853D01*
G01X688154Y552832D01*
X699524D01*
X699892Y552666D01*
X699957Y552600D01*
G03X702089I1066J1058D01*
G01X702154Y552666D01*
X702522Y552832D01*
X713400D01*
X750751Y515481D01*
Y478803D01*
X745700Y473752D01*
X720100D01*
X720000Y473798D01*
G03X718740I-630J-1362D01*
G01X718640Y473752D01*
X712952D01*
G02X712067Y475219I0J1000D01*
G03X712181Y476482I-1299J754D01*
G03X711694Y477155I-1413J-510D01*
G02X711638Y478683I616J788D01*
G03X710796Y481248I-967J1103D01*
G03X709753Y478641I-126J-1462D01*
G02X709783Y477106I-625J-780D01*
G03X709629Y476952I982J-1136D01*
G03X709469Y475219I1139J-979D01*
G02X708584Y473752I-885J-467D01*
G01X708396D01*
G02X707206Y473302I-868J497D01*
G03Y470524I-472J-1389D01*
G02X708528Y469577I322J-947D01*
G01Y460332D01*
X706528Y458332D01*
X706510D01*
X704948Y456770D01*
G02X703637Y456680I-707J707D01*
G03X701229Y455541I-907J-1197D01*
G01X701221Y455340D01*
X700931Y455061D01*
X694394D01*
G37*
G36*
G01X741630Y114376D02*
Y102545D01*
X739897Y100812D01*
X725254D01*
X723830Y102236D01*
Y115735D01*
X725150Y117055D01*
X740106D01*
X741630Y115531D01*
Y114376D01*
G37*
G36*
G01X744130Y117461D02*
X751311D01*
X751810D01*
X752840Y116431D01*
Y115932D01*
Y99245D01*
X751840Y98245D01*
X744034D01*
X743270Y99009D01*
Y116601D01*
X744130Y117461D01*
G37*
G36*
G01X763630Y101654D02*
X755528D01*
X754990Y102191D01*
Y108158D01*
X755582Y108750D01*
X763535D01*
X764542Y107743D01*
Y102566D01*
X763630Y101654D01*
G37*
G36*
G01X761020Y557643D02*
Y561676D01*
X761400Y562056D01*
Y573330D01*
X762440Y574370D01*
Y588372D01*
Y594439D01*
X763390Y595389D01*
X775040D01*
X783210D01*
X783650Y594949D01*
Y549205D01*
X782529Y548084D01*
X761890D01*
X761020Y548954D01*
Y557643D01*
G37*
%LPC*%
G75*
G36*
G01X14475Y611584D02*
G03X14198Y612756I-916J402D01*
G02X16872Y613179I1151J1386D01*
G03X16971Y611980I846J-534D01*
G02X14475Y611584I-1121J-1000D01*
G37*
G36*
G01X14844Y591249D02*
G02X14283Y593227I-1334J690D01*
G03X15686Y593624I515J857D01*
G02X16247Y591646I1334J-690D01*
G03X14844Y591249I-515J-857D01*
G37*
G36*
G01X21215Y547954D02*
G02X19245Y547371I-565J-1711D01*
G03X18859Y548916I-780J626D01*
G02X20698Y549461I591J1381D01*
G03X21215Y547954I830J-557D01*
G37*
G36*
G01X80213Y231737D02*
G03X79972Y230561I663J-749D01*
G02X77618Y231044I-1358J-641D01*
G03X77859Y232220I-663J749D01*
G02X80213Y231737I1358J641D01*
G37*
G36*
G01X82423Y259007D02*
G02X79939Y259038I-1258J-1290D01*
G03X80039Y260397I-680J733D01*
G02X79917Y260572I1168J944D01*
G03X78999Y260426I-430J-255D01*
G02X78497Y262104I-1760J388D01*
G03X80000Y262227I698J716D01*
G02X82358Y260368I1210J-890D01*
G03X82423Y259007I764J-646D01*
G37*
G36*
G01X50306Y625309D02*
G02X48046Y626686I-1766J-356D01*
G03X48771Y627706I-273J962D01*
G02X50880Y626421I1499J87D01*
G03X50306Y625309I407J-914D01*
G37*
G36*
G01X107523Y99696D02*
G03X108251Y98188I1927J0D01*
G02X88601I-9825J-12361D01*
G03X89329Y99696I-1199J1508D01*
G01Y105512D01*
G02X107523I9097J0D01*
G01Y99696D01*
G37*
G36*
G01Y713869D02*
G03X108251Y712361I1927J0D01*
G02X88601I-9825J-12361D01*
G03X89329Y713869I-1199J1508D01*
G01Y719685D01*
G02X107523I9097J0D01*
G01Y713869D01*
G37*
G36*
G01X142019Y424135D02*
G02X140444Y422502I220J-1789D01*
G03X139427Y423588I-996J86D01*
G02X140897Y425112I-32J1502D01*
G03X142019Y424135I1000J15D01*
G37*
G36*
G01X149208Y508113D02*
Y508180D01*
X149268D01*
X149284Y508194D01*
G02X150709Y508786I1424J-1416D01*
G01X152746D01*
X152887Y508927D01*
G02X155727Y506087I1420J-1420D01*
G01X154410Y504770D01*
X150709D01*
G02X149284Y505362I-1J2008D01*
G01X149268Y505376D01*
X149208D01*
Y505443D01*
G02Y508113I1501J1335D01*
G37*
G36*
G01X187601Y552518D02*
X187384D01*
Y552744D01*
X187301Y552869D01*
G02X187045Y554395I1585J1050D01*
G01X187060Y554456D01*
Y555331D01*
G03X186940Y555657I-500J1D01*
G02X189728Y558240I1443J1238D01*
G01X190864Y557104D01*
Y553208D01*
X190388Y552732D01*
Y552518D01*
X190171D01*
G02X187601I-1285J1402D01*
G37*
G36*
G01X201438Y550104D02*
G03X200312Y550316I-715J-700D01*
G02X200757Y552679I-603J1337D01*
G03X201883Y552467I715J700D01*
G02X203340Y552323I603J-1337D01*
G03X203990Y552382I291J407D01*
G02X206623Y552338I1296J-1252D01*
G03X207277Y552262I370J336D01*
G02X207213Y549892I832J-1208D01*
G03X206555Y549851I-306J-396D01*
G02X203990Y549878I-1269J1279D01*
G03X203340Y549937I-359J-348D01*
G02X201438Y550104I-854J1193D01*
G37*
G36*
G01X160975Y551434D02*
G03X161069Y552617I-755J655D01*
G02X163571Y552634I1246J774D01*
G03X163681Y551452I857J-516D01*
G02X160975Y551434I-1345J-1199D01*
G37*
G36*
G01X217446Y545200D02*
G03X218101Y545037I417J277D01*
G02X217813Y542841I650J-1202D01*
G03X217139Y542851I-342J-364D01*
G02X217446Y545200I-1193J1350D01*
G37*
G36*
G01X161142Y542603D02*
G03X159955Y542705I-662J-749D01*
G02Y545202I-770J1248D01*
G03X161141Y545304I524J851D01*
G02X161142Y542603I1194J-1350D01*
G37*
G36*
G01X187452Y526152D02*
X187443Y526346D01*
X187438Y526350D01*
Y529935D01*
X187386Y530040D01*
G02X189150Y531973I1254J627D01*
G03X189794Y532246I182J466D01*
G02X191061Y529795I1663J-693D01*
G03X189842Y528819I-219J-975D01*
G01Y528263D01*
G03X190104Y527823I500J0D01*
G01X190105D01*
G02X187452Y526152I-853J-1587D01*
G37*
G36*
G01X161634Y520732D02*
G03X160428Y520594I-513J-858D01*
G02X160418Y523202I-1249J1299D01*
G03X161625Y523074I687J726D01*
G02X161634Y520732I710J-1168D01*
G37*
G36*
G01X140594Y515772D02*
G03X140609Y514602I818J-575D01*
G02X138173Y514571I-1207J-895D01*
G03X138158Y515741I-818J575D01*
G02X140594Y515772I1207J895D01*
G37*
G36*
G01X162102Y514243D02*
G02X160549Y512699I233J-1787D01*
G03X159429Y513825I-991J135D01*
G02X160982Y515369I-233J1787D01*
G03X162102Y514243I991J-135D01*
G37*
G36*
G01X154938Y521567D02*
G02X152728Y521805I-1208J-833D01*
G03X152788Y523204I-683J730D01*
G02X152324Y524411I1338J1207D01*
G01Y524412D01*
G03X151824Y524912I-500J0D01*
G01X142733D01*
X138804Y528841D01*
Y555065D01*
X141875Y558136D01*
X147456D01*
X147814Y557778D01*
G03X148521I353J354D01*
G01X148797Y558054D01*
X152924D01*
X154210Y556768D01*
Y554826D01*
G03X154710Y554326I500J0D01*
G01X156239D01*
X156942Y553623D01*
Y550774D01*
X155950Y549782D01*
X154710D01*
G03X154210Y549282I0J-500D01*
G01Y548064D01*
G03X154710Y547564I500J0D01*
G01X155824D01*
X156708Y546679D01*
Y541715D01*
G02X155207Y540214I-1501J0D01*
G01X154555D01*
X154296Y539955D01*
Y538818D01*
X154704Y538410D01*
X155724D01*
X155959Y538175D01*
G03X157565Y538444I707J707D01*
G02X158197Y536147I1620J-790D01*
G03X157717Y536185I-275J-418D01*
G01X157316Y536005D01*
X157156Y535758D01*
Y535641D01*
X156851Y535335D01*
G03X156793Y534699I354J-353D01*
G01Y534698D01*
G02X157060Y533845I-1234J-855D01*
G01Y533163D01*
G02X156319Y531609I-2001J1D01*
G03X156165Y531047I315J-388D01*
G02Y529797I-1690J-625D01*
G03X156319Y529235I469J-174D01*
G02X156347Y529212I-1256J-1558D01*
G03X157773Y529352I645J765D01*
G02X157827Y529417I1412J-1118D01*
G03X157931Y530595I-751J660D01*
G02X160437Y530591I1254J761D01*
G03X160537Y529412I853J-521D01*
G02X158117Y526772I-1358J-1185D01*
G03X157629Y526829I-295J-404D01*
G01X157367Y526720D01*
G03X157060Y526259I193J-461D01*
G01Y525937D01*
X156067Y524945D01*
G03X155922Y524552I353J-354D01*
G02X155178Y522948I-1796J-141D01*
G03X154938Y521567I583J-813D01*
G37*
G36*
G01X186157Y535228D02*
G02X183281Y534893I-1314J-1233D01*
G03X183070Y536146I-867J498D01*
G02X182974Y536236I1320J1504D01*
G03X181831Y536425I-704J-710D01*
G02X180503Y536498I-598J1229D01*
G03X179283Y536380I-534J-846D01*
G02X176844Y536416I-1201J1274D01*
G01X175202Y538057D01*
X175063Y538139D01*
G02X175016Y538168I896J1505D01*
G01X174894Y538246D01*
X174652D01*
Y538463D01*
X174553Y538596D01*
G02X174225Y539927I1401J1051D01*
G03X173604Y541018I-987J160D01*
G02X175472Y542324I501J1272D01*
G03X176283Y541367I1000J25D01*
G02X176845Y541155I-328J-1720D01*
G01X177025Y541048D01*
X177256D01*
Y540957D01*
X179320Y538892D01*
G02X179503Y538678I-1235J-1241D01*
G03X180263Y538618I405J293D01*
G02X182063Y538739I969J-964D01*
G03X182770Y538840I304J397D01*
G02X182969Y539071I1611J-1187D01*
G01X183632Y539735D01*
Y540853D01*
G02X184952Y542735I2002J0D01*
G03X185407Y544281I-341J940D01*
G02X187540Y543711I1434J1091D01*
G03X187163Y542144I387J-922D01*
G02X187636Y540853I-1529J-1292D01*
G01Y538077D01*
X186179Y536620D01*
G03X186157Y535228I707J-707D01*
G37*
G36*
G01X212325Y538531D02*
G02X210611Y537229I17J-1802D01*
G03X209746Y538502I-961J277D01*
G02X208929Y538850I139J1460D01*
G03X208274Y538848I-326J-379D01*
G02X206368Y538828I-965J1105D01*
G03X205670Y538772I-320J-384D01*
G02X203058Y538656I-1361J1181D01*
G03X202405Y538692I-347J-360D01*
G02X201986Y538466I-897J1161D01*
G03X201322Y537374I325J-946D01*
G02X199219Y538885I-1783J-262D01*
G03X200042Y539863I-177J984D01*
G02X202320Y541075I1467J-10D01*
G03X202969Y541158I277J417D01*
G02X205670Y541134I1340J-1205D01*
G03X206368Y541078I378J328D01*
G02X208266Y541065I941J-1125D01*
G03X208921Y541067I326J379D01*
G02X211330Y539706I965J-1105D01*
G03X212325Y538531I985J-175D01*
G37*
G36*
G01X179091Y551208D02*
G02X176920Y550959I-992J-941D01*
G03X176781Y552157I-862J507D01*
G02X179258Y554768I1302J1245D01*
G03X180438Y554677I652J758D01*
G02X182194Y554556I794J-1275D01*
G03X183463Y554546I641J768D01*
G02X183466Y552263I923J-1140D01*
G03X182197Y552251I-627J-779D01*
G02X180438Y552127I-965J1151D01*
G03X179258Y552036I-528J-849D01*
G02X179156Y551954I-1179J1363D01*
G03X179091Y551208I297J-402D01*
G37*
G36*
G01X170296Y560345D02*
G02X168144Y560005I-852J-1588D01*
G03X168170Y561361I-722J692D01*
G02X170128Y563607I1123J997D01*
G03X171471Y563821I556J831D01*
G02X171713Y561345I1418J-1111D01*
G03X170354Y561295I-653J-758D01*
G02X170223Y561178I-1064J1060D01*
G03X170296Y560345I309J-393D01*
G37*
G36*
G01X183832Y503796D02*
X183724Y503852D01*
X183232D01*
Y504293D01*
X183155Y504415D01*
G02X182882Y505353I1479J939D01*
G01Y509065D01*
X183720Y509903D01*
X183758Y510255D01*
X183662Y510403D01*
G02X183382Y511353I1472J950D01*
G01Y511512D01*
G03X182882Y512012I-500J0D01*
G01X182747D01*
X182515Y511877D01*
X182448Y511760D01*
G02X180506Y511255I-1217J695D01*
G03X179309Y511133I-518J-856D01*
G02X179310Y513778I-1224J1323D01*
G03X180399Y513599I680J733D01*
G03X180472Y514471I-205J456D01*
G02X182265Y514712I760J1136D01*
G03X182276Y513390I756J-655D01*
G02X182448Y513150I-1047J-932D01*
G03X182882Y512898I434J248D01*
G01X183090D01*
X183382Y513190D01*
Y513428D01*
X185229Y515274D01*
G02X185439Y515454I1241J-1235D01*
G03X185420Y517086I-587J809D01*
G02X185179Y517288I1000J1438D01*
G01X184165Y518302D01*
X183784D01*
G02X182846Y518574I-1J1751D01*
G01X182724Y518652D01*
X182036D01*
Y518552D01*
X181544D01*
X181436Y518496D01*
G02X180634Y518302I-801J1557D01*
G01X180108D01*
X179323Y517517D01*
G02X176847Y519993I-1238J1238D01*
G01X177531Y520678D01*
G03X176824Y522386I-707J708D01*
G01X175728D01*
G03X175374Y522239I0J-500D01*
G01X175053Y521917D01*
X175025Y521873D01*
G02X174263Y521216I-1511J982D01*
G03X173704Y520085I416J-909D01*
G02X171817Y518533I-1333J-302D01*
G03X171181Y518324I-202J-457D01*
G02X170701Y520654I-1566J892D01*
G03X171369Y520713I301J399D01*
G02X171842Y521043I1001J-931D01*
G03X172053Y521798I-194J461D01*
G02X172001Y521873I1454J1064D01*
G01X171973Y521917D01*
X169854Y524036D01*
Y524041D01*
G03X169354Y524541I-500J0D01*
G01X169252D01*
X169157Y524500D01*
G02X168965Y524434I-539J1256D01*
G03X168602Y523849I127J-484D01*
G02X166769Y525287I-1765J-363D01*
G03X167250Y525778I-19J499D01*
G02X167931Y526939I1367J-22D01*
G03X168165Y528481I-501J865D01*
G02X167689Y529663I1326J1221D01*
G03X166550Y530632I-1000J-21D01*
G02X165545Y534054I-253J1784D01*
G03X165930Y535560I-417J909D01*
G02X166007Y537286I1097J816D01*
G03Y538616I-747J665D01*
G02X166270Y540664I1020J910D01*
G03X166618Y541928I-554J833D01*
G02X168935Y541042I1625J778D01*
G03X168350Y539868I383J-924D01*
G02X168047Y538616I-1323J-342D01*
G03Y537286I747J-665D01*
G02X167760Y535222I-1020J-910D01*
G03X167583Y533678I537J-844D01*
G02X168099Y532455I-1286J-1263D01*
G03X169238Y531486I1000J21D01*
G02X171293Y529743I253J-1784D01*
G03X171751Y529256I500J11D01*
G02X172432Y529056I-143J-1746D01*
G03X173043Y529166I236J441D01*
G02X173283Y529393I1353J-1190D01*
G03X173534Y530677I-617J787D01*
G02X175499Y532479I1186J679D01*
G03X176791Y532610I569J822D01*
G02X179874Y531086I1303J-1245D01*
G03X180997Y529941I988J-154D01*
G02X182470Y529443I234J-1736D01*
G01X183298Y528616D01*
Y524137D01*
G02X182947Y523086I-1752J1D01*
G01X182848Y522953D01*
Y522262D01*
G03X183348Y521762I500J0D01*
G01X183396D01*
X183444Y521771D01*
G02X183784Y521804I338J-1718D01*
G01X185615D01*
X187655Y519764D01*
G02X187445Y517108I-1238J-1238D01*
G03X187464Y515476I587J-809D01*
G02X187705Y512798I-997J-1440D01*
G01X186886Y511978D01*
Y511353D01*
G02X186535Y510302I-1752J1D01*
G01X186436Y510169D01*
Y509512D01*
X186488Y509407D01*
G02X186449Y507772I-1568J-781D01*
G01X186386Y507658D01*
Y505353D01*
G02X186113Y504415I-1752J1D01*
G01X186036Y504293D01*
Y503852D01*
X185544D01*
X185436Y503796D01*
G02X183832I-802J1557D01*
G37*
G36*
G01X170346Y698445D02*
G02X168267Y698519I-1078J-1046D01*
G03X168318Y699960I-667J745D01*
G02X170397Y699886I1078J1046D01*
G03X170346Y698445I667J-745D01*
G37*
G36*
G01X179180Y699177D02*
G02X177376I-902J-1201D01*
G03Y700775I-601J799D01*
G02Y703177I902J1201D01*
G03Y704775I-601J799D01*
G02Y707177I902J1201D01*
G03Y708775I-601J799D01*
G02X179180I902J1201D01*
G03Y707177I601J-799D01*
G02Y704775I-902J-1201D01*
G03Y703177I601J-799D01*
G02Y700775I-902J-1201D01*
G03Y699177I601J-799D01*
G37*
G36*
G01X186671Y293580D02*
G03X186311Y293070I139J-480D01*
G02X184395Y294422I-1499J-91D01*
G03X184755Y294932I-139J480D01*
G02X186671Y293580I1499J91D01*
G37*
G36*
G01X211471Y261343D02*
G03X211522Y260659I389J-315D01*
G02X209088I-1217J-1329D01*
G03X209139Y261343I-338J369D01*
G02X211471I1166J946D01*
G37*
G36*
G01X206726Y242543D02*
G03X206704Y241302I773J-634D01*
G02X204056Y241539I-1432J-1093D01*
G03X204254Y242765I-675J738D01*
G02X206726Y242543I1312J732D01*
G37*
G36*
G01X272037Y236736D02*
G02X270622Y238802I-1777J301D01*
G03X271197Y239132I101J490D01*
G02X271246Y239259I1424J-476D01*
G03X270955Y239932I-458J201D01*
G02X270058Y240803I503J1415D01*
G01X270020Y240902D01*
X269944Y240977D01*
G03X269237Y240976I-353J-354D01*
G01X269174Y240912D01*
X264116D01*
X261201Y243827D01*
G03X260848Y243974I-354J-353D01*
G01X258263D01*
G02X256948Y244494I0J1923D01*
G01X256762D01*
Y244685D01*
X256675Y244813D01*
G02Y246979I1588J1083D01*
G01X256762Y247107D01*
Y247298D01*
X256948D01*
G02X258263Y247818I1315J-1403D01*
G01X261365D01*
X261446Y247846D01*
G02X262818I686J-1957D01*
G01X262899Y247818D01*
X262921D01*
X262937Y247803D01*
X263010Y247769D01*
G02X263861Y247035I-879J-1879D01*
G01X264656Y246240D01*
G03X265591Y246559I187J982D01*
G02X267194Y247395I1527J-972D01*
G03X267709Y247975I21J500D01*
G02X267691Y248144I1482J243D01*
G01X267685Y248275D01*
X267546Y248497D01*
X267430Y248560D01*
G03X266941Y248553I-238J-440D01*
G02X267614Y250320I-754J1299D01*
G03X268815Y249663I950J311D01*
G02X269624Y246770I377J-1454D01*
G03X268911Y245833I287J-958D01*
G02X268919Y245765I-1793J-245D01*
G01Y245764D01*
G03X269417Y245314I498J50D01*
G01X269620D01*
G02X270270Y245210I1J-2075D01*
G03X270880Y245474I157J475D01*
G02X273030Y243563I1362J-632D01*
G03X272717Y242166I525J-851D01*
G02X272924Y241020I-1259J-819D01*
G03X273388Y239944I976J-217D01*
G02X272552Y237152I-768J-1291D01*
G03X272037Y236736I-22J-499D01*
G37*
G36*
G01X255998Y228032D02*
G02X253999Y227482I-711J-1323D01*
G03X253527Y228919I-858J514D01*
G02X253068Y231967I694J1663D01*
G03X253129Y233449I-640J769D01*
G02X255255Y233471I1052J1072D01*
G03X255346Y231990I715J-699D01*
G02X255668Y229509I-1125J-1407D01*
G03X255998Y228032I803J-596D01*
G37*
G36*
G01X259399Y237321D02*
G02X257673Y238400I-1449J-397D01*
G03X258423Y239737I-185J983D01*
G02X260272Y238581I1685J639D01*
G03X259399Y237321I91J-996D01*
G37*
G36*
G01X215819Y396657D02*
G02X213452Y397068I-1413J-1118D01*
G03X213707Y398536I-530J848D01*
G02X216074Y398125I1413J1118D01*
G03X215819Y396657I530J-848D01*
G37*
G36*
G01X262747Y97255D02*
G02X262876Y97603I1462J-344D01*
G03X262665Y98798I-889J459D01*
G02X263474Y101389I1018J1104D01*
G03X264332Y102454I-139J990D01*
G02X267305Y102284I1498J112D01*
G01X267296Y102238D01*
Y102190D01*
G03X267796Y101690I500J0D01*
G01X268184D01*
X268325Y101810D01*
G02X270925I1300J-1521D01*
G01X271066Y101690D01*
X271126D01*
Y101623D01*
X271226Y101490D01*
G02X271626Y100289I-1601J-1200D01*
G01Y99754D01*
G03X273165Y98911I1000J0D01*
G02X275469Y97779I808J-1266D01*
G03X276465Y96868I996J89D01*
G01X278749D01*
G03X279728Y98069I-1J1000D01*
G02X279702Y98483I1472J300D01*
G03X278727Y99559I-997J76D01*
G02X277873Y102273I33J1502D01*
G03X277973Y103803I-591J807D01*
G02X279897Y103677I1037J1086D01*
G03X279797Y102147I591J-807D01*
G02X280258Y100947I-1037J-1087D01*
G03X281233Y99871I997J-76D01*
G02X282672Y98069I-33J-1502D01*
G03X283651Y96868I980J-201D01*
G01X285733D01*
X285861Y96956D01*
G02X287559I849J-1239D01*
G01X287687Y96868D01*
X288289D01*
X288490Y96963D01*
X288562Y97050D01*
G02X290878I1158J-956D01*
G01X290950Y96963D01*
X291151Y96868D01*
X292588D01*
X293788Y98068D01*
G03X293768Y99502I-707J707D01*
G02X293315Y100368I1032J1091D01*
G03X292184Y101207I-988J-151D01*
G02X293687Y102603I-257J1784D01*
G03X294331Y102020I488J-108D01*
G02X294395Y102039I459J-1430D01*
G03X295125Y102998I-270J963D01*
G02X297149Y101203I1802J-7D01*
G03X296284Y100363I123J-993D01*
G02X296245Y100182I-1485J225D01*
G03X297207Y98908I962J-274D01*
G01X299128D01*
X301168Y96868D01*
X301502D01*
G03X302002Y97368I0J500D01*
G01Y97507D01*
X301931Y97625D01*
G02X304688Y98080I1289J772D01*
G03X305666Y96868I978J-212D01*
G01X308663D01*
G03X309443Y98494I0J1000D01*
G02X312525Y98955I1407J1126D01*
G03X312962Y97715I929J-370D01*
G02X313540Y97128I-740J-1307D01*
G01X313606Y97008D01*
X313842Y96868D01*
X316546D01*
G03X316902Y97017I0J500D01*
G02X317953Y97463I1068J-1056D01*
G03X318940Y98511I-12J1000D01*
G02X322480Y98129I1800J87D01*
G03X323445Y96868I965J-261D01*
G01X323865D01*
G03X324317Y97153I0J500D01*
G01X324445Y97422D01*
G03X324423Y97893I-452J215D01*
G02X325954Y100619I1547J924D01*
G03X326449Y101103I-5J500D01*
G02X326554Y101612I1501J-44D01*
G03X326328Y102235I-465J184D01*
G02X328740Y102899I862J1583D01*
G03X328865Y102248I430J-255D01*
G02X328180Y99573I-915J-1191D01*
G03X327760Y99022I77J-494D01*
G02X327666Y98207I-1790J-206D01*
G03X328607Y96868I941J-339D01*
G01X334264D01*
G03X335094Y98427I0J1000D01*
G02X334846Y99418I1246J838D01*
G03X334161Y100471I-995J102D01*
G02X336469Y101752I559J1713D01*
G03X337001Y100614I971J-239D01*
G02X337586Y98427I-661J-1349D01*
G03X338416Y96868I830J-559D01*
G01X344078D01*
X344177Y96770D01*
G03X344605Y96629I354J353D01*
G02X346655Y94579I268J-1782D01*
G03X346796Y94151I494J-74D01*
G01X349514Y91432D01*
Y90759D01*
G03X350388Y89767I1000J0D01*
G02X350060Y86781I-190J-1490D01*
G03X349514Y86283I-46J-498D01*
G01Y86252D01*
X345528Y82266D01*
X247908D01*
X246392Y83782D01*
Y90203D01*
G03X245937Y90701I-500J0D01*
G02X245896Y93689I135J1496D01*
G03X246771Y94809I-117J993D01*
G02X249208Y96719I1787J229D01*
G01X249346Y96665D01*
X249636Y96727D01*
X249778Y96868D01*
X253753D01*
G03X254602Y98396I0J1000D01*
G02X256049Y101147I1531J951D01*
G01X256243Y101156D01*
X257046Y101960D01*
Y108595D01*
G03X256546Y109095I-500J0D01*
G01X256274D01*
X256148Y109012D01*
G02X255098Y108696I-1050J1585D01*
G01X245255D01*
G03X244419Y107146I0J-1000D01*
G02X244524Y105351I-1506J-989D01*
G03X244744Y104165I895J-447D01*
G02X242302Y103522I-1014J-1108D01*
G03X241908Y104661I-951J309D01*
G02X241121Y105969I1005J1496D01*
G03X240205Y106861I-994J-105D01*
G02X239010Y110102I150J1896D01*
G01X241407Y112498D01*
X246770D01*
G03X247728Y113787I0J1000D01*
G02X251178I1725J520D01*
G03X252136Y112498I958J-289D01*
G01X255098D01*
G02X256148Y112182I0J-1901D01*
G01X256274Y112099D01*
X259650D01*
Y109095D01*
X259450Y108894D01*
Y100964D01*
X257942Y99457D01*
X257933Y99263D01*
G02X257664Y98396I-1800J83D01*
G03X258513Y96868I849J-528D01*
G01X262260D01*
G03X262747Y97255I0J500D01*
G37*
G36*
G01X398898Y91035D02*
G03X399842Y90280I970J245D01*
G02X398348Y88410I-38J-1502D01*
G03X397404Y89165I-970J-245D01*
G02X398898Y91035I38J1502D01*
G37*
G36*
G01X435224Y124034D02*
G03Y123330I355J-352D01*
G02X433092I-1066J-1058D01*
G03Y124034I-355J352D01*
G02X435224I1066J1058D01*
G37*
G36*
G01X453614Y124212D02*
G03X453898Y123631I485J-123D01*
G02X452360Y121081I-600J-1377D01*
G03X451736I-312J-391D01*
G02X450349Y123687I-938J1173D01*
G03X450689Y124269I-149J477D01*
G02X453614Y124212I1469J313D01*
G37*
G36*
G01X295126Y119408D02*
X295059D01*
X294926Y119309D01*
G02X292524I-1201J1601D01*
G01X292391Y119408D01*
X292324D01*
Y119469D01*
X292204Y119610D01*
G02X291724Y120910I1520J1300D01*
G01Y131038D01*
X292458Y131772D01*
G02X295756Y129679I1415J-1415D01*
G01X295726Y129597D01*
Y120910D01*
G02X295246Y119610I-2000J0D01*
G01X295126Y119469D01*
Y119408D01*
G37*
G36*
G01X370315Y115816D02*
X367297Y118833D01*
X367151Y118864D01*
G02X366010Y122089I409J1959D01*
G03X365998Y122736I-387J316D01*
G02X369009Y123224I1352J1191D01*
G01X368950Y123083D01*
X369008Y122784D01*
X371973Y119818D01*
X373243D01*
X375948Y122523D01*
G02X376254Y122774I1416J-1414D01*
G03X376586Y124069I-554J832D01*
G02X379983Y124988I1597J835D01*
G01X379992Y124794D01*
X380852Y123935D01*
Y118459D01*
X379910Y117518D01*
Y116315D01*
X376691D01*
X376558Y116215D01*
G02X375358Y115816I-1199J1602D01*
G01X370315D01*
G37*
G36*
G01X274253Y112631D02*
G02X272953Y112150I-1302J1520D01*
G01X268953D01*
G02X268393Y112231I4J2001D01*
G01X268324Y112250D01*
X262115D01*
X259439Y114926D01*
X257294D01*
X256416Y115805D01*
Y119207D01*
X255598Y120024D01*
Y126063D01*
X256687Y127152D01*
X261275D01*
X262686Y125740D01*
Y125378D01*
G03X263186Y124878I500J1D01*
G01X279409D01*
X280302Y123986D01*
Y116917D01*
X278750Y115366D01*
X275947D01*
G03X274949Y114294I0J-1000D01*
G02X274554Y112951I-1996J-142D01*
G01X274454Y112818D01*
Y112750D01*
X274394D01*
X274253Y112631D01*
G37*
G36*
G01X287595Y108110D02*
G02Y104108I0J-2001D01*
G01X284199D01*
G02X282899Y104588I0J2000D01*
G01X282758Y104708D01*
X282698D01*
Y104775D01*
X282598Y104908D01*
G02Y107310I1601J1201D01*
G01X282698Y107443D01*
Y107510D01*
X282758D01*
X282899Y107630D01*
G02X284199Y108110I1300J-1520D01*
G01X287595D01*
G37*
G36*
G01X360868Y99126D02*
G03X360469Y100258I-954J300D01*
G02X363088Y100963I1001J1499D01*
G03X363312Y99784I898J-440D01*
G02X360868Y99126I-1012J-1110D01*
G37*
G36*
G01X399695Y129271D02*
G02X397254Y130052I-1607J-816D01*
G03X397734Y131272I-463J887D01*
G02X400012Y130543I1416J501D01*
G03X399695Y129271I574J-819D01*
G37*
G36*
G01X393856Y130085D02*
G02X391440Y129184I-768J-1630D01*
G03X391067Y130429I-915J404D01*
G02X393322Y131271I813J1263D01*
G03X393856Y130085I960J-281D01*
G37*
G36*
G01X352772Y125546D02*
G02X350278Y125523I-1239J-849D01*
G03X350178Y126750I-835J550D01*
G02X350301Y129315I1325J1222D01*
G03X350351Y130008I-333J372D01*
G02X350320Y131898I1152J964D01*
G03X350242Y133219I-788J616D01*
G02X352654Y133277I1179J1171D01*
G03X352640Y131954I743J-669D01*
G02X352655Y130008I-1137J-982D01*
G03X352705Y129315I383J-321D01*
G02X352850Y126775I-1202J-1343D01*
G03X352772Y125546I747J-664D01*
G37*
G36*
G01X445248Y123574D02*
G02X443797Y121040I-420J-1442D01*
G03X442474Y121084I-686J-727D01*
G02X441177Y123705I-956J1158D01*
G03X441948Y124628I-228J974D01*
G02X444903Y124179I1500J-76D01*
G03X445248Y123574I484J-125D01*
G37*
G36*
G01X459932Y123073D02*
G02X457704I-1114J-1008D01*
G03Y124414I-741J670D01*
G02X459932I1114J1008D01*
G03Y123073I741J-670D01*
G37*
G36*
G01X228058Y122676D02*
G02X226141Y123396I-1345J-669D01*
G03X226609Y124849I-381J925D01*
G02X228662Y124078I1529J953D01*
G03X228058Y122676I291J-957D01*
G37*
G36*
G01X234253Y122876D02*
G02X232212Y122810I-985J-1134D01*
G03X232091Y124336I-702J712D01*
G02X234277Y124406I1047J1466D01*
G03X234253Y122876I632J-775D01*
G37*
G36*
G01X232614Y107058D02*
G02X230446Y106065I-704J-1327D01*
G03X229939Y107170I-975J221D01*
G02X232107Y108163I704J1327D01*
G03X232614Y107058I975J-221D01*
G37*
G36*
G01X400636Y105757D02*
G02X398614Y105779I-1023J-1100D01*
G03X398630Y107257I-665J746D01*
G02X400652Y107235I1023J1100D01*
G03X400636Y105757I665J-746D01*
G37*
G36*
G01X355716Y105479D02*
G02X353599Y103520I-773J-1288D01*
G03X352340Y104005I-895J-446D01*
G02X351889Y106903I-547J1399D01*
G03X352950Y107977I64J998D01*
G02X355518Y107038I1498J115D01*
G03X355716Y105479I713J-702D01*
G37*
G36*
G01X239955Y102357D02*
G02X238009Y101104I-455J-1432D01*
G03X237318Y102175I-993J118D01*
G02X239264Y103428I455J1432D01*
G03X239955Y102357I993J-118D01*
G37*
G36*
G01X344572Y99358D02*
G02X341576Y99218I-1502J14D01*
G03X340534Y100114I-995J-103D01*
G02X342226Y101610I-84J1800D01*
G03X343170Y101310I493J-84D01*
G03X343268Y101732I-902J432D01*
G02X345251Y100295I1502J-14D01*
G03X344572Y99358I321J-947D01*
G37*
G36*
G01X368156Y88958D02*
G02X365852Y89693I-1423J-481D01*
G03X366161Y90947I-587J810D01*
G02X368630Y90159I1615J799D01*
G03X368156Y88958I473J-881D01*
G37*
G36*
G01X374684Y89629D02*
G02X372411Y88920I-864J-1229D01*
G03X371938Y90151I-938J346D01*
G02X372037Y93390I838J1595D01*
G03X372588Y94581I-409J912D01*
G02X372656Y95608I1442J420D01*
G03X372093Y96949I-914J405D01*
G02X371226Y97796I527J1406D01*
G03X370047Y98391I-928J-373D01*
G02X371064Y100404I-377J1454D01*
G03X372243Y99809I928J373D01*
G02X373994Y97747I377J-1454D01*
G03X374557Y96406I914J-405D01*
G02X375352Y95713I-527J-1407D01*
G03X376025Y95508I440J237D01*
G02X375401Y93465I698J-1330D01*
G03X374728Y93670I-440J-237D01*
G02X374489Y93570I-697J1330D01*
G03X374237Y92801I153J-476D01*
G02X374373Y90911I-1461J-1055D01*
G03X374684Y89629I886J-464D01*
G37*
G36*
G01X361143Y88295D02*
G02X358203Y88592I-1497J-121D01*
G03X357858Y89213I-480J140D01*
G02X359719Y92112I485J1735D01*
G03X361142Y92006I764J645D01*
G02X362137Y89375I991J-1129D01*
G03X361143Y88295I3J-1000D01*
G37*
G36*
G01X354115Y73351D02*
G02X353850Y75569I-1537J941D01*
G03X355353Y75674I706J708D01*
G02X355600Y73604I1197J-907D01*
G03X354115Y73351I-632J-775D01*
G37*
G36*
G01X383236Y99979D02*
G02X385476Y98165I854J-1236D01*
G03X385851Y96944I923J-385D01*
G02X383309Y96350I-988J-1507D01*
G03X383104Y97610I-862J506D01*
G02X383041Y97668I985J1134D01*
G03X381679Y97699I-698J-716D01*
G02X378994Y100062I-1196J1348D01*
G03X378565Y101544I-826J564D01*
G02X377778Y103512I595J1379D01*
G03X377527Y104648I-920J393D01*
G02X376941Y106177I1206J1339D01*
G03X376008Y107281I-994J106D01*
G02X377602Y108784I92J1499D01*
G03X378649Y107787I1000J2D01*
G02X380534Y106051I84J-1800D01*
G03X381755Y105112I999J36D01*
G02X381496Y102266I332J-1465D01*
G03X380326Y101977I-394J-919D01*
G02X380291Y101935I-1171J940D01*
G03X380199Y101435I377J-328D01*
G01X380300Y101159D01*
G03X380707Y100835I470J172D01*
G02X381888Y100175I-224J-1788D01*
G03X383236Y99979I779J627D01*
G37*
G36*
G01X393193Y94308D02*
G02X390887Y93465I-700J-1661D01*
G03X390490Y94787I-891J453D01*
G02X389773Y95742I744J1305D01*
G03X388824Y96508I-972J-234D01*
G02X389002Y99505I37J1502D01*
G03X389540Y99909I47J498D01*
G02X392565Y98276I1770J-340D01*
G03X392450Y96973I696J-718D01*
G02X392643Y95574I-1217J-881D01*
G03X393193Y94308I938J-345D01*
G37*
G36*
G01X329440Y111870D02*
X313789D01*
G02X311788Y113871I0J2001D01*
G01Y115659D01*
G02X312188Y116860I2001J1D01*
G01X312288Y116993D01*
Y117060D01*
X312348D01*
X312489Y117180D01*
G02X315089I1300J-1521D01*
G01X315230Y117060D01*
X315290D01*
Y116993D01*
X315390Y116860D01*
G02X315707Y116230I-1601J-1201D01*
G01X315755Y116070D01*
X316020Y115872D01*
X327156D01*
G03X327656Y116372I-1J500D01*
G01Y119312D01*
X327856Y119512D01*
Y121065D01*
X330989Y124198D01*
X332453D01*
G02X333189Y124050I1J-1901D01*
G01X333330Y123991D01*
X333628Y124050D01*
X333736Y124158D01*
G03Y124865I-354J354D01*
G01X331693Y126908D01*
X331499Y126917D01*
G02X333383Y128801I84J1800D01*
G01X333392Y128607D01*
X337139Y124860D01*
G03X337847I354J353D01*
G01X339285Y126298D01*
X344073D01*
G02X345441Y123077I0J-1901D01*
G03X345298Y121877I720J-694D01*
G02X342131Y121772I-1555J-910D01*
G01X342184Y121878D01*
Y121996D01*
G03X341684Y122496I-500J0D01*
G01X340861D01*
X340850Y122484D01*
Y117297D01*
G02X340454Y116136I-1902J1D01*
G01X340350Y116001D01*
Y115795D01*
X340124D01*
X339998Y115712D01*
G02X337898I-1050J1585D01*
G01X337772Y115795D01*
X334396D01*
Y118799D01*
X334596Y119000D01*
Y119630D01*
G03X333202Y120549I-1000J0D01*
G02X332725Y120415I-748J1748D01*
G01X332560Y120391D01*
X331858Y119689D01*
Y115508D01*
X331758D01*
Y114188D01*
X329440Y111870D01*
G37*
G36*
G01X246133Y328652D02*
G03X246067Y329355I-385J318D01*
G02X245941Y331552I958J1157D01*
G03X245989Y332185I-361J346D01*
G02X248302Y332009I1229J864D01*
G03X248254Y331376I361J-346D01*
G02X248182Y329554I-1229J-864D01*
G03X248248Y328851I385J-318D01*
G02X246133Y328652I-958J-1157D01*
G37*
G36*
G01X340529Y481358D02*
G03X340164Y480175I568J-823D01*
G02X337741Y480738I-1402J-539D01*
G03X337934Y481960I-679J734D01*
G02X340529Y481358I1572J881D01*
G37*
G36*
G01X374688Y302154D02*
G02X372832Y302344I-1048J-1076D01*
G03X372992Y303904I-537J843D01*
G02X374848Y303714I1048J1076D01*
G03X374688Y302154I537J-843D01*
G37*
G36*
G01X365722Y296803D02*
G02X363769Y298228I-1502J-8D01*
G03X364468Y299186I-301J954D01*
G02X365385Y300577I1502J8D01*
G03X365789Y302106I-390J921D01*
G02X367774Y301487I1431J1096D01*
G03X367238Y300000I308J-951D01*
G02X366421Y297761I-1268J-806D01*
G03X365722Y296803I301J-954D01*
G37*
G36*
G01X383098Y525882D02*
G03X382609Y526320I-496J-62D01*
G02X381459Y528760I23J1502D01*
G03Y529384I-391J312D01*
G02Y531260I1173J938D01*
G03Y531884I-391J312D01*
G02X383805I1173J938D01*
G03Y531260I391J-312D01*
G02Y529384I-1173J-938D01*
G03Y528760I391J-312D01*
G02X384122Y528009I-1173J-938D01*
G03X384611Y527571I496J62D01*
G02X383098Y525882I-23J-1502D01*
G37*
G36*
G01X375159Y518967D02*
G03X374469Y519034I-380J-325D01*
G02X374527Y521344I-931J1179D01*
G03X375219Y521376I329J376D01*
G02X375159Y518967I1309J-1238D01*
G37*
G36*
G01X376292Y496600D02*
G03X375233Y496000I-138J-990D01*
G02X373836Y498087I-1383J585D01*
G03X374795Y498836I-9J1000D01*
G02X376292Y496600I1745J-451D01*
G37*
G36*
G01X375296Y481049D02*
G03X375297Y480362I364J-343D01*
G02X372731Y479052I-1090J-1033D01*
G03X371510Y479839I-983J-184D01*
G02X372033Y483119I-430J1750D01*
G03X373218Y483213I529J848D01*
G02X375296Y481049I985J-1134D01*
G37*
G36*
G01X378055Y429639D02*
G03X377365Y429522I-285J-411D01*
G02X377005Y431640I-1215J883D01*
G03X377695Y431757I285J411D01*
G02X378055Y429639I1215J-883D01*
G37*
G36*
G01X385131Y515691D02*
G02X382564Y515434I-1207J-894D01*
G03X382357Y516573I-906J424D01*
G02X383120Y519594I1260J1289D01*
G03X383722Y521034I-276J961D01*
G02X385583Y520354I1318J720D01*
G03X385114Y518865I362J-932D01*
G02X385107Y516849I-1497J-1003D01*
G03X385131Y515691I827J-562D01*
G37*
G36*
G01X440523Y557319D02*
G02X440303Y554950I803J-1269D01*
G03X438983Y554988I-682J-732D01*
G02X439218Y557525I-1151J1386D01*
G03X440523Y557319I770J639D01*
G37*
G36*
G01X452492Y526927D02*
G02X450254Y527034I-1167J-946D01*
G03X450241Y528448I-713J701D01*
G02X452639Y528334I1263J1286D01*
G03X452492Y526927I629J-777D01*
G37*
G36*
G01X476223Y60939D02*
G02X474244Y60804I-913J-1193D01*
G03X474068Y62355I-709J705D01*
G02X476188Y62499I961J1524D01*
G03X476223Y60939I643J-766D01*
G37*
G36*
G01X485436Y61950D02*
G02X485603Y59447I1374J-1165D01*
G03X484257Y59440I-669J-743D01*
G02X484100Y61777I-1017J1105D01*
G03X485436Y61950I573J820D01*
G37*
G36*
G01X481102Y54216D02*
G02Y14840I0J-19688D01*
G01Y14841D01*
G02Y54215I0J19687D01*
G01Y54216D01*
G37*
G36*
G01X531069Y441643D02*
G02X528917Y441680I-1101J-1427D01*
G03X529015Y443224I-584J812D01*
G02X531023Y443189I1023J1099D01*
G03X531069Y441643I656J-754D01*
G37*
G36*
G01X544133Y455267D02*
G02X543095Y457282I-1395J556D01*
G03X544298Y457993I238J971D01*
G02X545410Y455834I1740J-470D01*
G03X544133Y455267I-348J-938D01*
G37*
G36*
G01X531773Y420957D02*
G03X531361Y419866I554J-832D01*
G02X529077Y420728I-1451J-388D01*
G03X529489Y421819I-554J832D01*
G02X531773Y420957I1451J388D01*
G37*
G36*
G01X517835Y559894D02*
X508430D01*
X507668Y560655D01*
Y564231D01*
X508495Y565058D01*
X518107D01*
X518952Y564213D01*
Y561010D01*
X517835Y559894D01*
G37*
G36*
G01X510757Y595786D02*
X510861Y595921D01*
Y596127D01*
X511087D01*
X511213Y596210D01*
G02X513313I1050J-1585D01*
G01X513439Y596127D01*
X514237D01*
X514363Y596210D01*
G02X516463I1050J-1585D01*
G01X516589Y596127D01*
X516815D01*
Y595921D01*
X516919Y595786D01*
G02X517314Y594625I-1506J-1160D01*
G01Y590950D01*
G02X514262Y589437I-1901J0D01*
G03X513625Y589411I-303J-398D01*
G02X511009Y589480I-1272J1414D01*
G01X510362Y590128D01*
Y594625D01*
G02X510757Y595786I1901J1D01*
G37*
G36*
G01X498919Y586890D02*
G03X499024Y587548I-315J388D01*
G02X501446Y586969I1514J977D01*
G03X501241Y586334I252J-432D01*
G02X498919Y586890I-1373J-609D01*
G37*
G36*
G01X550011Y569659D02*
G03X549964Y570310I-401J298D01*
G01X549893Y570380D01*
G02X552042Y573448I1344J1345D01*
G01X552142Y573402D01*
X555138D01*
G02X556299Y573006I-1J-1902D01*
G01X556434Y572902D01*
X556640D01*
Y572676D01*
X556723Y572550D01*
G02Y570450I-1585J-1050D01*
G01X556640Y570324D01*
Y569526D01*
X556723Y569400D01*
G02Y567300I-1585J-1050D01*
G01X556640Y567174D01*
Y566948D01*
X556434D01*
X556299Y566844D01*
G02X555138Y566448I-1162J1506D01*
G01X550925D01*
X550193Y567180D01*
G02X550011Y569659I1345J1345D01*
G37*
G36*
G01X556426Y560048D02*
X555701Y559324D01*
X551438D01*
G02Y563126I0J1901D01*
G01X554234D01*
X554334Y563173D01*
G02X556423Y562852I804J-1723D01*
G01X556640D01*
Y562626D01*
X556723Y562501D01*
G02Y560399I-1585J-1051D01*
G01X556640Y560274D01*
Y560048D01*
X556426D01*
G37*
G36*
G01X547340Y530637D02*
X545483Y528780D01*
G02X542793Y531470I-1345J1345D01*
G01X543536Y532213D01*
Y533250D01*
G02X543814Y534239I1902J-1D01*
G01X543887Y534358D01*
Y534498D01*
G03X543387Y534998I-500J0D01*
G01X542834D01*
X542699Y534894D01*
G02X540253Y534998I-1161J1506D01*
G01X540036D01*
Y535224D01*
X539953Y535349D01*
G02X539636Y536400I1584J1051D01*
G01Y538592D01*
X539574Y538705D01*
G02X542583Y540970I1664J921D01*
G01X542811Y540741D01*
G03X543519I354J353D01*
G01X543550Y540772D01*
X543576Y540809D01*
G02X546483Y541070I1563J-1084D01*
G01X547340Y540213D01*
Y536400D01*
G02X547023Y535350I-1902J1D01*
G01X546940Y535224D01*
Y534426D01*
X547023Y534300D01*
G02X547340Y533250I-1585J-1051D01*
G01Y530637D01*
G37*
G36*
G01X545645Y108844D02*
G02X546305Y111695I661J1349D01*
G02X547787Y109946I1J-1502D01*
G02X547549Y109350I-1481J246D01*
G03X547933Y107918I841J-542D01*
G02X545997Y107413I-685J-1336D01*
G03X545645Y108844I-833J554D01*
G37*
G36*
G01X539680Y106948D02*
G02X538164Y109940I-170J1794D01*
G02X541311Y108795I1346J-1198D01*
G03X542286Y107835I999J40D01*
G02X540763Y106105I-38J-1502D01*
G03X539680Y106948I-988J-152D01*
G37*
G36*
G01X553237Y231384D02*
G03X553209Y230079I744J-669D01*
G02X550804Y228286I-1159J-955D01*
G03X549728Y228697I-830J-558D01*
G02X548176Y231080I-370J1456D01*
G03X547510Y231807I-394J308D01*
G02X546917Y231581I-819J1259D01*
G03X546492Y231087I75J-494D01*
G02X544763Y232571I-1502J-1D01*
G03X545188Y233065I-75J494D01*
G02X545296Y233624I1502J0D01*
G03X544943Y234814I-928J372D01*
G02X547541Y235386I1038J1473D01*
G03X547721Y234158I866J-500D01*
G02X547764Y234116I-1028J-1095D01*
G03X548463Y234101I357J350D01*
G02X550727Y233851I1025J-1098D01*
G03X551385Y233698I413J283D01*
G02X553237Y231384I735J-1310D01*
G37*
G36*
G01X604058Y607186D02*
G02X602781Y609381I-1744J455D01*
G03X603969Y609974I260J966D01*
G02X605160Y607925I1393J-561D01*
G03X604058Y607186I-134J-991D01*
G37*
G36*
G01X605189Y602562D02*
G02X604169Y600443I332J-1465D01*
G03X602928Y600947I-900J-436D01*
G02X604021Y603217I-614J1694D01*
G03X605189Y602562I947J320D01*
G37*
G36*
G01X606601Y591892D02*
G02X604115Y591819I-1205J-1340D01*
G03X604158Y593179I-711J703D01*
G02X606478Y593247I1132J987D01*
G03X606601Y591892I791J-611D01*
G37*
G36*
G01X692575Y560870D02*
G02X690489I-1043J-1081D01*
G03X690415Y562375I-694J720D01*
G02Y565203I1117J1414D01*
G03X690489Y566708I-620J785D01*
G02X690630Y568990I1043J1081D01*
G03Y570588I-601J799D01*
G02X690489Y572870I902J1201D01*
G03X690415Y574375I-694J720D01*
G02Y577203I1117J1414D01*
G03X690489Y578708I-620J785D01*
G02Y580870I1043J1081D01*
G03X690415Y582375I-694J720D01*
G02Y585203I1117J1414D01*
G03X690489Y586708I-620J785D01*
G02X692575I1043J1081D01*
G03X692649Y585203I694J-720D01*
G02Y582375I-1117J-1414D01*
G03X692575Y580870I620J-785D01*
G02Y578708I-1043J-1081D01*
G03X692649Y577203I694J-720D01*
G02Y574375I-1117J-1414D01*
G03X692575Y572870I620J-785D01*
G02X692434Y570588I-1043J-1081D01*
G03Y568990I601J-799D01*
G02X692575Y566708I-902J-1201D01*
G03X692649Y565203I694J-720D01*
G02Y562375I-1117J-1414D01*
G03X692575Y560870I620J-785D01*
G37*
G36*
G01X663546Y588751D02*
G02X660130Y587336I-2001J0D01*
G01X659981Y587485D01*
G02X659514Y589580I1415J1415D01*
G01X659544Y589663D01*
Y592143D01*
G02X660024Y593443I2000J0D01*
G01X660144Y593584D01*
Y593644D01*
X660211D01*
X660344Y593744D01*
G02X660522Y593863I1200J-1602D01*
G03Y594723I-256J430D01*
G02X660344Y594842I1022J1721D01*
G01X660211Y594942D01*
X660144D01*
Y595002D01*
X660024Y595143D01*
G02Y597743I1521J1300D01*
G01X660144Y597884D01*
Y597944D01*
X660211D01*
X660344Y598044D01*
G02X661545Y598444I1200J-1601D01*
G01X665499D01*
X666585Y597358D01*
G02X663969Y594342I-1416J-1414D01*
G01X663836Y594442D01*
X663446D01*
G03X662946Y593942I1J-500D01*
G01Y593584D01*
X663066Y593443D01*
G02X663546Y592143I-1520J-1300D01*
G01Y588751D01*
G37*
G36*
G01X664603Y603978D02*
G02Y599974I0J-2002D01*
G01X661647D01*
G02X660446Y600375I1J2002D01*
G01X660313Y600474D01*
X660246D01*
Y600535D01*
X660126Y600676D01*
G02Y603276I1521J1300D01*
G01X660246Y603417D01*
Y603478D01*
X660313D01*
X660446Y603577D01*
G02X661647Y603978I1202J-1601D01*
G01X664603D01*
G37*
G36*
G01X660344Y615984D02*
Y617040D01*
X660310D01*
Y617100D01*
X660191Y617241D01*
G02Y619841I1521J1300D01*
G01X660310Y619982D01*
Y620042D01*
X660378D01*
X660511Y620142D01*
G02X661712Y620542I1200J-1601D01*
G01X667095D01*
X669025Y618612D01*
G02X667772Y615202I-1415J-1415D01*
G03X666859Y614318I81J-997D01*
G02X664870Y612542I-1989J226D01*
G01X661745D01*
G02X660544Y612942I-1J2001D01*
G01X660411Y613042D01*
X660344D01*
Y613102D01*
X660224Y613243D01*
G02Y615843I1521J1300D01*
G01X660344Y615984D01*
G37*
G36*
G01X690572Y626700D02*
Y620224D01*
X689784Y619436D01*
X681268D01*
Y628202D01*
X689070D01*
G02X690572Y626700I0J-1502D01*
G37*
G36*
G01X708730Y619318D02*
Y627052D01*
X709737Y628058D01*
X723849D01*
X724874Y627034D01*
Y617826D01*
X723767Y616720D01*
X711329D01*
X708730Y619318D01*
G37*
G36*
G01X699152Y97703D02*
G02X678801Y97704I-10176J-12073D01*
G03X679487Y99177I-1241J1474D01*
G01Y105315D01*
G02X698467I9490J0D01*
G01Y99177D01*
G03X699152Y97703I1927J-1D01*
G37*
G36*
G01Y711876D02*
G02X678801Y711877I-10176J-12073D01*
G03X679487Y713350I-1241J1474D01*
G01Y719488D01*
G02X698467I9490J0D01*
G01Y713350D01*
G03X699152Y711876I1927J-1D01*
G37*
G36*
G01X714990Y526573D02*
G02X714718Y524363I1270J-1278D01*
G03X713230Y524621I-856J-517D01*
G02X713484Y526684I-949J1164D01*
G03X714990Y526573I801J599D01*
G37*
G36*
G01X734125Y490176D02*
G02X732765Y490937I-1308J-741D01*
G03X733083Y491563I-14J401D01*
G02X734492Y490774I1492J1012D01*
G03X734125Y490176I-18J-401D01*
G37*
G36*
G01X726918Y485869D02*
G02X726889Y487743I-1188J919D01*
G03X728452Y487767I772J636D01*
G02X728481Y485893I1188J-919D01*
G03X726918Y485869I-772J-636D01*
G37*
G36*
G01X716826Y481013D02*
G02X715693Y482579I-1498J109D01*
G03X716933Y483477I243J970D01*
G02X718903Y484794I1498J-109D01*
G03X720033Y485203I293J956D01*
G02X720831Y482951I1257J-822D01*
G03X719694Y482555I-306J-952D01*
G02X718066Y481911I-1263J813D01*
G03X716826Y481013I-243J-970D01*
G37*
G36*
G01X684022Y480981D02*
G02X682202I-910J-1195D01*
G03X682211Y482566I-606J796D01*
G02X684013I901J1157D01*
G03X684022Y480981I615J-789D01*
G37*
G36*
G01X700205Y469320D02*
G02X697515Y466630I-1345J-1345D01*
G01X696107Y468038D01*
X692932D01*
Y469633D01*
G03X691548Y470557I-1000J0D01*
G02X690190Y473144I-561J1355D01*
G03X690418Y473564I-272J420D01*
G01Y476944D01*
X690479D01*
X690607Y477253D01*
G03X690498Y477797I-462J190D01*
G01X689748Y478548D01*
G02X692224Y481024I1238J1238D01*
G01X694272Y478977D01*
Y477236D01*
X694564Y476944D01*
X694622D01*
Y472742D01*
G03X695122Y472242I500J0D01*
G01X697077D01*
G03X697523Y472515I0J500D01*
G02X697685Y472791I1339J-600D01*
G01X697795Y472938D01*
X697493Y473240D01*
X695308D01*
Y477744D01*
X695508D01*
G03X696008Y478244I0J500D01*
G01Y479410D01*
X697423Y480826D01*
G03Y481532I-354J353D01*
G01X696654Y482301D01*
G03X696301Y482448I-354J-353D01*
G01X694608D01*
X692122Y484934D01*
Y485197D01*
G03X691067Y486195I-1000J-1D01*
G02X691883Y488821I-81J1465D01*
G01X692032Y488706D01*
X692409Y488729D01*
X693374Y489694D01*
X696744D01*
X697605Y488832D01*
X697916Y488777D01*
X698059Y488845D01*
G02X699719Y486478I624J-1328D01*
G03Y485770I353J-354D01*
G01X700442Y485047D01*
G03X701731Y484942I706J708D01*
G02X701610Y482653I854J-1193D01*
G01X701609Y482654D01*
G03X700924Y482634I-332J-374D01*
G01X700388Y482098D01*
G03X700283Y480807I707J-707D01*
G02X700098Y478548I-1423J-1021D01*
G01X699510Y477960D01*
X699726Y477744D01*
X700210D01*
Y473240D01*
X699993D01*
X699979Y472864D01*
X700023Y472806D01*
G02X699946Y470925I-1163J-894D01*
G03X699979Y469546I740J-672D01*
G01X700205Y469320D01*
G37*
G36*
G01X702322Y461775D02*
G02X700832Y464058I-1732J497D01*
G03X701381Y464422I67J495D01*
G02X703174Y462620I1416J-384D01*
G01X703044Y462586D01*
X702358Y461900D01*
X702322Y461775D01*
G37*
G36*
G01X696154Y460701D02*
G02X694270Y458817I-84J-1800D01*
G01X694261Y459011D01*
X690664Y462608D01*
X690559Y462645D01*
G02X689870Y463155I512J1412D01*
G03X688295Y463184I-799J-602D01*
G02X686160Y465279I-1165J948D01*
G03X686137Y466826I-645J764D01*
G02X688009Y466866I912J1149D01*
G03X688050Y465319I654J-757D01*
G02X688330Y465035I-920J-1187D01*
G03X689905Y465006I799J602D01*
G02X692559Y464257I1165J-948D01*
G01X692581Y464089D01*
X695960Y460710D01*
X696154Y460701D01*
G37*
G54D95*
X40749Y249194D03*
G54D93*
X49244Y360352D03*
X18960Y572061D03*
X17876Y578422D03*
X21881Y595792D03*
X14500Y601957D03*
X9240Y638699D03*
X54062Y257049D03*
X68756Y167695D03*
X59640Y161376D03*
X55963Y199565D03*
X68930Y197193D03*
X57749Y204326D03*
X56383Y218543D03*
X63720Y228683D03*
X56936Y223944D03*
X81030Y172605D03*
X71510Y164548D03*
X75236Y188946D03*
X75359Y201109D03*
X85876Y218939D03*
X78190Y214642D03*
X75560Y218513D03*
X72150Y225148D03*
X86479Y249259D03*
X79544Y267579D03*
X90878Y177967D03*
X86560Y205852D03*
X88399Y244041D03*
X50170Y636895D03*
X56500Y789667D03*
X129028Y425593D03*
X126072Y480864D03*
X151145Y469456D03*
X171616Y467804D03*
X179857Y477790D03*
X168370D03*
X197809Y469953D03*
X252670Y443592D03*
X132960Y550005D03*
X149860Y726626D03*
X169268Y705304D03*
X171154Y715673D03*
X169531Y710542D03*
X187812Y286352D03*
X184754Y302843D03*
X198890Y584105D03*
X198296Y232699D03*
X281954Y255588D03*
X269263Y252800D03*
X218947Y312617D03*
X389400Y89232D03*
X247870Y105821D03*
X360827Y108541D03*
X365283Y128125D03*
X380906Y88134D03*
X384450Y108830D03*
X391536Y108990D03*
X408072Y109146D03*
X391190Y104173D03*
X327430Y108208D03*
X265532Y422648D03*
X316963Y467655D03*
X321357Y456709D03*
X316956Y478833D03*
X321246Y472669D03*
X315980Y472128D03*
X325040Y480129D03*
X336010Y531598D03*
X340182Y531787D03*
X340330Y541931D03*
X341011Y537828D03*
X342190Y565848D03*
X336088Y454511D03*
X346750Y466532D03*
X368787Y472998D03*
X368943Y506356D03*
X383750Y437058D03*
X377284Y473374D03*
X381760Y496004D03*
X374203Y491029D03*
X379177Y509798D03*
X387080Y486400D03*
X409985Y508431D03*
X416515Y547602D03*
X442763Y549595D03*
X492955Y99440D03*
X484068Y99980D03*
X488438Y100123D03*
X487030Y68075D03*
X479450Y63721D03*
X464767Y78145D03*
X457583Y66384D03*
X543381Y448428D03*
X542738Y463123D03*
X536440Y431923D03*
X541440Y431787D03*
X533038Y590325D03*
X532955Y108669D03*
Y100604D03*
X566090Y109136D03*
X542700Y112881D03*
X545424Y226722D03*
X551341Y274262D03*
X673700Y562515D03*
X677850D03*
X673590Y567696D03*
X677730Y567706D03*
X713190Y583032D03*
X713300Y578995D03*
X695600Y590788D03*
X715528Y459332D03*
X672190Y457216D03*
X691148Y140140D03*
X691280Y149571D03*
X691314Y145071D03*
X701687Y212132D03*
X700947Y216868D03*
X700994Y221368D03*
X710585Y539103D03*
X701170Y538508D03*
X691161Y518684D03*
X700719Y516954D03*
X729942Y515757D03*
X696494Y513677D03*
X738130Y502748D03*
X720150Y491632D03*
X742779Y487639D03*
X731340Y476723D03*
G54D103*
X738000Y506600D03*
X727602Y500100D03*
X748300Y496800D03*
X748425Y481000D03*
G54D94*
X20350Y555807D03*
X16200Y566921D03*
X11980Y617956D03*
X14550Y628297D03*
X13807Y634826D03*
X9300Y631472D03*
X23610Y568111D03*
X24168Y655750D03*
X56190Y170026D03*
X57257Y180712D03*
X67853Y180744D03*
X68690Y175589D03*
X66570Y189983D03*
X68830Y215817D03*
X63718Y239030D03*
X82030Y191733D03*
X73870Y205758D03*
X46890Y633564D03*
X47480Y616848D03*
X135300Y468444D03*
X146240Y472111D03*
X197161Y465628D03*
X266822Y443297D03*
X300040Y459733D03*
X164259Y557273D03*
X168189Y514331D03*
X173252Y515693D03*
X165707Y506156D03*
X172087Y510536D03*
X174930Y547106D03*
X169157Y548676D03*
X173163Y551903D03*
X167105Y552882D03*
X193466Y546886D03*
X180430Y392969D03*
X148200Y669205D03*
X138198Y712628D03*
X192298Y286183D03*
X172430Y584035D03*
X196740Y589735D03*
X192130Y632235D03*
X199786Y618893D03*
X202510Y624005D03*
X205221Y630886D03*
X198685Y244085D03*
Y237385D03*
X276904Y252550D03*
X254418Y240407D03*
X256492Y222466D03*
X217135Y230585D03*
X279161Y237817D03*
X236710Y244042D03*
X243373Y88767D03*
X252683Y105867D03*
X262473Y106937D03*
X302930Y132994D03*
X337630Y106304D03*
X353713Y93057D03*
X421893Y123537D03*
X320080Y512736D03*
X322986Y467109D03*
X330115Y490303D03*
X335162Y502791D03*
X326740Y495763D03*
X329672Y502057D03*
X326170Y518386D03*
X335860Y516486D03*
X327058Y358376D03*
X314550Y331564D03*
X348220Y486484D03*
X348870Y501571D03*
X369507Y464391D03*
X375190Y463996D03*
X381239Y467171D03*
X421461Y547703D03*
X420883Y556729D03*
X431145Y556608D03*
X445838Y538085D03*
X450367Y540720D03*
X516146Y113121D03*
X519625Y108543D03*
X512878Y108635D03*
X513120Y72069D03*
X509691Y112938D03*
X504750Y111749D03*
X500310Y109211D03*
X502900Y57670D03*
X484350Y112811D03*
X494355Y108674D03*
X488438Y109623D03*
X464170Y56436D03*
X458120Y44721D03*
X547638Y462356D03*
X547488Y452373D03*
X546384Y445107D03*
X540141Y442994D03*
X535352Y440414D03*
X512867Y443679D03*
X506456Y446928D03*
X557995Y110244D03*
X550490Y112989D03*
X564274Y279395D03*
X579707Y229395D03*
X585579Y230095D03*
X591707Y230162D03*
X605286Y584152D03*
X609026Y579132D03*
X617270Y580443D03*
X615690Y625536D03*
X611572Y629894D03*
X627084Y578257D03*
X623940Y628720D03*
X636890Y627095D03*
X634137Y631342D03*
X641236Y381616D03*
X645236Y377858D03*
X648425Y373474D03*
X652139Y377125D03*
X712740Y593101D03*
X651437Y578943D03*
X668925Y364887D03*
X673740Y449887D03*
X667070Y483608D03*
X667774Y477992D03*
X686770Y543325D03*
X706361Y532632D03*
X719761Y532432D03*
X716021Y516945D03*
X696891Y507279D03*
X707920Y505575D03*
X700829Y504041D03*
X704766Y498880D03*
X713978Y498075D03*
X720140Y478333D03*
G54D98*
X242460Y237591D03*
X745500Y492500D03*
G54D101*
X554780Y28803D03*
X544780Y38803D03*
X534780D03*
Y28803D03*
X524780Y38803D03*
X514780D03*
X524780Y28803D03*
X514780D03*
G54D96*
X43898Y168544D03*
Y231457D03*
G54D97*
X154517Y513931D03*
X181232Y543953D03*
X674353Y463842D03*
X687049Y487660D03*
X683112D03*
X706734Y483723D03*
X687049D03*
X706734Y479786D03*
Y475850D03*
X683113Y471941D03*
G54D91*
X45282Y321764D03*
G54D102*
X711575Y143555D03*
X733975D03*
X711575Y222361D03*
G54D90*
X25455Y356832D03*
G54D99*
X413386Y377165D03*
G54D100*
X554780Y38803D03*
G54D92*
X45282Y338300D03*
%LPD*%
G75*
G36*
G01X143593Y557135D02*
X147041D01*
X147670Y556506D01*
Y548821D01*
X147646Y548797D01*
Y535970D01*
X148363Y535253D01*
X148831Y534786D01*
X149271Y534345D01*
X155558D01*
G02X156058Y533845I0J-500D01*
G01Y533163D01*
G02X154850Y532185I-1000J0D01*
G03Y528659I-375J-1763D01*
G02X156058Y527681I208J-978D01*
G01Y526352D01*
X155734Y526028D01*
X154928D01*
X154834Y526068D01*
G03X153237Y525979I-709J-1657D01*
G01X153122Y525913D01*
X143790D01*
X143148D01*
X143100Y525961D01*
X141625Y527436D01*
X139805Y529256D01*
Y547707D01*
Y554650D01*
X142290Y557135D01*
X143593D01*
G37*
G36*
G01X148899Y536134D02*
Y555943D01*
Y556740D01*
X149212Y557053D01*
X150009D01*
X152509D01*
X153209Y556353D01*
Y554053D01*
X153226Y554036D01*
Y553568D01*
X153470Y553324D01*
X155114D01*
X155824D01*
X155940Y553208D01*
Y551189D01*
X155535Y550784D01*
X153440D01*
X153209Y550553D01*
Y546953D01*
X153609Y546553D01*
X154355D01*
X154364Y546562D01*
X155409D01*
X155707Y546264D01*
Y541715D01*
G02X155207Y541215I-500J0D01*
G01X154140D01*
X153295Y540370D01*
Y538403D01*
X154289Y537409D01*
X155309D01*
X156155Y536563D01*
Y536056D01*
X155446Y535347D01*
X149686D01*
X148899Y536134D01*
G37*
G36*
G01X179794Y526859D02*
G02X178650Y525870I-1000J0D01*
G03X178396Y525888I-250J-1733D01*
G01X176978D01*
G02X176056Y527276I0J1000D01*
G03X175757Y529155I-1661J699D01*
G02X175755Y530463I755J655D01*
G03X175761Y530470I-1035J893D01*
G02X176566Y530410I381J-324D01*
G03X178360Y529583I1528J955D01*
G02X179498Y528452I148J-989D01*
G03X179725Y527313I1734J-247D01*
G01X179794Y527195D01*
Y526859D01*
G37*
G36*
G01D02*
G02X178650Y525870I-1000J0D01*
G03X178396Y525888I-250J-1733D01*
G01X176978D01*
G02X176056Y527276I0J1000D01*
G03X175757Y529155I-1661J699D01*
G02X175755Y530463I755J655D01*
G03X175761Y530470I-1035J893D01*
G02X176566Y530410I381J-324D01*
G03X178360Y529583I1528J955D01*
G02X179498Y528452I148J-989D01*
G03X179725Y527313I1734J-247D01*
G01X179794Y527195D01*
Y526859D01*
G37*
G36*
G01D02*
G02X178650Y525870I-1000J0D01*
G03X178396Y525889I-257J-1733D01*
G01X176978D01*
G02X176056Y527276I0J1000D01*
G03X175541Y529366I-1661J699D01*
G02X175569Y530160I317J386D01*
G03X175571Y530161I-655J1313D01*
G02X176844Y530067I580J-815D01*
G03X178360Y529583I1250J1298D01*
G02X179498Y528452I148J-989D01*
G03X179725Y527313I1734J-247D01*
G01X179794Y527195D01*
Y526859D01*
G37*
G36*
G01D02*
G02X178650Y525870I-1000J0D01*
G03X178396Y525889I-257J-1733D01*
G01X176978D01*
G02X176056Y527276I0J1000D01*
G03X175541Y529366I-1661J699D01*
G02X175569Y530160I317J386D01*
G03X175571Y530161I-655J1313D01*
G02X176844Y530067I580J-815D01*
G03X178360Y529583I1250J1298D01*
G02X179498Y528452I148J-989D01*
G03X179725Y527313I1734J-247D01*
G01X179794Y527195D01*
Y526859D01*
G37*
G36*
G01X287855Y95867D02*
G02X288321Y95549I0J-500D01*
G03X290593Y94871I1400J545D01*
G02X292105Y94420I581J-814D01*
G03X294570Y96024I1400J545D01*
G02X294572Y97436I709J705D01*
G01X295043Y97907D01*
X298713D01*
X300753Y95867D01*
X310512D01*
G02X310940Y95627I1J-500D01*
G03X311052Y95466I1286J775D01*
G02X310730Y93950I-779J-627D01*
G03X312240Y90681I823J-1603D01*
G02X313606Y89937I382J-924D01*
G03X314639Y91642I1477J270D01*
G02X313348Y92508I-295J955D01*
G03X312848Y93600I-1795J-161D01*
G02X313029Y95140I718J696D01*
G03X313506Y95627I-806J1267D01*
G02X313934Y95867I427J-260D01*
G01X316058D01*
G02X316536Y95515I0J-500D01*
G03X319404I1434J446D01*
G02X319882Y95867I478J-148D01*
G01X342071D01*
G02X343071Y94860I0J-1000D01*
G03X343996Y93273I1802J-13D01*
G02X344290Y91775I-487J-873D01*
G03X346891Y91300I1173J-938D01*
G01Y91301D01*
X346848Y91436D01*
X346880Y91572D01*
G02X347720Y91810I487J-116D01*
G01X348513Y91017D01*
Y86667D01*
X345113Y83267D01*
X248323D01*
X247393Y84197D01*
Y91217D01*
X248283Y92107D01*
Y92747D01*
G02X248734Y93245I500J0D01*
G03X250342Y95296I-176J1793D01*
G01X250337Y95331D01*
Y95367D01*
G02X250837Y95867I500J0D01*
G01X251279D01*
G02X251779Y95367I0J-500D01*
G01Y95331D01*
X251774Y95296D01*
G03X255357Y94928I1784J-258D01*
G02X256355Y95867I998J-61D01*
G01X261093D01*
G02X262025Y94503I0J-1000D01*
G03X265381I1678J-656D01*
G02X266313Y95867I932J364D01*
G01X287855D01*
G37*
G36*
G01X261717Y120070D02*
G02X261775Y119837I-442J-234D01*
G01Y116512D01*
X261191Y115928D01*
X257709D01*
X257417Y116220D01*
Y119622D01*
X256600Y120439D01*
Y125648D01*
X257102Y126150D01*
X260860D01*
X261685Y125325D01*
Y120102D01*
X261717Y120070D01*
G37*
G36*
G01X263663Y123877D02*
X275283D01*
X278994D01*
X279300Y123571D01*
Y117332D01*
X278335Y116367D01*
X274883D01*
X263743D01*
X263463Y116647D01*
Y123677D01*
X263663Y123877D01*
G37*
G36*
G01X352080Y134390D02*
G03I-660J0D01*
G37*
G36*
G01X508910Y564056D02*
X517692D01*
X517950Y563798D01*
Y561425D01*
X517420Y560895D01*
X508845D01*
X508670Y561070D01*
Y563816D01*
X508910Y564056D01*
G37*
G36*
G01X625340Y563591D02*
Y554731D01*
X650850D01*
Y563591D01*
X625340D01*
G37*
G36*
G01X682270Y627200D02*
X689070D01*
G02X689570Y626700I0J-500D01*
G01Y620639D01*
X689369Y620438D01*
X682270D01*
Y627200D01*
G37*
G36*
G01X698040Y486032D02*
X699819Y484254D01*
Y482945D01*
X699523Y482649D01*
X697723D01*
X696923Y483449D01*
X695023D01*
X693123Y485349D01*
Y488027D01*
X693789Y488693D01*
X696328D01*
X696708Y488312D01*
Y486752D01*
X697428Y486032D01*
X698040D01*
G37*
G36*
G01X709732Y626637D02*
X710152Y627057D01*
X723434D01*
X723872Y626619D01*
Y618241D01*
X723352Y617721D01*
X711744D01*
X709732Y619733D01*
Y626637D01*
G37*
%LPC*%
G75*
G36*
G01X273072Y91186D02*
G02X270604Y90329I-827J-1601D01*
G03X270268Y91559I-911J412D01*
G02X272573Y92359I865J1228D01*
G03X273072Y91186I958J-285D01*
G37*
G36*
G01X325438Y89482D02*
G02X323395Y90203I-1368J-621D01*
G03X323807Y91603I-450J893D01*
G02X325996Y90831I1553J914D01*
G03X325438Y89482I352J-936D01*
G37*
G54D93*
X340543Y88647D03*
G54D94*
X335668Y92822D03*
X296870Y92072D03*
X301870D03*
X287423Y91857D03*
X276603Y92119D03*
X330668Y92822D03*
%LPD*%
G75*
G54D10*
X-294532Y1044846D03*
X-281332D03*
X-287932D03*
X-267012Y1044916D03*
X20650Y546243D03*
X20350Y555807D03*
X16200Y566921D03*
X11980Y617956D03*
X15349Y614142D03*
X14550Y628297D03*
X13807Y634826D03*
X9300Y631472D03*
X33841Y9183D03*
X36588Y32278D03*
X34008Y91017D03*
X32260Y96899D03*
X33231Y556346D03*
X30672Y551245D03*
X23610Y568111D03*
X34440Y597285D03*
X28112Y591718D03*
X28185Y612088D03*
X30744Y617898D03*
X24168Y655750D03*
X37920Y651828D03*
X49890Y30392D03*
X51580Y17595D03*
X42205Y21518D03*
X54800Y25547D03*
X44010Y55170D03*
X54981Y59420D03*
X54101Y74252D03*
X51340Y69181D03*
X46570Y73891D03*
X47510Y109421D03*
X47420Y433725D03*
X53769Y513033D03*
X54988Y518683D03*
X49857Y520516D03*
X50630Y529281D03*
X50140Y550572D03*
X39540Y538464D03*
X50870Y564008D03*
X43467Y555938D03*
X49680Y579709D03*
X49620Y574212D03*
X47557Y588971D03*
X44507Y594082D03*
X40908Y589691D03*
X39370Y600956D03*
X42950Y612487D03*
X48540Y624953D03*
X52230Y614907D03*
X47480Y616848D03*
X46890Y633564D03*
X53751Y652029D03*
X44640Y651029D03*
X40980Y656396D03*
X56610Y20553D03*
X64190Y72841D03*
X61760Y107321D03*
X55230Y112521D03*
X63900Y112081D03*
X56190Y170026D03*
X57257Y180712D03*
X67853Y180744D03*
X68690Y175589D03*
X66570Y189983D03*
X68830Y215817D03*
X56287Y242872D03*
X63718Y239030D03*
X61945Y267579D03*
X66818Y297483D03*
X57994Y287655D03*
X61357Y477892D03*
X64480Y501596D03*
X62253Y522589D03*
X67369Y522993D03*
X70696Y527237D03*
X67260Y546688D03*
X65900Y566403D03*
X66262Y553344D03*
X65989Y578115D03*
X57710Y572918D03*
X57070Y580074D03*
X69766Y582525D03*
X57440Y585607D03*
X68630Y599945D03*
X61205Y623870D03*
X63570Y613914D03*
X63610Y618917D03*
X61205Y628870D03*
X56240Y630081D03*
X63650Y646957D03*
X61600Y653611D03*
X76030Y156152D03*
X82553Y185431D03*
X82030Y191733D03*
X73870Y205758D03*
X77239Y260814D03*
X81165Y257717D03*
X78373Y276029D03*
X72190Y297395D03*
X77368Y299206D03*
X83084Y389621D03*
X83245Y397913D03*
X85951Y410263D03*
X74291Y486665D03*
X83536Y498308D03*
X81635Y517104D03*
X85346Y512295D03*
X73057Y515286D03*
X72635Y508991D03*
X81491Y533191D03*
X80318Y544311D03*
X75380Y608914D03*
Y603914D03*
X101449Y194368D03*
X101020Y223348D03*
X95951Y376661D03*
X98470Y418834D03*
X91458Y511853D03*
X92422Y531081D03*
X98803Y531597D03*
X97268Y537055D03*
X96200Y616325D03*
X95310Y647481D03*
X97180Y786472D03*
X111220Y160923D03*
X106090Y167615D03*
X112530Y186363D03*
X106760Y175370D03*
X114920Y179082D03*
X108910Y193194D03*
X116960Y394023D03*
X114502Y401262D03*
X107531Y394023D03*
X109972Y509321D03*
X106650Y779581D03*
X102421Y785938D03*
X131068Y76588D03*
X129650Y250414D03*
Y255414D03*
X120144Y401104D03*
X126622Y401436D03*
X132344Y401278D03*
X132902Y394857D03*
X118124Y510811D03*
X124279Y523691D03*
X120300Y572512D03*
X121070Y670509D03*
X132050Y671817D03*
X133607Y686699D03*
X130260Y679836D03*
X132438Y704733D03*
X133490Y695470D03*
X131960Y720941D03*
X119900Y754021D03*
X125600Y759000D03*
X131900Y760900D03*
X125960Y785699D03*
X120090Y780618D03*
X141490Y19267D03*
X137872Y29551D03*
X139931Y40842D03*
X139932Y35310D03*
X135050Y53493D03*
X143857Y51943D03*
X149025Y51720D03*
X135290Y87664D03*
X148330Y258806D03*
X145200Y276468D03*
X138930Y278965D03*
X148350Y281769D03*
X134540Y267786D03*
X145720Y311336D03*
X135224Y323543D03*
X146100D03*
X145580Y316836D03*
X136506Y332193D03*
X139146Y400804D03*
X145284Y401507D03*
X142239Y422346D03*
X135300Y468444D03*
X146240Y472111D03*
X143543Y532024D03*
X141893Y544799D03*
X142087Y538145D03*
X146361Y555387D03*
X149050Y588044D03*
X148200Y669205D03*
X140110Y675907D03*
X139158Y686725D03*
X135280Y679212D03*
X138726Y696707D03*
X138198Y712628D03*
X144631Y735955D03*
X135470Y781697D03*
X145570Y780580D03*
X157877Y30674D03*
X152810Y29921D03*
X158165Y21300D03*
X159861Y36134D03*
X157010Y58963D03*
X164550Y61239D03*
X156440Y74863D03*
X151618Y83343D03*
X164280Y101810D03*
X164490Y127110D03*
X159190Y127781D03*
X152990Y248096D03*
X157690Y249918D03*
X154546Y256986D03*
X152634Y276809D03*
X149721Y292987D03*
X152733Y288517D03*
X158076Y290635D03*
X154581Y308767D03*
X151230Y330164D03*
X150918Y318134D03*
X150510Y336306D03*
X156448Y336629D03*
X162071Y336947D03*
X158605Y364565D03*
X161563Y432521D03*
X154370Y449930D03*
X159690Y465290D03*
X150547Y459363D03*
X162335Y512456D03*
X159196Y515612D03*
X159179Y521893D03*
X154126Y524411D03*
X154475Y530422D03*
X159180Y528227D03*
X162335Y543954D03*
X159185Y537654D03*
X162336Y550253D03*
X164259Y557273D03*
X161280Y581585D03*
X156480Y583315D03*
X150380Y602885D03*
X152442Y627881D03*
X157963Y633735D03*
X161981Y730784D03*
X163138Y778565D03*
X155170Y780656D03*
X160320Y786346D03*
X168961Y27073D03*
X180159Y40661D03*
X165336Y46126D03*
X167383Y93147D03*
X168850Y99251D03*
X169510Y106579D03*
X174710Y105699D03*
X177763Y121057D03*
X168170Y123367D03*
X173170D03*
X178040Y228978D03*
X167483Y239914D03*
X177891Y249324D03*
X175756Y257668D03*
X170501Y259161D03*
X178025Y279018D03*
X178810Y287263D03*
X174148Y289289D03*
X180410Y304866D03*
X172988Y305719D03*
X168110Y350642D03*
X174860Y362416D03*
X180430Y392969D03*
X180440Y398056D03*
X167527Y420268D03*
X179562Y424001D03*
X170683Y436834D03*
X170361Y428595D03*
X169728Y487664D03*
X165970Y497629D03*
X176909Y501153D03*
X168189Y514331D03*
X178085Y512456D03*
X173252Y515693D03*
X165707Y506156D03*
X172087Y510536D03*
X169615Y519216D03*
X178094Y531365D03*
X166297Y532416D03*
X169491Y529702D03*
X166837Y523486D03*
X174395Y527975D03*
X173513Y522854D03*
X168243Y542706D03*
X174930Y547106D03*
X169157Y548676D03*
X173163Y551903D03*
X169444Y558757D03*
X167105Y552882D03*
X178083Y553402D03*
X172889Y562710D03*
X175330Y578535D03*
X166930Y578435D03*
X166786Y569056D03*
X172430Y584035D03*
X177830Y583535D03*
X166570Y583874D03*
X179120Y639615D03*
X169930Y635329D03*
X172510Y639771D03*
X167810Y668131D03*
X171180Y683815D03*
X180820Y717914D03*
X175463Y720245D03*
X174954Y728404D03*
X167568Y743335D03*
X177070Y785736D03*
X177224Y777765D03*
X169860Y782086D03*
X191596Y27620D03*
X184928Y91847D03*
X189928D03*
X196653Y91837D03*
X196493Y105637D03*
X188203Y104567D03*
X194463Y122631D03*
X184050Y230139D03*
X184296Y241098D03*
X181176Y257643D03*
X183440Y269816D03*
X193245Y280285D03*
X189689Y268237D03*
X183198Y278034D03*
X188979Y273444D03*
X191970Y297731D03*
X192298Y286183D03*
X183254Y310663D03*
X183228Y317023D03*
X191159Y317171D03*
X190557Y325701D03*
X195530Y340946D03*
X192040Y333606D03*
X184953Y361563D03*
X182788Y352108D03*
X195420Y372406D03*
X192681Y377554D03*
X193590Y383383D03*
X196273Y403152D03*
X190700Y418325D03*
X182370Y439198D03*
X192527Y429049D03*
X189077Y438281D03*
X192741Y497930D03*
X184843Y533995D03*
X189252Y526236D03*
X191457Y531553D03*
X193466Y546886D03*
X186841Y545372D03*
X194709Y557353D03*
X181491Y557436D03*
X193080Y581235D03*
X182480Y566819D03*
X196740Y589735D03*
X189460Y587915D03*
X192130Y632235D03*
X184748Y639687D03*
X182480Y634585D03*
X191480Y639135D03*
X185993Y682670D03*
X191542Y691925D03*
X181950Y698191D03*
X188566Y722353D03*
X183566D03*
X193566Y722333D03*
X187570Y770605D03*
X192949Y771020D03*
X191081Y785766D03*
X183650Y774332D03*
X182500Y780786D03*
X189770Y778082D03*
X204978Y10605D03*
X204003Y91247D03*
X208908Y96975D03*
X205903Y101477D03*
X210623Y121267D03*
X207154Y175212D03*
X207070Y188978D03*
X205535Y234497D03*
Y228682D03*
X211935Y230585D03*
X205271Y240209D03*
X198685Y237385D03*
Y244085D03*
X210305Y259330D03*
X200977Y256305D03*
X208101Y273007D03*
X197850Y272666D03*
X197468Y289193D03*
X202687Y296024D03*
X198801Y318727D03*
X208000Y325200D03*
X206318Y334987D03*
X200687Y374520D03*
X206973Y361900D03*
X208529Y366783D03*
X201267Y403294D03*
X204584Y462478D03*
X197161Y465628D03*
X203628Y475993D03*
X197628Y489843D03*
X211609Y516553D03*
X205257Y528822D03*
X211287Y528547D03*
X212342Y536729D03*
X199539Y537112D03*
X204309Y539953D03*
X205286Y551130D03*
X211240Y572893D03*
X201510Y576885D03*
X197730Y572893D03*
X197709Y567464D03*
X210790Y566926D03*
X209940Y584893D03*
X198210Y611085D03*
X204024Y604135D03*
Y609135D03*
X208904Y611515D03*
X200380Y629085D03*
X199786Y618893D03*
X202510Y624005D03*
X208904Y616515D03*
X197480Y639815D03*
X203065Y638700D03*
X205221Y630886D03*
X205410Y661200D03*
X211560Y670575D03*
X199590Y682868D03*
X199350Y692724D03*
X196966Y700705D03*
X198566Y722353D03*
X209017Y722344D03*
X203611Y722303D03*
X199760Y763929D03*
X210250Y784919D03*
X202050D03*
X200550Y772046D03*
X206180Y777654D03*
X196886Y779156D03*
X206210Y771577D03*
X212350Y773283D03*
X215773Y90147D03*
X220200Y93561D03*
X226620Y89385D03*
X214320Y101978D03*
X220983Y106174D03*
X213908Y96975D03*
X219510Y101338D03*
X228138Y125802D03*
X226010Y233542D03*
X217135Y230585D03*
Y240785D03*
X216512Y258490D03*
X221784Y256315D03*
X219199Y288344D03*
X214657Y356205D03*
X223831Y359027D03*
X221280Y350255D03*
X214007Y362701D03*
X216687Y374434D03*
X222225Y364031D03*
X227745Y368007D03*
X220687Y370857D03*
X224759Y374125D03*
X214786Y388603D03*
X218090Y390891D03*
X215120Y399654D03*
X214406Y395539D03*
X223085Y401702D03*
X222419Y479933D03*
X218040Y473853D03*
X226255Y472579D03*
X227284Y502591D03*
X213209Y498353D03*
X224209Y491853D03*
X217609Y516353D03*
X219328Y528823D03*
X226909Y528053D03*
X223376Y523322D03*
X225087Y534356D03*
X215946Y544202D03*
X218950Y565589D03*
X227100Y580916D03*
X227838Y566913D03*
X219960Y596373D03*
Y601373D03*
X215699Y625977D03*
X216107Y637977D03*
X228290Y629893D03*
X218240Y674433D03*
X217530Y715305D03*
X221320Y720698D03*
X213310Y719064D03*
X222710Y713706D03*
X216820Y723301D03*
X219520Y770824D03*
X214160Y779627D03*
X226250Y785923D03*
X218270Y785657D03*
X220960Y778561D03*
X226670Y773299D03*
X243373Y88767D03*
X239563Y92077D03*
X233083Y94817D03*
X242913Y106157D03*
X233138Y125802D03*
X232948Y234047D03*
X236710Y244042D03*
X242460Y237591D03*
X237654Y249719D03*
X231710Y240242D03*
X230318Y249425D03*
X228495Y256384D03*
X236618Y270187D03*
X240567Y293811D03*
X240925Y306257D03*
X228432Y321468D03*
X230253Y328616D03*
X232873Y342946D03*
X235220Y348277D03*
X240241Y352958D03*
X228419Y356855D03*
X233635Y357082D03*
X241179Y347675D03*
X230010Y373300D03*
X237578Y369584D03*
X233136Y367070D03*
X243078Y368384D03*
X231257Y362218D03*
X236430Y393470D03*
X231461Y462591D03*
X243471Y460292D03*
X238430Y460338D03*
X228820Y467780D03*
X239700Y486907D03*
X234209Y480953D03*
X228604Y479682D03*
X234909Y489653D03*
X236909Y494453D03*
X236085Y500866D03*
X242502Y496300D03*
X240473Y549168D03*
X242834Y564253D03*
X235307Y566357D03*
X232088Y570503D03*
X241928Y570263D03*
X229269Y597682D03*
X242830Y597415D03*
X234370Y593242D03*
X242796Y589749D03*
X236780Y628738D03*
X229199Y642180D03*
X243693Y632254D03*
X238420Y642148D03*
X229584Y652668D03*
X237451Y652761D03*
X243596Y671772D03*
X229895Y671672D03*
X237275Y679609D03*
X236680Y700668D03*
X242680Y712337D03*
X234960Y714064D03*
X234910Y720816D03*
X238470Y770074D03*
X236180Y786517D03*
X242230Y774803D03*
X231460Y780174D03*
X234011Y772902D03*
X240080Y779908D03*
X258300Y22289D03*
X252683Y105867D03*
X253558Y95038D03*
X256133Y99347D03*
X248558Y95038D03*
X249453Y114307D03*
X244970Y176856D03*
X246003Y197877D03*
X254221Y230582D03*
X256492Y222466D03*
X254418Y240407D03*
X244526Y258705D03*
X256980Y299300D03*
X250469Y305798D03*
X251207Y329651D03*
X251491Y357134D03*
X246410Y348948D03*
X245258Y358468D03*
X258818Y349693D03*
X249410Y368527D03*
X244595Y363535D03*
X256331Y371006D03*
X254445Y364991D03*
X251126Y373722D03*
X254813Y427018D03*
X246465Y464893D03*
X251780Y460883D03*
X257568Y461513D03*
X246509Y486753D03*
X254999Y485763D03*
X250322Y493466D03*
X256809Y496153D03*
X244509Y491353D03*
X254809Y491153D03*
X248609Y498353D03*
X258965Y526457D03*
X255710Y574383D03*
X259678Y581553D03*
X249462Y648383D03*
X257271Y671772D03*
X244780Y682521D03*
X259170Y705138D03*
X258570Y722981D03*
X249190Y769760D03*
X256650Y770638D03*
Y778342D03*
X247900Y778823D03*
X252470Y785797D03*
X244910Y785782D03*
X271421Y7319D03*
X262955Y12663D03*
X266111Y29229D03*
X265789Y20990D03*
X268809Y16400D03*
X274990Y16396D03*
X272245Y89585D03*
X263703Y93847D03*
X262473Y106937D03*
X264980Y121886D03*
X264987Y205682D03*
X260108Y240376D03*
X267118Y245587D03*
X270260Y237037D03*
X273521Y265849D03*
X263774Y256464D03*
X272464Y259964D03*
X261024Y280657D03*
X261463Y296111D03*
X270444Y286183D03*
X268299Y306992D03*
X261915Y302033D03*
X262700Y325494D03*
X263173Y331794D03*
X260970Y343563D03*
X273871Y336662D03*
X269716Y349689D03*
X269886Y358753D03*
X260536Y374216D03*
X270293Y363972D03*
X268118Y374558D03*
X270796Y386643D03*
X263419Y393450D03*
X265162Y401391D03*
X272220Y401343D03*
X274180Y424966D03*
X266822Y443297D03*
X263807Y461234D03*
X260609Y486153D03*
X266205Y483343D03*
X272209Y485753D03*
X273841Y497993D03*
X264909Y498153D03*
X260109Y500153D03*
X263924Y491754D03*
X265009Y515555D03*
X263309Y531253D03*
X266098Y561963D03*
X269609Y576413D03*
X274309Y574653D03*
X261175Y569054D03*
X263792Y574203D03*
X268009Y570953D03*
X273480Y589201D03*
X269428Y622966D03*
X266610Y654171D03*
X261890Y664761D03*
X265550Y668415D03*
X274360Y673831D03*
X267240Y682519D03*
X269420Y677062D03*
X267124Y707892D03*
X273510Y699749D03*
X266170Y694826D03*
X260680Y712988D03*
X271210Y718000D03*
X264600Y723086D03*
X263430Y770417D03*
X275440Y770793D03*
X264340Y778780D03*
X272175Y783074D03*
X266850Y785971D03*
X269890Y773268D03*
X260000Y785233D03*
X284505Y30676D03*
X287766Y21289D03*
X278245Y31043D03*
X276603Y92119D03*
X287423Y91857D03*
X283383Y136155D03*
X284603Y210533D03*
X279161Y237817D03*
X276904Y252550D03*
X282166Y262922D03*
X278811Y259135D03*
X281767Y277742D03*
X290363Y286082D03*
X281818Y290787D03*
X284574Y305700D03*
X276282Y306927D03*
X275832Y329303D03*
X289822Y333092D03*
X281205Y340997D03*
X289191Y341348D03*
X280042Y358589D03*
X275902Y355665D03*
X277040Y376172D03*
X286550Y374402D03*
X281450Y373151D03*
X285390Y390550D03*
X287067Y402358D03*
X276626Y442913D03*
X276347Y459741D03*
X287588Y482033D03*
X284024Y502595D03*
X290323D03*
X281749Y531351D03*
X279658Y574443D03*
X285530Y573002D03*
X283650Y589044D03*
X287997Y649064D03*
X280880Y650295D03*
X278699Y656491D03*
X289365Y673719D03*
X279843Y675688D03*
X282391Y687978D03*
X275710Y681593D03*
X289248Y680521D03*
X286798Y704143D03*
X278370Y705093D03*
X277475Y695723D03*
X285130Y714433D03*
X275880Y722141D03*
X285880Y722268D03*
X280210Y734805D03*
X288390Y734796D03*
X284532Y747493D03*
X275627Y777692D03*
X281930Y773190D03*
X286722Y785929D03*
X278549Y786377D03*
X289028Y778380D03*
X301870Y92072D03*
X296870D03*
X291927Y102991D03*
X296927D03*
X302930Y132994D03*
X299776Y248010D03*
X301511Y262204D03*
X296210Y253187D03*
X292710Y266542D03*
X297810Y280709D03*
X294382Y291966D03*
X291853Y327033D03*
X305880Y339046D03*
X299410Y331201D03*
X300530Y337075D03*
X296218Y353688D03*
X295527Y359812D03*
X293290Y389737D03*
X299533Y394056D03*
X300040Y459733D03*
X298218Y478853D03*
X297370Y498563D03*
X305708Y503043D03*
X304410Y572782D03*
X294909Y578653D03*
X301796Y603917D03*
X298303Y613184D03*
X293843Y642536D03*
X297394Y657033D03*
X302772Y659604D03*
X300880Y664296D03*
X295890Y662662D03*
X295950Y689520D03*
X293068Y677108D03*
X296858Y702544D03*
X297300Y697221D03*
X293300Y718944D03*
X298590Y733669D03*
X293480Y725080D03*
X293440Y748380D03*
X291340Y771217D03*
X295100Y786269D03*
X299249Y771403D03*
X304740Y777277D03*
X297280Y778936D03*
X302440Y784731D03*
X311553Y92347D03*
X310850Y99620D03*
X320740Y98599D03*
X311290Y247249D03*
X315019Y295263D03*
X309347Y291940D03*
X309798Y306104D03*
X311740Y325839D03*
X316670Y316560D03*
X314550Y331564D03*
X318480Y335039D03*
X319288Y350376D03*
X307410Y348380D03*
X313222Y374229D03*
X321297Y367739D03*
X310484Y383312D03*
X317140Y421775D03*
X321910Y410139D03*
X320080Y512736D03*
X320094Y604114D03*
X320512Y613603D03*
X308741Y623871D03*
X311311Y618197D03*
X316183Y644594D03*
X316190Y649621D03*
Y668863D03*
X316184Y662630D03*
Y687630D03*
X316165Y693404D03*
X319620Y716403D03*
X308430Y718693D03*
X321930Y724895D03*
X314930Y724533D03*
X307146Y769416D03*
X315020Y780559D03*
X320657Y779595D03*
X320440Y771967D03*
X311440Y774049D03*
X317020Y786486D03*
X310050Y785923D03*
X335668Y92822D03*
X330668D03*
X325360Y92517D03*
X325970Y98817D03*
X327190Y103818D03*
X337630Y106304D03*
X334720Y102184D03*
X331583Y128717D03*
X331867Y291367D03*
X334622Y302861D03*
X336720Y310846D03*
X337293Y316660D03*
X327058Y358376D03*
X336850Y380332D03*
X331090Y424304D03*
X331900Y419317D03*
X336740Y417069D03*
X322986Y467109D03*
X330115Y490303D03*
X335162Y502791D03*
X326740Y495763D03*
X329672Y502057D03*
X326170Y518386D03*
X335860Y516486D03*
X329348Y533403D03*
X332408Y544097D03*
X336057Y575657D03*
X323931Y589733D03*
X323346Y621930D03*
X337070Y639759D03*
X326350Y638968D03*
X324120Y703114D03*
X332666Y706026D03*
X325560Y713391D03*
X330940Y719125D03*
X338460Y724585D03*
X328280Y770057D03*
X326280Y775980D03*
X337800Y774677D03*
X322871Y785090D03*
X349490Y57698D03*
X352578Y74292D03*
X339750Y73383D03*
X353713Y93057D03*
X344873Y94847D03*
X340450Y101914D03*
X343743Y120967D03*
X351503Y127972D03*
X343220Y280416D03*
X341693Y286010D03*
X342754Y295326D03*
X340792Y307107D03*
X339487Y301038D03*
X351650Y420270D03*
X345270Y452745D03*
X339506Y482841D03*
X348220Y486484D03*
X348870Y501571D03*
X343420Y497966D03*
X340902Y503742D03*
X341512Y512429D03*
X350902Y512520D03*
X346350Y517286D03*
X351964Y599332D03*
X351720Y644191D03*
X348480Y638558D03*
X351730Y649206D03*
Y675057D03*
Y663450D03*
X351720Y670018D03*
X339300Y716800D03*
X342230Y720936D03*
X344710Y785782D03*
X350450Y784982D03*
X338642Y785716D03*
X343370Y779720D03*
X345100Y771906D03*
X350630Y777187D03*
X363025Y12926D03*
X366159Y21822D03*
X361930Y60031D03*
X367300Y60442D03*
X367776Y91746D03*
X358343Y90948D03*
X361470Y101757D03*
X367350Y123927D03*
X356835Y313894D03*
X367220Y303202D03*
X369934Y322946D03*
X364580Y391273D03*
X365850Y414874D03*
X354565Y451562D03*
X354750Y445325D03*
X369507Y464391D03*
X368825Y539776D03*
X361473Y620588D03*
X364950Y639095D03*
X365990Y645272D03*
X367870Y650239D03*
X364980Y655266D03*
X363340Y650512D03*
X365620Y663069D03*
X365380Y668972D03*
X364765Y687963D03*
X365090Y676923D03*
X364115Y692990D03*
X367520Y701710D03*
X357830Y718682D03*
X364750Y727821D03*
X364090Y748565D03*
X357610Y748302D03*
X354870Y771388D03*
X360160Y775523D03*
X363300Y781303D03*
X367904Y778327D03*
X356600Y782086D03*
X362264Y786424D03*
X381907Y21507D03*
X383280Y59940D03*
X376006Y60991D03*
X372776Y91746D03*
X380483Y99047D03*
X378733Y105987D03*
X384863Y95437D03*
X378183Y124904D03*
X372080Y330574D03*
X382190Y388077D03*
X371260Y412879D03*
X371950Y430527D03*
X375190Y463996D03*
X381239Y467171D03*
X371080Y481589D03*
X376540Y498385D03*
X383617Y517862D03*
X376528Y520138D03*
X379733Y549392D03*
X370309Y550322D03*
X382333Y540414D03*
X385573Y629998D03*
X373218Y634217D03*
X382580Y637413D03*
X385145Y652326D03*
X383627Y646254D03*
X379492Y650239D03*
X376089Y646156D03*
X373680Y662417D03*
X376087Y670156D03*
X379461Y675246D03*
X384868Y675433D03*
X379462Y666156D03*
X377673Y686355D03*
X377682Y681355D03*
X377681Y694244D03*
X377679Y701168D03*
X377669Y706237D03*
X372360Y704766D03*
X376770Y734898D03*
X373500Y748457D03*
X370130Y770105D03*
X373370Y783928D03*
X397655Y21336D03*
X397790Y61360D03*
X390355Y75775D03*
X392493Y92647D03*
X400163Y99177D03*
X391310Y99570D03*
X398088Y128455D03*
X393088D03*
X399598Y260251D03*
X398258Y252341D03*
X394378Y260501D03*
X393458Y282931D03*
X392508Y275581D03*
X398038Y292571D03*
X390080Y331575D03*
X395740Y407528D03*
X392076Y470970D03*
X388982Y496939D03*
X396558Y522251D03*
X396470Y527847D03*
X396590Y549310D03*
X399590Y553502D03*
X393596Y567630D03*
X401191Y603637D03*
X391447Y611973D03*
X394389Y604053D03*
X399223Y644930D03*
X394380Y643389D03*
X389856Y645705D03*
X391790Y715248D03*
X400730Y721954D03*
X410713Y76187D03*
X417248Y266301D03*
X404738Y260421D03*
X403148Y270191D03*
X403628Y292201D03*
X406352Y471405D03*
X410607Y485620D03*
X413138Y504813D03*
X407865Y516627D03*
X412088Y521721D03*
X407776Y527426D03*
X405954Y532502D03*
X404336Y545280D03*
X411058Y545353D03*
X408486Y537333D03*
X408736Y551529D03*
X413342Y556219D03*
X412783Y605500D03*
X416454Y621319D03*
X413105Y613739D03*
X403904Y618333D03*
X403970Y642364D03*
X406100Y631851D03*
X413535Y646804D03*
X411982Y660285D03*
X413718Y655267D03*
X415218Y664203D03*
X411675Y672654D03*
X411065Y667516D03*
X416938Y669947D03*
X414183Y686151D03*
X413643Y680004D03*
X414318Y700979D03*
X414080Y721334D03*
X409010Y726147D03*
X415780Y747078D03*
X414130Y779689D03*
X421893Y123537D03*
X421640Y223403D03*
X428405Y245194D03*
X424961Y241203D03*
X418905Y245694D03*
X426992Y250016D03*
X422528Y253531D03*
X426335Y267062D03*
X420858Y261331D03*
X427817Y258829D03*
X421728Y279141D03*
X428748Y275222D03*
X418588Y286681D03*
X421128Y292601D03*
X423178Y284601D03*
X427909Y286759D03*
X427468Y292287D03*
X428747Y463314D03*
Y468770D03*
X422050Y517028D03*
X418660Y541421D03*
X428039Y548119D03*
X421461Y547703D03*
X420883Y556729D03*
X431145Y556608D03*
X429340Y596874D03*
X431520Y607039D03*
X432180Y647458D03*
X425334Y656419D03*
X421080Y665945D03*
X418381Y690878D03*
X427230Y707377D03*
X429240Y721014D03*
X422010Y766690D03*
X421690Y779548D03*
X417880Y786361D03*
X425540Y786506D03*
X431290Y785484D03*
X428250Y772054D03*
X426900Y779752D03*
X417552Y772874D03*
X446920Y78358D03*
X447715Y97926D03*
X444550Y184057D03*
X441580Y250730D03*
X443212Y240957D03*
X441792Y259473D03*
X445890Y283317D03*
X443240Y401984D03*
X437887Y471073D03*
X444920Y485259D03*
X437716Y476295D03*
X445199Y494590D03*
X439749Y506523D03*
X439762Y515540D03*
Y523757D03*
X434605Y521488D03*
X445838Y538085D03*
X441063Y540563D03*
X437832Y556374D03*
X442240Y553337D03*
X435319Y600123D03*
X437120Y612933D03*
X448460Y625960D03*
X437509Y648996D03*
X444700Y651900D03*
X447210Y665143D03*
X447161Y673564D03*
X444458Y669350D03*
X440688Y684438D03*
X442920Y678095D03*
X440688Y689438D03*
X440690Y702386D03*
X440688Y694438D03*
X440660Y712065D03*
X436560Y770904D03*
X444370Y770152D03*
X434540Y778500D03*
X442100Y777623D03*
X446510Y784890D03*
X441006Y785297D03*
X458120Y44721D03*
X464170Y56436D03*
X461594Y99342D03*
X449538Y105144D03*
X453940Y98586D03*
X461880Y150596D03*
X462790Y183489D03*
X450650Y203785D03*
X450576Y234431D03*
X453620Y245162D03*
X451790Y300129D03*
X451504Y529734D03*
X450540Y521331D03*
X463991Y531504D03*
X456722Y529536D03*
X463031Y543563D03*
X453917Y550069D03*
X450367Y540720D03*
X453700Y545047D03*
X453854Y555069D03*
X462270Y612911D03*
X464050Y633877D03*
X458903Y644884D03*
X463178Y647483D03*
X460587Y669424D03*
X457138Y663251D03*
X449060Y721761D03*
X461565Y785806D03*
X463750Y780452D03*
X454120Y785923D03*
X454399Y771873D03*
X457530Y779016D03*
X449610Y777933D03*
X475030Y63879D03*
X470324Y133424D03*
X474813Y162220D03*
X467473Y159766D03*
X473951Y157235D03*
X473950Y172124D03*
X475770Y186451D03*
X471300Y201900D03*
X466200Y207300D03*
X464810Y311253D03*
X480118Y479107D03*
Y474107D03*
X471804Y561085D03*
Y556085D03*
X468740Y585897D03*
X469890Y596580D03*
X476320Y629280D03*
X469229Y638135D03*
X475820Y635422D03*
X468810Y652180D03*
X479512Y649436D03*
X466980Y667059D03*
X479354Y677054D03*
X466070Y774997D03*
X469360Y780411D03*
X475620Y779095D03*
X478290Y786393D03*
X471780Y786300D03*
X486810Y60785D03*
X488438Y109623D03*
X494355Y108674D03*
X490175Y122348D03*
X484350Y112811D03*
X487857Y152147D03*
X492424Y142234D03*
X494467Y148867D03*
X490130Y163086D03*
X493670Y171871D03*
X489040Y169483D03*
X482980Y181071D03*
X488850Y175419D03*
X487839Y194142D03*
X488017Y203716D03*
X486370Y189279D03*
X492700Y223800D03*
X484169Y272867D03*
X486300Y422150D03*
X481300D03*
X482880Y467935D03*
Y462935D03*
X490334Y497342D03*
X483209Y545250D03*
Y550250D03*
X490661Y547148D03*
X489962Y540849D03*
X483838Y566194D03*
Y556148D03*
Y561148D03*
Y571194D03*
X485738Y587125D03*
X490738D03*
X481340Y593296D03*
X494238Y600441D03*
X490600Y608136D03*
X489800Y600200D03*
X487832Y624429D03*
X480310Y642224D03*
X481253Y654837D03*
X484700Y660355D03*
X482398Y673087D03*
X482544Y668042D03*
X490120Y662703D03*
X481227Y685366D03*
Y691366D03*
X490900Y706145D03*
X481227Y696366D03*
X495560Y694781D03*
X488180Y719244D03*
X490890Y714898D03*
X488090Y710545D03*
X488250Y786657D03*
X480770Y778125D03*
X485870Y776087D03*
X491720Y776713D03*
X495110Y771733D03*
X502900Y57670D03*
X500310Y109211D03*
X497430Y124024D03*
X504750Y111749D03*
X509691Y112938D03*
X509710Y127269D03*
X500215Y136449D03*
X502183Y156709D03*
X496360Y167221D03*
X498940Y179744D03*
X510000Y173500D03*
X509100Y191900D03*
X499225Y205296D03*
X506234Y207368D03*
X498867Y227773D03*
X504160Y255584D03*
X497111Y388567D03*
X502111D03*
X505819Y417473D03*
X498238Y417825D03*
X499551Y429636D03*
X502494Y436725D03*
X509486Y433829D03*
X506456Y446928D03*
X502938Y463823D03*
X498119Y470011D03*
X511230Y499059D03*
X506230D03*
X504613Y525200D03*
X503338Y549825D03*
Y544825D03*
X500538Y588525D03*
Y600925D03*
X508400Y617803D03*
X502080Y622999D03*
X505690Y654419D03*
X508061Y645381D03*
X504295Y649612D03*
X504114Y670830D03*
X496453Y670876D03*
X501914Y675624D03*
X504241Y665809D03*
X497320Y665216D03*
X496577Y684553D03*
X505580Y679105D03*
X496277Y678185D03*
X501540Y681970D03*
X506409Y691373D03*
X497350Y699767D03*
X506092Y697575D03*
X501604Y733003D03*
X501890Y746663D03*
X497880Y785893D03*
X509000Y775415D03*
X502480Y782382D03*
X507935Y785704D03*
X511770Y779940D03*
X499270Y776431D03*
X504440Y772548D03*
X513120Y72069D03*
X512878Y108635D03*
X519625Y108543D03*
X526835Y108314D03*
X516146Y113121D03*
X522111Y113310D03*
X518640Y125539D03*
X514510Y133093D03*
X522448Y137674D03*
X523100Y153100D03*
X512600Y147500D03*
X523100Y159400D03*
X515600Y172800D03*
X521320Y178184D03*
X516100Y178100D03*
X526621Y177079D03*
X515231Y191334D03*
X520015Y194584D03*
X523593Y198171D03*
X512200Y196000D03*
X520068Y207142D03*
X516551Y214987D03*
X517670Y247527D03*
X515675Y254098D03*
X525480Y268959D03*
X527438Y340353D03*
X517617Y422944D03*
X514820Y417617D03*
X526440Y422428D03*
X527300Y417368D03*
X517929Y439676D03*
X512867Y443679D03*
X525638Y484023D03*
X524848Y548755D03*
X513998Y568675D03*
X525808Y582665D03*
X514058Y605055D03*
X526300Y623621D03*
X518920Y615387D03*
X514320Y641085D03*
X525692Y654862D03*
X517328Y655529D03*
X521516Y650576D03*
X517222Y673917D03*
X518800Y665776D03*
X515541Y661845D03*
X526430Y664730D03*
X515429Y692278D03*
X526600Y679117D03*
X517888Y687901D03*
X527111Y686052D03*
X515429Y697278D03*
X512548Y722093D03*
X512610Y747115D03*
X519560Y779689D03*
X514430Y785721D03*
X525110Y774395D03*
X519440Y772861D03*
X523683Y786110D03*
X539510Y108742D03*
X536955Y100257D03*
X535960Y112850D03*
X527613Y113373D03*
X538968Y168838D03*
X539500Y196500D03*
X536232Y192086D03*
X529592Y192999D03*
X533474Y196500D03*
X541657Y207645D03*
X532320Y209470D03*
X534208Y227832D03*
X528105Y230594D03*
X535772Y250076D03*
X539267Y267102D03*
X530119Y280101D03*
X533913Y402151D03*
X541650Y422280D03*
X529968Y440216D03*
X529028Y430469D03*
X535352Y440414D03*
X540141Y442994D03*
X537378Y564875D03*
X529408Y603485D03*
X542848Y602975D03*
X535048Y602885D03*
X532420Y615484D03*
X542424Y654821D03*
X536557Y655498D03*
X529525Y669349D03*
X529899Y661020D03*
X539734Y675020D03*
X539577Y721891D03*
X540062Y708779D03*
X531557Y786392D03*
X537320Y786298D03*
X539650Y780942D03*
X529300Y771341D03*
X543075Y775577D03*
X533600Y778780D03*
X527620Y781318D03*
X557995Y110244D03*
X550490Y112989D03*
X552173Y138528D03*
X550599Y132596D03*
X550550Y151682D03*
X558059Y154254D03*
X558348Y142511D03*
X551464Y143862D03*
X550604Y168072D03*
X550370Y157461D03*
X557668Y176534D03*
X551395Y174172D03*
X544500Y197500D03*
X546000Y192000D03*
X557909Y207537D03*
X547148Y220220D03*
X554663Y230782D03*
X545703Y245725D03*
X545981Y236287D03*
X545116Y266847D03*
X547929Y258102D03*
X545223Y276895D03*
X557207Y280328D03*
X555072Y289563D03*
X552090Y388953D03*
X553230Y407251D03*
X549574Y432582D03*
X546384Y445107D03*
X547488Y452373D03*
X554550Y469674D03*
X545513Y469740D03*
X547638Y462356D03*
X546038Y457523D03*
X546250Y490302D03*
X554860Y531701D03*
X549920Y527242D03*
X550149Y604639D03*
X543400Y625963D03*
X552350Y614028D03*
X558281Y637840D03*
X551030Y637200D03*
X543400Y635615D03*
X549314Y647594D03*
X551230Y652844D03*
X551283Y670800D03*
Y699243D03*
X544934Y720820D03*
X550535Y721903D03*
X555551Y722342D03*
X557488Y713709D03*
X553725Y717251D03*
X550004Y709559D03*
X555062Y708679D03*
X545062D03*
X557978Y734053D03*
X545300Y783152D03*
X550940Y771858D03*
X554870Y779438D03*
X549350Y777416D03*
X552830Y785015D03*
X558360Y775757D03*
X569559Y103123D03*
X566105Y112518D03*
X564076Y145372D03*
X563410Y165289D03*
X562195Y159015D03*
X563129Y178369D03*
X569682Y195199D03*
X563775Y227018D03*
X564274Y279395D03*
X561525Y298192D03*
X560865Y285434D03*
X565953Y301635D03*
X565310Y412700D03*
X572440Y464323D03*
Y469323D03*
X562340Y484252D03*
X567791Y528325D03*
X562308Y536895D03*
X566298Y548465D03*
X563188Y541925D03*
X566338Y554235D03*
X561174Y564471D03*
X574738Y579525D03*
X565858Y576195D03*
X561198Y581793D03*
X566378Y567725D03*
X561608Y571775D03*
X574537Y591325D03*
X565398Y584765D03*
X568163Y595115D03*
X561568Y589355D03*
X574071Y606204D03*
X568930Y607754D03*
X574730Y625521D03*
X565647Y637705D03*
X565556Y632431D03*
X571790Y646799D03*
X559440Y650767D03*
X566950Y659439D03*
X571494Y663571D03*
X565168Y664614D03*
Y674614D03*
Y669614D03*
Y684614D03*
Y679614D03*
Y689614D03*
Y694614D03*
Y699614D03*
X560544Y718091D03*
X569604Y721248D03*
X574190Y717805D03*
X564319Y721587D03*
X562540Y713454D03*
X560062Y708679D03*
X570614Y713237D03*
X565062Y708679D03*
X566798Y734023D03*
X569680Y771106D03*
X560150Y781347D03*
X571230Y785131D03*
X562700Y772391D03*
X572720Y777184D03*
X567210Y778530D03*
X563053Y785792D03*
X578938Y103123D03*
X580501Y138336D03*
X583829Y132232D03*
X587968Y138765D03*
X581565Y154969D03*
X579897Y161355D03*
X582792Y167632D03*
X581915Y179955D03*
X588692Y192809D03*
X585580Y210516D03*
X579707Y229395D03*
X585579Y230095D03*
X585874Y281995D03*
X588607Y305034D03*
X576650Y311446D03*
X581650D03*
X585984Y323246D03*
X589070Y423525D03*
X578830Y448192D03*
X585013Y547959D03*
X576208Y542405D03*
X575838Y548935D03*
X577778Y556355D03*
X588780Y611056D03*
X586810Y603344D03*
X588780Y616056D03*
X583930Y652439D03*
X577217Y652002D03*
X576987Y660180D03*
X580637Y663629D03*
X584312Y710716D03*
X583440Y724927D03*
X577570Y734118D03*
X586676Y786016D03*
X583880Y779251D03*
X578330Y785014D03*
X587170Y773768D03*
X579240Y775147D03*
X605070Y123991D03*
X600118Y112568D03*
X592938Y117657D03*
Y140689D03*
Y133232D03*
X594938Y127893D03*
X591707Y230162D03*
X595374Y236795D03*
X594374Y271395D03*
X596574Y276393D03*
X593607Y305034D03*
X590984Y323246D03*
X604338Y338285D03*
X597440Y391690D03*
X590720Y456076D03*
X591100Y450128D03*
X605800Y463167D03*
X603819Y485332D03*
X605798Y501238D03*
X596751Y532108D03*
X603010Y527908D03*
X604820Y555040D03*
X592437Y566543D03*
X601043Y567781D03*
X605396Y590552D03*
X605286Y584152D03*
X593867Y595695D03*
X602314Y607641D03*
Y602641D03*
X593867Y600695D03*
X605430Y622721D03*
X591279Y656223D03*
X596998Y658008D03*
X600736Y668425D03*
X600719Y675156D03*
X597300Y663128D03*
X600690Y691896D03*
X600727Y681876D03*
Y686876D03*
X604220Y703774D03*
X592960Y703291D03*
X601856Y711479D03*
X595950Y708997D03*
X594170Y719290D03*
X603938Y753623D03*
X602424Y778468D03*
X591460Y780096D03*
X596590Y786204D03*
X606270Y774615D03*
X597530Y780191D03*
X592480Y771514D03*
X610543Y107678D03*
X617925Y114064D03*
X613432Y153528D03*
X610415Y237441D03*
X617474Y246495D03*
X617778Y238873D03*
X617274Y257595D03*
X617374Y262695D03*
X613640Y336986D03*
X607671Y344818D03*
X611848Y359784D03*
X607855Y352341D03*
X618581Y354818D03*
X620238Y364369D03*
X609078Y388557D03*
Y393557D03*
X612641Y397478D03*
Y402478D03*
X611050Y423087D03*
X616258Y422211D03*
X610580Y448662D03*
X610010Y456581D03*
X617980Y460408D03*
X621760Y526967D03*
X613470Y537495D03*
X610070Y557588D03*
X610821Y566494D03*
X621937Y567143D03*
X609026Y579132D03*
X617270Y580443D03*
X611520Y596594D03*
X611254Y617943D03*
X615690Y625536D03*
X616730Y633290D03*
X611572Y629894D03*
X613796Y648705D03*
X612950Y656140D03*
X613200Y661577D03*
X620160Y670594D03*
X615940Y666862D03*
X616031Y675149D03*
X612670Y681438D03*
X620180Y678321D03*
X612811Y688422D03*
X607380Y699671D03*
X617930Y703520D03*
X615510Y692781D03*
X620480Y693827D03*
X609070Y721917D03*
X613730Y717663D03*
X620670Y722216D03*
X606940Y716692D03*
X618270Y713344D03*
X619080Y772610D03*
X619030Y778682D03*
X622030Y786047D03*
X606361Y785390D03*
X612260Y783106D03*
X609347Y778624D03*
X628838Y120216D03*
X628738Y133012D03*
X624800Y184953D03*
Y179953D03*
X623301Y200144D03*
Y194544D03*
X634962Y200121D03*
Y195121D03*
X634212Y281670D03*
X624383Y292591D03*
X631672Y301066D03*
X633773Y310439D03*
X628141Y344818D03*
X634511Y389156D03*
X630691Y405007D03*
Y410007D03*
X636586Y410910D03*
X635840Y449890D03*
X634945Y461888D03*
X628250Y471142D03*
X630420Y491511D03*
X636170Y493028D03*
X622600Y488753D03*
X622199Y506535D03*
X632157Y511230D03*
X625130Y534199D03*
X634530Y521565D03*
X634190Y538267D03*
X636890Y571351D03*
X624870Y573143D03*
X627084Y578257D03*
X634921Y580163D03*
X623940Y628720D03*
X636890Y627095D03*
X629781Y628559D03*
X622510Y635544D03*
X634137Y631342D03*
X627146Y638932D03*
X626340Y668853D03*
X633970Y723033D03*
X628160Y722343D03*
X632530Y716788D03*
X636170Y729335D03*
X632300Y749755D03*
X636910Y745815D03*
X624010Y746351D03*
X629912Y769200D03*
X625010Y778281D03*
X639200Y170100D03*
X639350Y250123D03*
X649995Y296433D03*
X640647Y339854D03*
X639838Y349818D03*
X648425Y373474D03*
X652139Y377125D03*
X641236Y381616D03*
X645236Y377858D03*
X650822Y425295D03*
X647280Y446851D03*
X651080Y455238D03*
X652110Y465238D03*
X646600Y463571D03*
X648956Y469323D03*
X650521Y482930D03*
X647921Y475778D03*
X646105Y492010D03*
X650790Y497730D03*
X646906Y505210D03*
X646460Y512967D03*
X652690Y531693D03*
X645040Y524444D03*
X639673Y576888D03*
X651437Y578943D03*
X653301Y585683D03*
X644636Y627257D03*
X646940Y643448D03*
X641263Y631393D03*
X649173Y629876D03*
X647870Y649784D03*
X646580Y654775D03*
X641630Y668783D03*
X647370Y668643D03*
X643740Y716004D03*
X643970Y722649D03*
X645400Y734600D03*
X650160Y733395D03*
X652660Y749000D03*
X640956Y750643D03*
X646680Y755009D03*
X646500Y746300D03*
X638470Y762212D03*
X647410Y767053D03*
X651690Y778099D03*
X640010Y778215D03*
X644110Y773108D03*
X655947Y53677D03*
X655642Y144915D03*
Y149915D03*
X655695Y159567D03*
Y164567D03*
X655030Y228744D03*
Y223744D03*
X657838Y243407D03*
Y238407D03*
X660899Y311515D03*
X654962Y307698D03*
X668925Y364887D03*
X663632Y366698D03*
X669215Y377488D03*
X655812Y424106D03*
X664450Y435739D03*
X664528Y463432D03*
X660458Y470932D03*
X659828Y465162D03*
X667774Y477992D03*
X661158Y486152D03*
X667070Y483608D03*
X662780Y477039D03*
X660518Y492862D03*
X654240Y511568D03*
X653800Y505331D03*
X659933Y513927D03*
X668573Y514155D03*
X659740Y536019D03*
X667050Y535324D03*
X658980Y610043D03*
X663560Y625019D03*
X654221Y631425D03*
X657550Y655072D03*
X669203Y673040D03*
X653870Y668979D03*
X658220Y671797D03*
X659978Y666274D03*
X657340Y690286D03*
X659300Y734119D03*
X657500Y761500D03*
X656970Y772761D03*
X669987Y53672D03*
X679590Y352829D03*
X677083Y375124D03*
X673368Y416621D03*
X671056Y426300D03*
X673740Y449887D03*
X682764Y444832D03*
X677070Y444820D03*
X679299Y491473D03*
X674156Y503662D03*
X677160Y529422D03*
X675044Y524581D03*
X678386Y668420D03*
X673386D03*
X681480Y777388D03*
X681164Y783461D03*
X669810Y786721D03*
X672500Y779579D03*
X687546Y154228D03*
X689480Y194615D03*
X687869Y386780D03*
X688118Y381043D03*
X685859Y403970D03*
X691037Y401739D03*
X696070Y458901D03*
X700590Y462272D03*
X689017Y497282D03*
X694823Y498932D03*
X689729Y509580D03*
X696891Y507279D03*
X686770Y543325D03*
X691532Y563789D03*
Y575789D03*
Y583789D03*
X685640Y634154D03*
X698386Y667241D03*
X693386D03*
X699600Y776000D03*
X689700Y774500D03*
X711676Y51019D03*
X712239Y452293D03*
X704550Y444407D03*
X704766Y498880D03*
X713978Y498075D03*
X716021Y516945D03*
X700829Y504041D03*
X707920Y505575D03*
X706361Y532632D03*
X716260Y525295D03*
X712740Y593101D03*
X713742Y634373D03*
X708386Y669774D03*
X703386D03*
X713445Y677641D03*
X704000Y770800D03*
X731566Y442136D03*
X726580Y455637D03*
X731570Y464043D03*
X726830Y460815D03*
X727940Y469943D03*
X720140Y478333D03*
X719761Y532432D03*
X727830Y641829D03*
X728690Y649829D03*
X718445Y677641D03*
X736310Y450774D03*
X737350Y464330D03*
X734575Y492575D03*
X745500Y492500D03*
X744020Y566143D03*
X743951Y578833D03*
X744050Y571834D03*
X740430Y616409D03*
X744000Y647919D03*
X733210Y645829D03*
X732540Y653829D03*
X758223Y446532D03*
X748723Y455332D03*
X752960Y653967D03*
X771110Y578643D03*
X770850Y587025D03*
G54D20*
X23628Y321764D03*
Y338300D03*
X45282Y321764D03*
G54D11*
G01X110230Y360735D02*
X109780Y361185D01*
X83395D01*
X64000Y380580D01*
Y395967D01*
X55388Y404579D01*
X41796D01*
X32840Y413535D01*
Y479772D01*
X27880Y484732D01*
Y520137D01*
X34064Y526321D01*
X43868D01*
X46256Y523933D01*
X52313D01*
X53657Y522589D01*
X62253D01*
G01X110230Y363235D02*
X109780Y362785D01*
X84058D01*
X65600Y381243D01*
Y396637D01*
X56058Y406179D01*
X42459D01*
X34440Y414198D01*
Y480435D01*
X29480Y485395D01*
Y519474D01*
X29483D01*
X34730Y524721D01*
X43202D01*
X45590Y522333D01*
X48041D01*
X49857Y520517D01*
Y520516D01*
G01X65554Y527977D02*
Y524808D01*
X67369Y522993D01*
G01X203520Y327969D02*
X203720Y330961D01*
X200905Y333776D01*
G01X197015Y708156D02*
X201336D01*
X201411Y708231D01*
G01X217564Y249954D02*
X217852Y250242D01*
Y253573D01*
X218863Y254584D01*
X220413D01*
X221784Y255955D01*
Y256315D01*
G01X225445Y247519D02*
X229010D01*
X230318Y248827D01*
Y249425D01*
G01X225445Y251519D02*
X228495Y254569D01*
Y256384D01*
G01X225973Y259197D02*
X223637D01*
X221784Y257344D01*
Y256315D01*
G01X230318Y249425D02*
Y253687D01*
X230940Y254309D01*
Y258330D01*
X231749Y259139D01*
G01X228495Y256384D02*
Y258886D01*
X231748Y262139D01*
X231749D01*
G01X227718Y277838D02*
Y275300D01*
X228821Y274197D01*
G01X230718Y277838D02*
Y275173D01*
X231648Y274243D01*
G01X283660Y251542D02*
X285022Y250180D01*
X286563D01*
G01X421640Y228403D02*
X419940Y226703D01*
X315758D01*
X292906Y249555D01*
X290338D01*
X289713Y250180D01*
G01X421640Y223403D02*
X419940Y225103D01*
X315095D01*
X292243Y247955D01*
X291114D01*
X289959Y246800D01*
G01X298160Y736489D02*
X298174D01*
X299440Y737755D01*
Y739081D01*
G01X321987Y539202D02*
X322751Y538438D01*
X330060D01*
X332408Y540786D01*
Y544097D01*
G01X315957Y594127D02*
X329627D01*
X333070Y597570D01*
Y624739D01*
X326398Y631411D01*
X312267D01*
X308741Y627885D01*
Y623871D01*
G01X322440Y696731D02*
Y700130D01*
G01X351728Y653860D02*
X350846Y654742D01*
X345468D01*
G01X353902Y667128D02*
X353574Y667456D01*
X349768D01*
X348650Y668574D01*
X345440D01*
Y668581D01*
G01X568215Y702343D02*
Y698575D01*
X569559Y697231D01*
X571440D01*
G01X590570Y663828D02*
Y667457D01*
X592194Y669081D01*
X594440D01*
X-44872Y125213D03*
Y141213D03*
Y232533D03*
D03*
Y248533D03*
D03*
Y738493D03*
Y754493D03*
X-26872Y125213D03*
Y141213D03*
Y232533D03*
D03*
Y248533D03*
D03*
Y738493D03*
Y754493D03*
X434102Y232640D03*
Y311875D03*
G54D30*
X76880Y143269D03*
X739968Y29361D03*
G54D21*
X36024Y187233D03*
Y181225D03*
Y205257D03*
Y199249D03*
Y193241D03*
Y217272D03*
Y211264D03*
X41930Y178221D03*
Y202253D03*
Y196245D03*
Y190237D03*
Y220276D03*
Y214268D03*
Y208260D03*
G54D12*
G01X146380Y20345D02*
Y19722D01*
X138108Y11450D01*
X107770D01*
X102465Y6145D01*
X29820D01*
X23987Y11978D01*
Y12977D01*
G01X62404Y527977D02*
X55238D01*
X54117Y529098D01*
G01X74058Y389621D02*
X78211Y385468D01*
X91104D01*
X98760Y377812D01*
Y377739D01*
X103151Y373348D01*
Y373340D01*
G01X73868Y397913D02*
X71531Y395576D01*
Y392148D01*
X74058Y389621D01*
G01X70925Y807872D02*
Y791695D01*
G01X82736Y807872D02*
Y791695D01*
G01D02*
Y788695D01*
G01X70925Y791695D02*
Y788695D01*
G01X94547Y807872D02*
Y791695D01*
G01D02*
Y788695D01*
G01X117030Y389978D02*
Y387219D01*
X103151Y373340D01*
G01X114232Y807872D02*
Y791695D01*
G01D02*
Y788695D01*
G01X130195Y19162D02*
X121300Y28057D01*
Y62762D01*
X138347Y79809D01*
X139310Y78847D01*
X141390D01*
Y78851D01*
X142562Y80023D01*
X168420D01*
X171731Y76712D01*
X256717D01*
X263596Y69833D01*
X336200D01*
X339750Y73383D01*
G01X146380Y20345D02*
Y20874D01*
X144896Y22358D01*
X133818D01*
X124570Y31606D01*
Y60180D01*
X135111Y70721D01*
X168317D01*
X170270Y72674D01*
X254901D01*
X261348Y66227D01*
X356702D01*
X358530Y64399D01*
Y59133D01*
X362472Y55191D01*
X408369D01*
X433890Y80712D01*
X442086D01*
X443130Y81756D01*
X454809D01*
X458598Y77967D01*
G01X146380Y20345D02*
X149963D01*
X150592Y20974D01*
G01X145880Y584125D02*
X147735Y582270D01*
Y581013D01*
G01Y577105D02*
X146124D01*
X145020Y576001D01*
G01X147735Y573105D02*
X143252D01*
G01X141190Y597685D02*
X144738Y594137D01*
X147688D01*
G01X147655Y598135D02*
X144710D01*
G01X141791Y807872D02*
Y791695D01*
G01D02*
Y788695D01*
G01X154307Y507507D02*
X153578Y506778D01*
X150709D01*
G01X155109Y561153D02*
X155309Y561353D01*
Y564853D01*
G01X151900Y590454D02*
X154119Y588235D01*
X154755D01*
G01X157905D02*
X160368D01*
X160699Y587904D01*
G01X163330Y589860D02*
X162655D01*
X160699Y587904D01*
G01X157355Y605135D02*
X155514D01*
X153422Y603043D01*
G01X169330Y589860D02*
X168605D01*
X166605Y587860D01*
G01X176263Y589958D02*
X176307D01*
X178416Y587849D01*
G01X173287Y807872D02*
Y791695D01*
G01D02*
Y788695D01*
G01X187970Y383876D02*
X184927D01*
G01X184384Y537656D02*
X185634Y538906D01*
Y540853D01*
G01X193505Y594735D02*
X196630D01*
X197230Y595335D01*
G01X183330Y590060D02*
Y589535D01*
X181330Y587535D01*
G01X193505Y607835D02*
X194084D01*
X196907Y605012D01*
G01X193538Y603833D02*
X195728D01*
X196907Y605012D01*
G01X193538Y598933D02*
X196632D01*
X197030Y598535D01*
G01X193505Y614735D02*
X196530D01*
X197230Y615435D01*
G01X193538Y623033D02*
X194028D01*
X197130Y626135D01*
G01X193505Y627135D02*
X196130D01*
X197130Y626135D01*
G01X187798Y704513D02*
X188795Y703516D01*
Y701936D01*
G01X196144Y712602D02*
X194440Y714306D01*
Y714898D01*
G01X191930Y712624D02*
X189940Y714614D01*
Y714931D01*
G01X185440D02*
Y712499D01*
G01X194440Y735623D02*
Y739081D01*
G01X185440D02*
Y735681D01*
G01X189940Y739081D02*
Y735681D01*
G01X198653Y284796D02*
X198648D01*
Y288013D01*
X197468Y289193D01*
G01X208687Y382271D02*
Y384201D01*
X205885Y387003D01*
X205790D01*
G01X212709Y483278D02*
X208209D01*
G01D02*
X206384Y481453D01*
X203509D01*
G01X210023Y712842D02*
X207940Y714925D01*
Y714931D01*
G01X201663Y712694D02*
Y712683D01*
X203440Y714460D01*
Y714898D01*
G01X198940Y714931D02*
Y712499D01*
G01Y735681D02*
Y739081D01*
G01X207940Y735681D02*
Y739081D01*
G01X203440D02*
Y735681D01*
G01X200846Y791695D02*
Y788695D01*
G01Y807872D02*
Y791695D01*
G01X220276Y88440D02*
X221590Y87126D01*
Y84629D01*
G01X224108Y388029D02*
X224176D01*
X226131Y386074D01*
Y383715D01*
X224687Y382271D01*
G01X216687D02*
X216633Y382325D01*
Y384989D01*
G01X212709Y483278D02*
X216709D01*
G01D02*
X219634D01*
G01X224209Y494928D02*
X227942D01*
X228689Y494181D01*
G01X227343Y498103D02*
Y502532D01*
X227284Y502591D01*
G01X225940Y727581D02*
Y724061D01*
G01X221440Y739081D02*
Y735934D01*
G01X216940Y730731D02*
Y736063D01*
G01X212440Y739081D02*
Y735829D01*
G01X220532Y791695D02*
Y788695D01*
G01Y807872D02*
Y791695D01*
G01X241979Y469728D02*
Y472483D01*
X241909Y472553D01*
G01X235319Y467118D02*
Y464362D01*
G01X241909Y474978D02*
Y472553D01*
G01X243900Y724662D02*
Y727541D01*
X243940Y727581D01*
G01X234940D02*
Y724325D01*
G01X230440Y739081D02*
Y736412D01*
G01X239440Y739081D02*
Y736140D01*
G01X240217Y791695D02*
Y788695D01*
G01Y807872D02*
Y791695D01*
G01X256532Y384895D02*
Y382510D01*
X256490Y382468D01*
X256687Y382271D01*
G01X263419Y393450D02*
X262021Y392052D01*
X258687D01*
G01X255509Y472253D02*
Y469128D01*
G01X251309Y472553D02*
Y469228D01*
G01X246089Y475029D02*
Y472485D01*
X246109Y472465D01*
G01X255509Y474978D02*
Y472253D01*
G01X251309Y474978D02*
Y472553D01*
G01X255673Y565580D02*
X255100Y566153D01*
X253239D01*
G01X255673Y562431D02*
X255095Y561853D01*
X253239D01*
G01X250109Y577909D02*
Y579015D01*
X252036Y580942D01*
Y582131D01*
G01X244498Y703150D02*
X250795D01*
G01X252940Y739081D02*
Y736318D01*
G01X257440Y739081D02*
Y736041D01*
G01X248440Y739081D02*
Y736163D01*
G01X267703Y89397D02*
Y97337D01*
X269625Y99259D01*
Y100289D01*
G01Y103439D02*
Y107005D01*
X268702Y107928D01*
G01X272953Y114152D02*
X268953D01*
G01X273477Y385100D02*
X273128Y384751D01*
G01X272687Y383694D02*
Y382271D01*
G01X260687D02*
Y384217D01*
X261663Y385193D01*
G01X269209Y469128D02*
Y472253D01*
X269109Y472353D01*
G01X273509Y471649D02*
Y469128D01*
G01X260609D02*
Y472453D01*
G01X264909Y469128D02*
Y472553D01*
G01X260609Y472453D02*
Y474978D01*
G01X264909Y472553D02*
Y474978D01*
G01X269109D02*
Y472353D01*
G01X267741Y491608D02*
X269071Y490278D01*
X270209D01*
G01X274209D02*
X270209D01*
G01X270940Y730731D02*
Y735642D01*
G01X266440Y739081D02*
Y736030D01*
G01X261940Y739081D02*
Y735878D01*
G01X259902Y807872D02*
Y791695D01*
G01X284199Y106109D02*
X287595D01*
G01X284199Y109259D02*
X287171D01*
X287599Y108831D01*
G01X289822Y333092D02*
X293727D01*
X294303Y332516D01*
X295971D01*
X300530Y337075D01*
G01X283644Y330552D02*
Y330585D01*
X286151Y333092D01*
X289822D01*
G01X280494Y330552D02*
X280414D01*
X279718Y331248D01*
Y333694D01*
G01X283990Y734977D02*
Y736148D01*
X283440Y736698D01*
Y739081D01*
G01X275440D02*
Y735626D01*
G01X279940Y727281D02*
Y724126D01*
G01X288630Y727362D02*
X290680D01*
X292840Y729522D01*
G01X279587Y807872D02*
Y791695D01*
G01X293725Y124910D02*
Y130209D01*
X293873Y130357D01*
G01X293725Y124910D02*
Y120910D01*
G01X300375Y344346D02*
Y342541D01*
X301330Y341586D01*
Y337875D01*
X300530Y337075D01*
G01X300375Y344346D02*
Y349641D01*
X309410Y358676D01*
G01X301209Y488853D02*
X297762D01*
X296735Y487826D01*
G01X303709Y489353D02*
X306284Y491928D01*
Y493853D01*
G01Y497853D02*
Y493853D01*
G01X294909Y586128D02*
X291357D01*
G01X299090Y634421D02*
X301344Y636675D01*
X308170D01*
X309525Y638030D01*
Y639136D01*
G01X300575Y642208D02*
X297305D01*
X297162Y642065D01*
G01X305200Y652883D02*
X305290Y652793D01*
Y650190D01*
X308324Y647156D01*
X308785D01*
G01X304870Y655747D02*
X305274D01*
X305330Y655803D01*
X308142D01*
X308785Y655160D01*
Y655156D01*
G01Y659156D02*
X306294D01*
G01X308785Y667156D02*
X306294D01*
G01X308785Y663156D02*
X306294D01*
G01X308785Y675156D02*
X306294D01*
G01X308785Y671156D02*
X306294D01*
G01X305979Y691156D02*
X308785D01*
G01Y683156D02*
X306145D01*
G01X308785Y687156D02*
X305979D01*
G01X308785Y679156D02*
X306294D01*
G01X291440Y739081D02*
Y736326D01*
X291790Y735976D01*
G01X303440Y739081D02*
Y737139D01*
X302660Y736359D01*
G01X299272Y807872D02*
Y791695D01*
G01X313789Y115659D02*
Y113871D01*
X328611D01*
X329757Y115017D01*
Y117410D01*
G01X313789Y118809D02*
Y122181D01*
X313583Y122387D01*
G01X309510Y344127D02*
X311284Y342353D01*
X313190D01*
G01Y339203D02*
X311434D01*
X309190Y336959D01*
G01X308120Y334380D02*
Y335889D01*
X309190Y336959D01*
G01X309410Y358676D02*
X313389D01*
X321297Y366584D01*
Y367739D01*
G01X312675Y639136D02*
Y639802D01*
X314940Y642067D01*
G01X308785Y655156D02*
Y651156D01*
G01Y691156D02*
Y695156D01*
G01Y699156D02*
Y695156D01*
G01X307940Y739081D02*
Y736445D01*
G01X311940Y739081D02*
Y736331D01*
X311440Y735831D01*
G01X318957Y807872D02*
Y791695D01*
G01X323957Y117410D02*
Y121312D01*
X323032Y122237D01*
G01X346020Y374075D02*
X348704Y371391D01*
X356480D01*
X360050Y367821D01*
Y363933D01*
X362540Y361443D01*
G01X347670Y642285D02*
X347490Y642105D01*
X346040D01*
X343080Y639145D01*
Y637073D01*
X351007Y629146D01*
X362949D01*
X363530Y629727D01*
G01X355955Y665128D02*
X355902D01*
X353902Y667128D01*
G01X367560Y120823D02*
X368138D01*
X371144Y117817D01*
X375358D01*
G01X366140Y407639D02*
Y400217D01*
X361796Y395873D01*
X360350D01*
G01X363530Y629727D02*
X373907Y640104D01*
Y643960D01*
X373289Y644578D01*
Y656963D01*
X379682Y663356D01*
X380622D01*
X383370Y666104D01*
Y668330D01*
X389250Y674210D01*
Y677047D01*
X392461Y680258D01*
Y685122D01*
X390660Y686923D01*
G01X359105Y665128D02*
X362173D01*
G01X370283Y685656D02*
Y689670D01*
X368074D01*
X367496Y690248D01*
G01X369428Y727622D02*
Y725168D01*
X367882Y723622D01*
X366510D01*
G01X364920Y716909D02*
Y716091D01*
X367350Y713661D01*
G01X368920Y716909D02*
Y715231D01*
X367350Y713661D01*
G01X360246Y739537D02*
X363162D01*
G01X370430Y749138D02*
X369336Y748044D01*
Y743459D01*
G01X354390Y807872D02*
Y790294D01*
G01X366201Y807872D02*
Y790976D01*
G01D02*
Y787976D01*
G01X375358Y117817D02*
Y119103D01*
X377363Y121108D01*
G01X383860Y661239D02*
X385579D01*
X386173Y662222D01*
Y665065D01*
G01X373485Y715026D02*
Y714010D01*
X371170Y711695D01*
Y711574D01*
G01X372486Y739459D02*
X375575D01*
G01X376960Y791580D02*
Y788580D01*
G01X378012Y805904D02*
Y798070D01*
X376960Y797018D01*
Y791580D01*
G01X390000Y567345D02*
Y567058D01*
X395062Y561996D01*
X452869D01*
X466791Y548074D01*
Y515968D01*
G01X391938Y672320D02*
Y670975D01*
X389999Y669036D01*
Y668428D01*
G01X394866Y676213D02*
X394848Y676231D01*
X392097D01*
G01X409481Y264679D02*
Y268679D01*
G01Y256489D02*
X405970D01*
G01X405038Y267521D02*
X405796Y268279D01*
X409081D01*
X409481Y268679D01*
G01Y272731D02*
X405248D01*
G01X407506Y650263D02*
X408779D01*
X409679Y649363D01*
X410918D01*
G01X401329Y650598D02*
X404853D01*
X405188Y650263D01*
X407506D01*
G01X418063Y681569D02*
X416436Y683196D01*
X412250D01*
G01X402540Y710649D02*
Y710949D01*
X405734Y714143D01*
X410617D01*
X412580Y712180D01*
Y709434D01*
X414550Y707464D01*
G01X420289Y697510D02*
Y697508D01*
X415350D01*
X414810Y696968D01*
G01X406720Y723395D02*
Y722955D01*
X402593Y718828D01*
Y716254D01*
G01X413940Y739081D02*
Y735665D01*
G01X427817Y258829D02*
X428921Y257725D01*
X435451D01*
G01X430873Y684536D02*
X432253Y683156D01*
X433265D01*
G01X421213Y681569D02*
Y679133D01*
X422510Y677836D01*
G01X433265Y679156D02*
X430861D01*
G01X422002Y685654D02*
Y689372D01*
X422981Y690351D01*
G01X433265Y691156D02*
X430862D01*
G01X433265Y687156D02*
X430813D01*
G01X433265Y699156D02*
X430618D01*
G01X433265Y703156D02*
X430667D01*
G01X433265Y707156D02*
X430731D01*
G01X433265Y695156D02*
X430813D01*
G01X430738Y711156D02*
X433265D01*
G01X418440Y739081D02*
Y735930D01*
G01X426940Y739081D02*
Y735636D01*
X426430Y735126D01*
G01X422940Y727581D02*
Y723802D01*
G01X427440Y727581D02*
X422940D01*
G01X421321Y791476D02*
Y807872D01*
G01X442580Y236459D02*
X435451Y243588D01*
Y251925D01*
G01X435773Y265453D02*
X440220D01*
X441498Y266731D01*
G01X435773Y262303D02*
Y258047D01*
X435451Y257725D01*
G01X450083Y657403D02*
X446922D01*
X446799Y657526D01*
G01X433265Y711156D02*
Y715156D01*
G01X435940Y739081D02*
Y736428D01*
X435440Y735928D01*
G01X444940Y739081D02*
Y736681D01*
X443940Y735681D01*
G01X445440Y727581D02*
Y726580D01*
X447240Y724780D01*
G01X436440Y727581D02*
Y724710D01*
G01X441006Y791476D02*
Y807872D01*
G01X459000Y202925D02*
Y200500D01*
G01X453530Y736212D02*
Y736331D01*
X453940Y736741D01*
Y739081D01*
G01X462440D02*
Y735687D01*
G01X454440Y727581D02*
Y726577D01*
X455964Y725053D01*
X458050D01*
G01X460691Y807872D02*
Y791476D01*
G01X469000Y139925D02*
X469575D01*
X471500Y138000D01*
G01X478000Y210075D02*
Y212500D01*
G01X466791Y515968D02*
X466587Y515764D01*
G01X465580Y641417D02*
Y641424D01*
X466310Y642154D01*
X471169D01*
X474039Y645024D01*
X480926D01*
X482180Y646278D01*
G01X471450Y736368D02*
Y736371D01*
X470440Y737381D01*
Y739081D01*
G01X492380Y594236D02*
X487649D01*
X485380Y596505D01*
G01X488615Y678656D02*
X490189D01*
X491189Y679656D01*
G01X488615Y682656D02*
X490985Y683656D01*
X491985Y682656D01*
G01D02*
X492294Y682347D01*
G01X488615Y682656D02*
X491985D01*
G01X485465Y678656D02*
X484028D01*
X483056Y679628D01*
G01X488615Y686656D02*
X490316D01*
X491167Y687507D01*
G01X488615Y686656D02*
Y690656D01*
G01Y698656D02*
X490067D01*
X491067Y699656D01*
G01X488615Y694656D02*
X491380D01*
G01X480376Y791476D02*
Y807872D01*
G01X495849Y128666D02*
X499456D01*
G01X497794Y157761D02*
X501131D01*
X502183Y156709D01*
G01X497794Y162261D02*
X500963D01*
G01X507700Y201800D02*
X509800D01*
X512200Y204200D01*
G01X502000Y235575D02*
X499075D01*
G01X510000D02*
Y237500D01*
X508500Y239000D01*
X507000D01*
G01X508663Y468723D02*
Y467838D01*
X505843Y465018D01*
G01X511070Y493380D02*
X508438Y490748D01*
Y490100D01*
G01X505138Y597300D02*
Y599825D01*
X505738Y600425D01*
G01X505138Y594150D02*
Y591125D01*
X505738Y590525D01*
G01X527828Y615387D02*
X523136D01*
X520336Y612587D01*
X514627D01*
X513616Y613598D01*
X508024D01*
G01X500061Y791476D02*
Y807872D01*
G01X515615Y120512D02*
X521459D01*
X525570Y124623D01*
G01X521320Y170525D02*
X518725D01*
G01X513725Y182600D02*
X512600Y181475D01*
Y178900D01*
G01X525400Y183325D02*
X529256D01*
X529272Y183309D01*
G01X514059Y230075D02*
X516625D01*
G01X517189Y226229D02*
X516493Y226925D01*
X514059D01*
G01X519830Y634663D02*
X519832D01*
X520782Y633713D01*
Y629598D01*
G01X514901Y724120D02*
X514940Y724159D01*
Y726581D01*
G01X523370Y724131D02*
Y726011D01*
X523940Y726581D01*
G01X519746Y791476D02*
Y807872D01*
G01X541614Y159415D02*
X538294D01*
G01X533483Y177449D02*
X535306D01*
X537928Y180071D01*
Y183283D01*
G01X533797Y180764D02*
X533768Y180793D01*
Y183269D01*
G01X529272Y183309D02*
Y178311D01*
G01X542002Y183276D02*
Y180100D01*
G01X541675Y216100D02*
X544700D01*
G01X538525D02*
Y213425D01*
G01X538513Y470423D02*
X544830D01*
X545513Y469740D01*
G01X541622Y644931D02*
Y647412D01*
X541440Y647594D01*
G01X527549Y645214D02*
Y647575D01*
X530465Y650491D01*
X531970D01*
G01X537702Y735662D02*
X537440Y735924D01*
Y738081D01*
G01X528440Y735681D02*
Y738081D01*
G01X531845Y724095D02*
X532940Y725190D01*
Y726581D01*
G01X541940Y738081D02*
Y735681D01*
G01X539431Y791476D02*
Y807872D01*
G01X555863Y183023D02*
X555782Y182942D01*
Y179313D01*
X555836Y179259D01*
G01X546000Y183276D02*
Y180000D01*
G01X558768Y191223D02*
X558979Y191012D01*
Y183057D01*
X559013Y183023D01*
G01X552599Y243395D02*
X552556Y243352D01*
Y239501D01*
G01X550040Y243929D02*
X550574Y243395D01*
X552599D01*
G01X557174Y272170D02*
Y274795D01*
X557207Y274828D01*
G01X557765Y665156D02*
X555356D01*
G01X557765Y669156D02*
X555356D01*
G01X557765Y673156D02*
X555308D01*
G01X557765Y689156D02*
X555357D01*
G01X557765Y685156D02*
X555284D01*
G01X557765Y681156D02*
X555235D01*
G01X557765Y677156D02*
X555308D01*
G01X557765Y701156D02*
Y697156D01*
G01D02*
X555150D01*
G01X557765Y693156D02*
X555271D01*
G01X546440Y735681D02*
Y738081D01*
G01X550940D02*
Y735681D01*
G01X559849Y149274D02*
X562282D01*
X563230Y150222D01*
G01X569874Y234520D02*
Y231795D01*
G01X564438Y735853D02*
X564440D01*
Y738581D01*
G01X562395Y724557D02*
X560371Y726581D01*
X559940D01*
G01X568940D02*
Y724090D01*
G01X573440Y738581D02*
Y735681D01*
G01X559116Y791476D02*
Y807872D01*
G01X587420Y663828D02*
X584903D01*
G01X579151Y705451D02*
Y707857D01*
G01X588151Y705451D02*
Y707857D01*
G01X583651Y705451D02*
X584101Y705901D01*
Y707893D01*
G01X577940Y726581D02*
Y724127D01*
G01X587940Y738081D02*
Y735681D01*
G01X578802Y791476D02*
Y807872D01*
G01X593142Y663828D02*
X590570D01*
G01X601440Y735681D02*
Y738081D01*
G01X605938Y735665D02*
Y736621D01*
X605940Y736623D01*
Y738081D01*
G01X596940D02*
Y735681D01*
G01X592440Y726581D02*
Y723768D01*
G01X598487Y791476D02*
Y807872D01*
G01X611520Y596594D02*
X612869Y597943D01*
X615895D01*
G01X615862Y589645D02*
X614166D01*
X612270Y587749D01*
Y586543D01*
G01X615895Y585543D02*
X613270D01*
X612270Y586543D01*
G01X615862Y608845D02*
X613672D01*
X612493Y607666D01*
G01X611254Y617943D02*
X615895D01*
G01X615862Y613745D02*
X612768D01*
X612370Y614143D01*
G01X608115Y675156D02*
X610651D01*
G01X617235Y685866D02*
Y689036D01*
G01X608115Y691156D02*
X610570D01*
G01X608115Y687156D02*
X610040D01*
X610550Y686646D01*
Y686640D01*
G01X608115Y679156D02*
Y683156D01*
G01D02*
X610033D01*
X610810Y683933D01*
G01X621410Y696941D02*
X620956Y697395D01*
X616236D01*
G01X608115Y695156D02*
X610570D01*
G01X619590Y735383D02*
X619410Y735563D01*
Y738051D01*
X619440Y738081D01*
G01X614732Y735517D02*
X614940Y735725D01*
Y738081D01*
G01X608791Y735775D02*
X610440Y737424D01*
Y738081D01*
G01X618172Y791476D02*
Y807872D01*
G01X610298Y791476D02*
Y807872D01*
G01X640663Y387285D02*
X637811D01*
X636990Y386464D01*
G01X640663Y396985D02*
X637888D01*
X637614Y397259D01*
G01X668627Y527718D02*
X666496D01*
X660370Y521592D01*
X642744D01*
X636900Y515748D01*
Y510263D01*
X627620Y500983D01*
Y489339D01*
X639540Y477419D01*
Y450350D01*
X653070Y436820D01*
Y427500D01*
G01X627047Y581066D02*
X626970Y581143D01*
Y584268D01*
G01X634921Y580163D02*
X632928D01*
X632570Y580521D01*
Y584468D01*
G01X640970Y584568D02*
X640870Y584468D01*
X636870D01*
G01X633137Y622720D02*
X633093D01*
X630984Y624829D01*
G01X623960Y735141D02*
X623940Y735161D01*
Y738081D01*
G01Y726581D02*
Y723503D01*
G01X633920Y791476D02*
Y807872D01*
G01X640663Y392085D02*
X637789D01*
X637738Y392034D01*
G01X648838Y414360D02*
X648493Y414705D01*
Y417221D01*
G01X645237Y584470D02*
Y582276D01*
X646732Y580781D01*
G01X640970Y584568D02*
Y581643D01*
X641870Y580743D01*
G01X652012Y591745D02*
X655272D01*
X655445Y591918D01*
G01X652012Y591745D02*
X651945Y591812D01*
Y595943D01*
G01X649409Y584388D02*
X645319D01*
X645237Y584470D01*
G01X652045Y607543D02*
X653886D01*
X655978Y609635D01*
G01X652012Y601745D02*
X655672D01*
X655688Y601761D01*
G01X646070Y622818D02*
X646745D01*
X648701Y624774D01*
G01X651495Y624443D02*
X649032D01*
X648701Y624774D01*
G01X661034Y680648D02*
X657950D01*
X657880Y680718D01*
G01X648077Y716674D02*
Y713569D01*
G01X652177Y728674D02*
X655574D01*
G01X651227Y724674D02*
X656230D01*
X657320Y723584D01*
G01X656660Y739360D02*
X652660D01*
G01X663938Y380510D02*
Y378587D01*
X662390Y377039D01*
G01X659938Y380510D02*
X659543Y380115D01*
Y377086D01*
G01X667538Y414360D02*
Y415276D01*
X668779Y416517D01*
Y417135D01*
G01X653538Y414460D02*
X653649Y414571D01*
Y417582D01*
G01X658338Y414360D02*
Y417619D01*
X658295Y417662D01*
G01X663238Y414460D02*
Y416349D01*
X663674Y416785D01*
Y417999D01*
G01X665170Y595943D02*
X664670Y596443D01*
X661545D01*
G01X661396Y588900D02*
X661545Y588751D01*
Y592143D01*
G01X658395Y596443D02*
Y592143D01*
G01D02*
X655670D01*
X655445Y591918D01*
G01X661647Y601976D02*
X664603D01*
G01X658497D02*
X655903D01*
X655688Y601761D01*
G01X667457Y609468D02*
X668338D01*
X670940Y612070D01*
G01X661745Y614543D02*
X664870D01*
G01X654645Y624443D02*
Y627064D01*
G01X667610Y617197D02*
X666266Y618541D01*
X661712D01*
G01X656254Y683277D02*
X656775Y683798D01*
X661034D01*
G01X664039Y676595D02*
X668000D01*
G01X665050Y680648D02*
X661034D01*
G01X656660Y736218D02*
Y739360D01*
G01X665416Y791476D02*
Y807872D01*
G01X675513Y388185D02*
X676487Y387211D01*
X677946D01*
G01X675513Y392385D02*
X675789Y392661D01*
X678986D01*
G01X675513Y401785D02*
X678659D01*
X680017Y403143D01*
G01X675513Y397585D02*
X678738D01*
X679138Y397985D01*
G01X675513Y406785D02*
X676513Y407785D01*
X678838D01*
G01X709500Y740425D02*
X706575D01*
G01X708723Y807872D02*
Y791092D01*
G01X729500Y734575D02*
Y737400D01*
G01Y740425D02*
Y737400D01*
G01X720534Y807872D02*
Y792664D01*
X721790Y791408D01*
G01X734460Y791654D02*
Y788654D01*
G01Y791654D02*
X732345Y793769D01*
Y807872D01*
G01X734460Y791654D02*
X736282Y793476D01*
Y805904D01*
X-39858Y731383D03*
X-35858D03*
X-31858D03*
X4390Y533777D03*
X13170Y372673D03*
X18340Y366452D03*
X13120Y375871D03*
X16010Y369168D03*
X21530Y368991D03*
X14140Y391826D03*
X18210Y386530D03*
X13950Y388616D03*
X13390Y397543D03*
X14240Y394866D03*
X19450Y550297D03*
X18960Y572061D03*
X17876Y578422D03*
X21881Y595792D03*
X17020Y592934D03*
X13510Y591939D03*
X15850Y610980D03*
X14500Y601957D03*
X9240Y638699D03*
X17071Y658951D03*
X11680Y656335D03*
X9260Y658321D03*
X14000Y658369D03*
X14170Y653991D03*
X9360Y653943D03*
X23987Y12977D03*
X28104Y30414D03*
X24411Y16186D03*
X36848Y25198D03*
X28408Y26414D03*
X34149Y44149D03*
X30282Y34564D03*
X30274Y37714D03*
X36567Y73145D03*
X39126Y84631D03*
X36567Y107988D03*
X38280Y362184D03*
X35750Y364593D03*
X33420Y367309D03*
X23860Y366275D03*
X28250Y438740D03*
X37990Y453022D03*
X28250Y472076D03*
X37990Y520218D03*
X38807Y543539D03*
X34140Y540345D03*
X34240Y536966D03*
X38349Y555730D03*
X36930Y611082D03*
X28270Y602194D03*
X33140Y602232D03*
X35862Y617052D03*
X29964Y658951D03*
X45410Y21563D03*
X54860Y16952D03*
X43480Y34592D03*
X45578Y50478D03*
X50981Y58681D03*
X46981Y58690D03*
X49559Y50577D03*
X41685Y73110D03*
X54703Y122796D03*
X46811Y122928D03*
X54062Y257049D03*
X49244Y360352D03*
X40690Y359555D03*
X53340Y393132D03*
X49750Y387305D03*
X51720Y384808D03*
X50840Y395761D03*
X47820Y398827D03*
X49730Y412473D03*
X45530D03*
X52150Y414896D03*
X47900Y414660D03*
X44360Y414915D03*
X49640Y430237D03*
X45410Y430444D03*
X51350Y433695D03*
X44360Y433729D03*
X51670Y462885D03*
X47590Y463876D03*
X49830Y465496D03*
X47200Y467262D03*
X49590Y469432D03*
X49625Y478472D03*
Y480972D03*
X49185Y472713D03*
X50330Y497940D03*
X53330D03*
X49645Y491804D03*
Y489304D03*
X47380Y494638D03*
X53622Y509276D03*
X53330Y506417D03*
Y503817D03*
X50330D03*
X54117Y529098D03*
X46140Y541712D03*
X41957Y543321D03*
X53988Y568748D03*
X43850Y602797D03*
X39360Y604593D03*
X50270Y627793D03*
X51051Y619407D03*
X48060Y621229D03*
X50170Y636895D03*
X51038Y643928D03*
X49720Y668412D03*
X59524Y25922D03*
X66981Y59390D03*
X62981Y59440D03*
X57040Y73421D03*
X60318Y65593D03*
X64309Y141882D03*
X68756Y167695D03*
X59640Y161376D03*
X55963Y199565D03*
X68930Y197193D03*
X57749Y204326D03*
X56383Y218543D03*
X63720Y228683D03*
X56936Y223944D03*
X57624Y366105D03*
X58000Y412641D03*
X64568Y451029D03*
X67568D03*
X70568D03*
X66747Y466363D03*
X64050Y465689D03*
X61183Y465314D03*
X61357Y483392D03*
Y480892D03*
X61188Y487117D03*
X56330Y497940D03*
X58830D03*
X61676Y502656D03*
Y500156D03*
X61188Y489617D03*
Y492117D03*
X55982Y494543D03*
X65438Y510666D03*
X61033Y510705D03*
X61003Y515110D03*
X65478D03*
X56148Y530809D03*
X66181Y562149D03*
X63930Y560181D03*
X66036Y574901D03*
X63670Y576040D03*
X63300Y621755D03*
X63490Y630693D03*
X62160Y644091D03*
X59390Y642906D03*
X59530Y631704D03*
X66880Y761625D03*
X59260Y779815D03*
X58840Y783097D03*
X62290Y779629D03*
X67660Y779452D03*
X62730Y782694D03*
X66860Y782716D03*
X60370Y776861D03*
X64790Y776777D03*
X56500Y789667D03*
X79360Y46044D03*
X82065Y73224D03*
X80845Y106859D03*
X76880Y126528D03*
X72890Y154349D03*
X81030Y172605D03*
X78850Y157866D03*
X85010Y171679D03*
X71510Y164548D03*
X74470Y175666D03*
X75236Y188946D03*
X75359Y201109D03*
X85876Y218939D03*
X78190Y214642D03*
X86172Y213852D03*
X75560Y218513D03*
X72150Y225148D03*
X78614Y229920D03*
X79217Y232861D03*
X83390Y235665D03*
X79142Y237920D03*
X86479Y249259D03*
X81210Y261337D03*
X79544Y267579D03*
X78220Y281745D03*
X78207Y279092D03*
X82368Y297135D03*
X72368Y287906D03*
X82560Y288099D03*
X82600Y285426D03*
X73917Y385722D03*
X74058Y389621D03*
X74031Y393857D03*
X73868Y397913D03*
X80490Y420690D03*
Y423690D03*
X86050Y428718D03*
X80490Y426690D03*
X79900Y439193D03*
X86050Y425112D03*
Y437470D03*
Y434470D03*
X79900Y445193D03*
Y442193D03*
X85617Y451275D03*
X82617D03*
X86050Y443432D03*
Y446432D03*
X83455Y489485D03*
Y491985D03*
X85955Y489485D03*
Y491985D03*
X83455Y494485D03*
X85955D03*
X81635Y513104D03*
X81174Y503587D03*
X81635Y521104D03*
X82031Y523928D03*
X72216Y540493D03*
X81585Y536382D03*
X80318Y541026D03*
X84990Y563286D03*
X82140Y560758D03*
X81980Y556851D03*
X81516Y577905D03*
X83030Y582656D03*
X85140Y585213D03*
X73130Y601599D03*
X73180Y611184D03*
X80630Y689682D03*
X82847Y716068D03*
X82736Y791695D03*
Y788695D03*
X70925D03*
Y791695D03*
X97830Y66508D03*
X98531Y121340D03*
X102257Y167955D03*
X90878Y177967D03*
X90905Y199733D03*
X86560Y205852D03*
X96168Y231618D03*
X98700Y234650D03*
X96990Y223043D03*
X88399Y244041D03*
X93200Y300734D03*
X99968Y367705D03*
X95968Y367814D03*
X98410Y421908D03*
X90031Y421693D03*
X90238Y418623D03*
X101650Y428745D03*
Y425552D03*
Y433296D03*
Y436075D03*
X101590Y446203D03*
X101650Y443038D03*
X88617Y451275D03*
X86726Y501997D03*
X88563Y491984D03*
Y489484D03*
Y494484D03*
X86695Y498180D03*
X87721Y505817D03*
X95660Y531362D03*
X97366Y542897D03*
X88200Y568111D03*
X98370Y619252D03*
X94070Y618986D03*
Y613841D03*
X97790Y613797D03*
X95350Y644088D03*
X98480Y646217D03*
X98410Y648878D03*
Y680541D03*
X100223Y733207D03*
X89810Y765905D03*
X97390Y766435D03*
X98590Y782494D03*
X94547Y788695D03*
Y791695D03*
X112386Y71874D03*
X115628Y104405D03*
X106517Y210796D03*
X104550Y262359D03*
X104270Y265662D03*
X110230Y360735D03*
X103151Y373340D03*
X110230Y363235D03*
X117030Y389978D03*
X110490Y397362D03*
X103750Y402740D03*
X103810Y405876D03*
X103870Y399604D03*
X108235Y401017D03*
X111120Y401084D03*
X115727Y405844D03*
X113412Y404826D03*
X113504Y407673D03*
X114207Y417910D03*
Y414910D03*
X105670Y411262D03*
X117980Y451981D03*
X118020Y455079D03*
X114072Y480964D03*
X115516Y485696D03*
X110400Y502223D03*
X110436Y499681D03*
X110472Y496888D03*
X113337Y502080D03*
X113372Y496888D03*
X113301Y499574D03*
X117026Y488316D03*
X108026Y492500D03*
X114372Y518898D03*
X112575Y532934D03*
X109972Y519508D03*
X113912Y541144D03*
X114005Y544358D03*
X112627Y536697D03*
X109640Y611890D03*
X109410Y621425D03*
X109500Y616724D03*
X109260Y644687D03*
Y648989D03*
X117790Y667235D03*
X115748Y716275D03*
X106358Y785790D03*
X102421Y782191D03*
X110295Y785734D03*
Y782191D03*
X116370Y785941D03*
X104300Y773100D03*
X114232Y791695D03*
Y788695D03*
X129860Y14571D03*
X130195Y19162D03*
X131474Y43439D03*
X126220Y80364D03*
Y83291D03*
X125480Y91163D03*
X132400Y88153D03*
X129580Y86837D03*
X129780Y92580D03*
X124150Y94643D03*
X128330Y98360D03*
X130350Y130400D03*
Y134167D03*
X126460Y250160D03*
X126570Y256194D03*
X129660Y279890D03*
X130310Y269174D03*
X130324Y272096D03*
Y277096D03*
X123160Y287060D03*
X129610Y287115D03*
X123960Y283696D03*
X128960D03*
X125050Y384546D03*
X122120Y386736D03*
X126300Y390369D03*
X122729Y398001D03*
X127729D03*
X125229D03*
X128226Y413925D03*
X125726D03*
X123226D03*
X129028Y425593D03*
X121080Y460060D03*
X124040Y459746D03*
X127060Y460040D03*
X126377Y466738D03*
X126260Y470267D03*
X121360Y472028D03*
X118720Y471989D03*
X126072Y480864D03*
X130794Y493910D03*
X133731D03*
X127705Y489431D03*
X125105D03*
X119326Y489706D03*
X121968Y488481D03*
X122018Y516353D03*
X133138Y510114D03*
X121644Y509398D03*
X130596Y510042D03*
X124652Y509398D03*
X130703Y512549D03*
X130844Y515128D03*
X128087Y513874D03*
X132960Y550005D03*
X125340Y558090D03*
X133590Y588438D03*
X130790Y595613D03*
X128240Y666583D03*
X120909Y674490D03*
X132190Y662616D03*
X129607Y686735D03*
X126220Y720949D03*
X120357Y738889D03*
X132334Y732982D03*
X120322Y742187D03*
X123518Y742030D03*
X130850Y782456D03*
X118169Y783857D03*
X130660Y785601D03*
X127290Y781982D03*
X122720Y785051D03*
X137500Y25494D03*
X147427Y30367D03*
X146380Y20345D03*
X147461Y38078D03*
X147497Y42983D03*
X145210Y60154D03*
X149157Y60010D03*
X137540Y58255D03*
X146558Y74863D03*
X140350Y81347D03*
X135640Y134167D03*
X135590Y130449D03*
X147570Y249033D03*
X147160Y242219D03*
X144400Y244061D03*
Y247561D03*
X141682Y269829D03*
X143150Y281123D03*
X137925Y290987D03*
X137990Y296735D03*
X139950Y293835D03*
X136130Y305640D03*
X137091Y301799D03*
X149020Y303498D03*
X135730Y314543D03*
X134768Y319043D03*
X144058Y376025D03*
X137889Y403348D03*
X141800Y404481D03*
X141847Y401820D03*
X135088Y405060D03*
X135181Y402121D03*
X145295Y404388D03*
X135507Y421367D03*
X139395Y425090D03*
X138437Y435930D03*
Y438430D03*
X147820Y441929D03*
X147576Y445279D03*
Y447779D03*
Y450279D03*
X138437Y440930D03*
X139310Y478102D03*
X136470Y481994D03*
X139365Y516636D03*
X139402Y513707D03*
X149477Y532733D03*
X144120Y547577D03*
X146920Y547677D03*
X145020Y576001D03*
X143252Y573105D03*
X145550Y588088D03*
X141260Y588175D03*
X141190Y597685D03*
X145880Y584125D03*
X144710Y598135D03*
X136420Y599352D03*
X147753Y627557D03*
X145750Y630254D03*
X148140Y660112D03*
X148487Y676041D03*
X147750Y687539D03*
X143823Y682907D03*
X134450Y682978D03*
X134777Y738726D03*
Y734726D03*
X134753Y726161D03*
X137070Y728012D03*
X134720Y742382D03*
X147290Y744113D03*
X145040Y740741D03*
X139600Y781281D03*
X135610Y784521D03*
X139680Y784596D03*
X149450Y780429D03*
X146150Y783820D03*
X141791Y788695D03*
Y791695D03*
X150787Y9246D03*
X158181Y11978D03*
X153863Y15176D03*
X164139Y13027D03*
X154592Y21173D03*
X150592Y20974D03*
X152412Y38112D03*
X152366Y42983D03*
X156255Y45743D03*
X160731Y41038D03*
X162350Y42984D03*
X152789Y53124D03*
X157659Y47891D03*
X161221Y89447D03*
X160040Y108844D03*
X162130Y129344D03*
X163518Y243987D03*
X162317Y249877D03*
X161918Y254287D03*
X160449Y259605D03*
X162484Y276599D03*
X158583Y285548D03*
X161918Y293869D03*
X161767Y287242D03*
X162181Y303075D03*
X161687Y310355D03*
X162063Y327940D03*
X162017Y324389D03*
X159564Y328013D03*
X161513Y317143D03*
X159285Y336220D03*
X164418Y348187D03*
X152058Y376016D03*
X160058Y375818D03*
X150524Y382808D03*
X165290Y385948D03*
X151820Y385554D03*
X150902Y379714D03*
X160886Y380294D03*
X160710Y384044D03*
X161640Y403286D03*
X162940Y406188D03*
X161577Y436834D03*
X151145Y469456D03*
X163377Y484538D03*
X152554Y494027D03*
X158406Y500016D03*
X155109Y561153D03*
X154140Y577815D03*
X158430Y568437D03*
X162786Y568599D03*
X151900Y590454D03*
X153527Y597138D03*
X160699Y587904D03*
X153712Y610917D03*
X153330Y599935D03*
X153422Y603043D03*
X153955Y620760D03*
X157963Y643289D03*
X162668Y631897D03*
X162530Y643235D03*
Y636435D03*
X151915Y675068D03*
X155957Y674813D03*
X160112Y674990D03*
X165012Y675887D03*
X164812Y662579D03*
X151567Y687579D03*
X155650Y681515D03*
X161994Y678445D03*
X159590Y683050D03*
X157287Y678138D03*
X165167Y681311D03*
X152222Y678394D03*
X160101Y687962D03*
X163018Y684381D03*
X164092Y688014D03*
X150840Y682436D03*
X149860Y726626D03*
X154970Y736966D03*
X158881Y730784D03*
X162640Y743927D03*
X158970D03*
X154400Y744337D03*
X155230Y740259D03*
X160480Y777583D03*
X164630Y781222D03*
X153320Y783499D03*
X149810Y783858D03*
X179235Y7369D03*
X171310Y12450D03*
X171666Y7449D03*
X175280Y12401D03*
X174166Y7449D03*
X166639Y13027D03*
X165959Y27133D03*
X173110Y26877D03*
X180907Y27544D03*
X176090Y26906D03*
X177224Y49101D03*
X174724D03*
X177224Y51601D03*
X174724D03*
X172224Y49101D03*
Y54101D03*
X177224D03*
X174724D03*
X172224Y51601D03*
X169149Y50968D03*
X168040Y61462D03*
X177757Y88271D03*
X168308Y88412D03*
X177733Y91967D03*
X180990Y108770D03*
X177210Y97657D03*
X165690Y98835D03*
X171950Y105105D03*
X173900Y97662D03*
X177680Y101764D03*
X167127Y120603D03*
X174213Y120569D03*
X180510Y233307D03*
X174138Y243873D03*
X171320Y243601D03*
X167467Y243242D03*
X171668Y256287D03*
X173263Y262589D03*
X176301Y262624D03*
X167322Y255855D03*
X167698Y260617D03*
X178929Y262244D03*
X175110Y260412D03*
X175118Y274287D03*
X170617Y267326D03*
X175318Y278687D03*
X170510Y275522D03*
X174078Y271435D03*
X170829Y271452D03*
X178941Y270160D03*
X177470Y294933D03*
X180254Y295023D03*
X175162Y293934D03*
X175659Y286984D03*
X176037Y309845D03*
X180254Y310663D03*
X175921Y301920D03*
X178921D03*
X178812Y324259D03*
X180342Y316469D03*
X175330Y318552D03*
X166189Y335285D03*
X167383Y341306D03*
X177359Y332553D03*
X174876Y336549D03*
X177604Y355155D03*
X177720Y352522D03*
X177029Y347811D03*
X177672Y358103D03*
X176058Y376568D03*
X168058Y376035D03*
X167951Y380551D03*
X175290Y389582D03*
X174500Y383383D03*
X178660Y388418D03*
X171934Y386364D03*
X175155Y380727D03*
X175663Y386424D03*
X176371Y404721D03*
X172760Y406540D03*
X170506Y424127D03*
X175993Y414924D03*
X173381Y424005D03*
X178232Y430642D03*
X178217Y435317D03*
X173151Y427552D03*
X172944Y448387D03*
X170444D03*
X177525Y451946D03*
X180125D03*
X178961Y448138D03*
X176220Y448247D03*
X171616Y467804D03*
X179857Y477790D03*
X168370D03*
X169293Y562358D03*
X171053Y569411D03*
X175386Y569589D03*
X179740Y568951D03*
X166605Y587860D03*
X178416Y587849D03*
X179532Y600437D03*
X173432D03*
X165832Y600337D03*
Y606037D03*
Y613137D03*
X172532Y619537D03*
X178632Y619437D03*
X165832D03*
X167530Y631935D03*
X174479Y631986D03*
X177038Y647135D03*
X166388Y647435D03*
X171180Y652009D03*
X171270Y655650D03*
X179180Y675205D03*
X174761Y663816D03*
X168645Y688064D03*
X165628Y691289D03*
X167315Y684943D03*
X178982Y688631D03*
X178278Y705976D03*
Y701976D03*
Y697976D03*
X169268Y705304D03*
X169396Y701006D03*
X169268Y697399D03*
X169619Y693335D03*
X178278Y709976D03*
X171154Y715673D03*
X169531Y710542D03*
X171689Y728920D03*
X165599Y730476D03*
X177920Y739302D03*
X169350Y785470D03*
X172600Y780150D03*
X167350Y778074D03*
X173287Y791695D03*
Y788695D03*
X189235Y7369D03*
X191735D03*
X181735D03*
X194825Y10196D03*
X194861Y12952D03*
X183407Y27544D03*
X188634Y27860D03*
X184843Y88467D03*
X191930Y88507D03*
X196000Y95568D03*
X195473Y108767D03*
X184170Y95213D03*
X186060Y100103D03*
X183013Y98813D03*
X190100Y99701D03*
X196010Y125188D03*
X186730Y121202D03*
X188821Y232784D03*
X183550Y235060D03*
X193677Y243855D03*
X189192Y243061D03*
X184318Y247612D03*
X188899Y240208D03*
X195126Y249955D03*
X188899Y236808D03*
X194056Y256697D03*
X193735Y265857D03*
X188442Y252643D03*
X184829Y259139D03*
X188658Y256870D03*
X184117Y264852D03*
X181602Y262656D03*
X186873Y263697D03*
X185798Y256760D03*
X186873Y260697D03*
X194693Y259197D03*
Y262197D03*
X190918Y277687D03*
X185991Y279041D03*
X186118Y270787D03*
X188418Y278887D03*
X194205Y271034D03*
X191860Y270148D03*
X183698Y285693D03*
X193557Y294428D03*
X187812Y286352D03*
X184812Y292979D03*
X186254Y295023D03*
X191054Y294424D03*
X183254Y295023D03*
X194771Y302176D03*
X193812Y308619D03*
X195254Y310663D03*
X184754Y302843D03*
X181921Y301920D03*
X191949Y301987D03*
X188810Y301998D03*
X187907Y308784D03*
X186254Y310663D03*
X193313Y325492D03*
X186296Y326366D03*
X186350Y317116D03*
X196476Y317042D03*
X193957Y317064D03*
X187404Y343998D03*
X192293Y340792D03*
X185195Y332852D03*
X184367Y337792D03*
X192230Y337322D03*
X186925Y355812D03*
X192519Y352761D03*
X186908Y352760D03*
X184058Y376479D03*
X194231Y390267D03*
X184927Y383876D03*
X185074Y380726D03*
X194330Y396425D03*
X192676Y402961D03*
X182771Y424013D03*
X185271D03*
X182771Y421513D03*
X185271D03*
X182132Y418327D03*
X182877Y430662D03*
X182879Y435312D03*
X192069Y444852D03*
X184523Y441915D03*
X181923Y445044D03*
Y442544D03*
X185747Y487664D03*
X193500Y489796D03*
X181231Y512455D03*
X188640Y530667D03*
X181232Y553402D03*
X188654Y573395D03*
X191500Y571956D03*
X181330Y587535D03*
X185032Y606737D03*
X184932Y600537D03*
X185032Y612937D03*
X184932Y619437D03*
X182353Y631612D03*
X196410Y650155D03*
X187410Y649715D03*
Y659705D03*
X191910Y650055D03*
X188200Y672526D03*
X196463Y685036D03*
X182163Y684555D03*
X194508Y704476D03*
X187798Y704513D03*
X181744Y694829D03*
X190375Y695624D03*
X185440Y712499D03*
X196144Y712602D03*
X187744Y708356D03*
X191930Y712624D03*
X196079Y723943D03*
X194440Y735623D03*
X189940Y735681D03*
X185440D03*
X182674Y730521D03*
X191150Y724108D03*
X186164Y724134D03*
X204785Y13762D03*
X201849Y15292D03*
X198577Y15374D03*
X199016Y88434D03*
X206103Y88207D03*
X202560Y107797D03*
X210203Y108457D03*
X206273Y98364D03*
X200480Y97687D03*
X212423Y104957D03*
X199993Y103637D03*
X207070Y179744D03*
X207041Y184502D03*
X212020Y234359D03*
X198296Y232699D03*
X211935Y244085D03*
X198685Y240785D03*
X211935Y237385D03*
Y240785D03*
X205566Y243497D03*
X211028Y255696D03*
X210333Y265197D03*
X208129Y257519D03*
X206144Y252477D03*
X208289Y263639D03*
X210305Y262289D03*
X201994Y261248D03*
X202402Y263713D03*
X200469Y259139D03*
X201518Y265990D03*
X208226Y269697D03*
X201667Y274542D03*
X199509Y278094D03*
X209449Y281098D03*
X210303Y268227D03*
X206299Y281098D03*
X210303Y271227D03*
X203149Y281098D03*
X201518Y268887D03*
X209449Y287398D03*
Y290548D03*
X203149Y287398D03*
X206299D03*
X196867Y294342D03*
X206299Y290548D03*
X206319Y296863D03*
X203149Y290548D03*
X206299Y293698D03*
Y312598D03*
X198880Y310245D03*
X196812Y308619D03*
X206299Y306298D03*
Y303148D03*
X209449Y312598D03*
X203166Y312577D03*
X202525Y299358D03*
X209300Y322800D03*
X207310Y330149D03*
X206299Y315748D03*
X203058Y315593D03*
X200211Y321446D03*
X200572Y323920D03*
X208700Y328000D03*
X200590Y327615D03*
X208485Y332356D03*
X200905Y333776D03*
X201489Y336207D03*
Y339107D03*
X197243Y344518D03*
X206817Y358874D03*
X207274Y353124D03*
X198987Y353137D03*
X206657Y356116D03*
X202823Y376922D03*
X197938Y376839D03*
X200439Y390168D03*
X203880Y385272D03*
X205790Y387003D03*
X200488Y396425D03*
X210880Y402359D03*
X206380Y402201D03*
X200039Y448750D03*
Y451350D03*
X197809Y469953D03*
X200434Y478345D03*
X200459Y487253D03*
X208710Y500856D03*
X211379Y501904D03*
X210040Y576893D03*
X209590Y580893D03*
X197230Y595335D03*
X198890Y584105D03*
X207178Y591595D03*
X211760Y610915D03*
X207476Y608936D03*
X207010Y602472D03*
X196907Y605012D03*
X197030Y598535D03*
X211862Y617709D03*
X197230Y615435D03*
X197130Y626135D03*
X200910Y659735D03*
Y650155D03*
X205410Y650035D03*
X209238Y674373D03*
X202450Y663633D03*
X199510Y663158D03*
X202518Y673273D03*
X197889Y671226D03*
X210824Y692266D03*
X197582Y703474D03*
X200692Y704081D03*
X211236Y695586D03*
X197243Y697899D03*
X210023Y712842D03*
X201663Y712694D03*
X198940Y712499D03*
X205440Y712510D03*
X211897Y723870D03*
X201411Y708231D03*
X212440Y735829D03*
X198940Y735681D03*
X207940D03*
X203440D03*
X205883Y724373D03*
X200817Y724180D03*
X200846Y788695D03*
Y791695D03*
X225990Y21219D03*
X221990D03*
X222290Y45504D03*
X226290D03*
X221310Y51103D03*
X225310D03*
X221600Y66317D03*
X225600D03*
X213190Y88414D03*
X220276Y88440D03*
X214573Y93771D03*
X222983Y91587D03*
X219095Y108675D03*
X217040Y103121D03*
X226713Y122007D03*
X217135Y244085D03*
X226010Y240342D03*
X217135Y237385D03*
X227517Y244187D03*
X219772Y252659D03*
X215761Y252833D03*
X224794Y256754D03*
X218153Y260697D03*
Y263697D03*
X223929Y263639D03*
X225973Y262197D03*
X216109Y265139D03*
Y262139D03*
X218508Y256664D03*
X225973Y265197D03*
Y259197D03*
X225199Y281098D03*
X216109Y274139D03*
X212599Y281098D03*
X218899D03*
X224357Y273228D03*
X216109Y271139D03*
X215749Y281098D03*
X213138Y274187D03*
X212599Y290548D03*
X225199Y287398D03*
X212599Y293698D03*
X222049Y290548D03*
X225160Y293676D03*
X225199Y290548D03*
Y284248D03*
X222049Y287398D03*
X212599D03*
X215749Y290548D03*
Y293698D03*
Y287398D03*
X225199Y309448D03*
Y299998D03*
Y303148D03*
X222049Y309448D03*
X212599Y299998D03*
Y303148D03*
X222049Y312598D03*
X218899Y309448D03*
X222049Y303148D03*
X225199Y306298D03*
Y312598D03*
X222049Y306298D03*
X218899D03*
X222049Y299998D03*
X212610Y306305D03*
X218899Y299998D03*
Y303148D03*
X218947Y312617D03*
X215100Y322700D03*
X217129Y327207D03*
X215085Y325649D03*
X212600Y319100D03*
X217129Y324207D03*
X224949Y328707D03*
X225199Y315748D03*
X224585Y322992D03*
X224711Y325922D03*
X217129Y336207D03*
X217067Y339542D03*
X217129Y333207D03*
X223010Y344242D03*
X223166Y338842D03*
X222911Y333155D03*
X224996Y334617D03*
X223095Y336241D03*
X221280Y340579D03*
X228057Y352837D03*
X222777Y353066D03*
X214888Y352909D03*
X222974Y356134D03*
X223561Y385108D03*
X214008Y385165D03*
X221438Y390655D03*
X224108Y388029D03*
X216633Y384989D03*
X213710Y402237D03*
X224730Y418003D03*
X221406Y436560D03*
X227816Y442675D03*
X218483Y442550D03*
X221858Y442300D03*
X225024Y442467D03*
X226276Y460704D03*
X213994Y466054D03*
X228242Y463681D03*
X223953Y463550D03*
X212809Y479053D03*
X215409Y479253D03*
X223786Y476638D03*
X216209Y488853D03*
X213209D03*
X224209Y494928D03*
X219309Y489353D03*
X222209D03*
X221591Y563371D03*
X223561Y561475D03*
X223453Y578087D03*
X216590Y570850D03*
X220428Y580271D03*
X218859Y593093D03*
X225100Y597453D03*
X219296Y604811D03*
X215604Y621977D03*
X215985Y633977D03*
X215948Y629977D03*
X221129Y642363D03*
X218308Y635939D03*
X225179Y642614D03*
X215768Y671993D03*
X225237Y671772D03*
X212635Y665604D03*
X224289Y680081D03*
X224360Y684366D03*
X213365Y692151D03*
X224060Y690317D03*
X224336Y687758D03*
X223707Y695436D03*
X220580Y692876D03*
X223741Y700554D03*
X221340Y697995D03*
X226610Y713482D03*
X227650Y720791D03*
X224410Y719970D03*
X216940Y736063D03*
X221440Y735934D03*
X225940Y724061D03*
Y733671D03*
Y736437D03*
X220532Y788695D03*
Y791695D03*
X212658D03*
Y788695D03*
X241990Y21219D03*
X229990D03*
X242290Y45504D03*
X230290D03*
X229310Y51103D03*
X233290Y51045D03*
X237310Y50983D03*
X241310D03*
X237600Y66317D03*
X241600D03*
X229600D03*
X233600D03*
X236360Y93931D03*
X236812Y88698D03*
X229725Y88719D03*
X235113Y91307D03*
X231013Y91547D03*
X243730Y103057D03*
X240355Y108757D03*
X239500Y100925D03*
X231910Y105731D03*
X235190Y96905D03*
X230643Y108497D03*
X234243Y100156D03*
X237773Y103607D03*
X233268Y121742D03*
X230749Y160807D03*
X230650Y164566D03*
X230890Y169424D03*
X231000Y173381D03*
X230100Y187389D03*
X230140Y197240D03*
X231710Y243642D03*
X231749Y265139D03*
X239569Y257639D03*
X241613Y262197D03*
X239569Y266639D03*
X241613Y259197D03*
X237594Y252754D03*
X241613Y265197D03*
X233793Y266697D03*
Y257697D03*
X233904Y252772D03*
X239569Y263639D03*
X233793Y263697D03*
X231749Y262139D03*
X233793Y260697D03*
X239569Y260639D03*
X231749Y259139D03*
X240910Y274742D03*
X233793Y269697D03*
X234649Y281098D03*
X237865Y281131D03*
X239569Y269639D03*
X232118Y271587D03*
X241613Y271197D03*
Y268197D03*
X228821Y274197D03*
X231648Y274243D03*
X237799Y290548D03*
Y284248D03*
X231499Y287398D03*
X231450Y290583D03*
X237760Y293692D03*
X237799Y287398D03*
X240949Y290548D03*
Y287398D03*
X231499Y284248D03*
Y296848D03*
Y293698D03*
X240949Y296848D03*
X237800Y299998D03*
X231499Y309448D03*
Y299998D03*
X237799Y312598D03*
X231499D03*
X240949Y309448D03*
X237799Y303148D03*
X234649D03*
X237799Y306298D03*
X240949Y299998D03*
Y303148D03*
X241258Y319123D03*
X231567Y321742D03*
X232782Y327096D03*
X230725Y325649D03*
X238545Y327149D03*
X240374Y328960D03*
X240511Y325517D03*
X240692Y344204D03*
X233055Y339936D03*
X230725Y331649D03*
X238548Y333149D03*
X230725Y334547D03*
X240598Y334642D03*
X240218Y338010D03*
X231144Y338225D03*
X238560Y336136D03*
X232769Y333207D03*
X232804Y336181D03*
X239290Y340428D03*
X233697Y353961D03*
X238084Y355992D03*
X243940Y390885D03*
X236687Y385234D03*
X232172Y388814D03*
X228729Y385227D03*
X241451Y392147D03*
X236412Y387722D03*
X231223Y391424D03*
X239546Y390528D03*
X239228Y393291D03*
X232647Y396011D03*
X228906Y424560D03*
X228713Y416525D03*
Y419525D03*
X240599Y440053D03*
X231870Y439511D03*
X228906Y433560D03*
Y427560D03*
Y436560D03*
X231885Y442252D03*
X235319Y464362D03*
X233309Y472553D03*
X237609Y472453D03*
X241909Y472553D03*
X242915Y576539D03*
X243209Y574018D03*
X239269Y597128D03*
X229809Y583627D03*
X234500Y637685D03*
X243743Y636514D03*
X241670Y652558D03*
X233584Y652519D03*
X239168Y671672D03*
X240493Y692678D03*
X239084Y696252D03*
X233954Y697395D03*
X236120Y704173D03*
X238348Y712469D03*
X239210Y720040D03*
X243900Y724662D03*
X239440Y736140D03*
X230440Y736412D03*
X234940Y724325D03*
Y733355D03*
X243940Y736412D03*
X239500Y733523D03*
X230440Y724242D03*
X234940Y736392D03*
X240217Y788695D03*
Y791695D03*
X232343D03*
Y788695D03*
X249990Y21219D03*
X245990D03*
X257270Y29334D03*
X250290Y45504D03*
X246290D03*
X258103Y53688D03*
X257500Y56117D03*
X245310Y50867D03*
X249300Y50862D03*
X253490Y53736D03*
X253810Y63244D03*
X245600Y66317D03*
X249600D03*
X246073Y92197D03*
X256573Y94097D03*
X247870Y105821D03*
X259030Y123727D03*
X259443Y120773D03*
X255287Y226709D03*
X254181Y234521D03*
X257950Y236924D03*
X255209Y260639D03*
X255359Y266557D03*
X247389Y259139D03*
X256553Y256881D03*
X249433Y263697D03*
Y260697D03*
X256916Y262609D03*
X247389Y262139D03*
X257253Y259197D03*
X259518Y252358D03*
X249433Y257697D03*
X246467Y255442D03*
X257046Y279607D03*
X255205Y272755D03*
X244109Y277996D03*
X244099Y281098D03*
X254234Y281622D03*
X250399Y281098D03*
X247389Y268139D03*
X257253Y271197D03*
Y268197D03*
X250399Y296848D03*
X253611Y293765D03*
X250399Y290548D03*
X244099Y284248D03*
X250399D03*
X244099Y293698D03*
X244110Y290505D03*
X257447Y287117D03*
X244099Y287398D03*
X250399D03*
X253549Y290548D03*
X247249Y296848D03*
X244099D03*
X258380Y295984D03*
X254334Y298728D03*
X247249Y303148D03*
X244118Y309387D03*
X254007Y306819D03*
X244118Y303187D03*
X257057Y309636D03*
X244099Y299998D03*
X247249Y306298D03*
X257418Y303533D03*
X258590Y311560D03*
X247281Y315727D03*
X247290Y327694D03*
X254631Y324716D03*
X254998Y329779D03*
X256276Y322652D03*
X247789Y322910D03*
X254905Y327213D03*
X250401Y315713D03*
X253710Y315669D03*
X248509Y339207D03*
X254819Y332435D03*
X250466Y344381D03*
X245691Y341215D03*
X247218Y333049D03*
X255009Y338318D03*
X246685Y337357D03*
X255124Y335244D03*
X247025Y330512D03*
X251334Y352857D03*
X259444Y354291D03*
X246265Y355855D03*
X256588Y359005D03*
X250661Y384780D03*
X256532Y384895D03*
X247065Y385398D03*
X244546Y385315D03*
X253762Y385255D03*
X247797Y406029D03*
X250297D03*
X252797D03*
X245297D03*
X244196Y419610D03*
Y417010D03*
X258798Y417594D03*
X254798Y417728D03*
X244196Y427610D03*
Y425010D03*
Y433010D03*
Y435610D03*
X252670Y443592D03*
X255509Y472253D03*
X246109Y472465D03*
X251309Y472553D03*
X245609Y517182D03*
X252036Y582131D03*
X245860Y575049D03*
X249909Y568653D03*
X249541Y587156D03*
X253709Y586128D03*
X249541Y583156D03*
X253187Y596382D03*
X246639Y608378D03*
Y605778D03*
X249640Y602519D03*
X246639Y624378D03*
Y621778D03*
Y616378D03*
Y613778D03*
X249013Y628514D03*
X251803Y636704D03*
X254773Y644424D03*
X254303Y636744D03*
X256463Y639364D03*
X252173Y644344D03*
X249083Y636664D03*
X256513Y642494D03*
X246553Y636684D03*
X252486Y671772D03*
X253398Y692357D03*
X250795Y703150D03*
X251451Y697465D03*
X254940Y712381D03*
X255310Y715915D03*
X248530Y721829D03*
X250630Y719457D03*
X253340Y724726D03*
X248440Y736163D03*
X257440Y736041D03*
X252940Y736318D03*
X248770Y724631D03*
X252940Y733567D03*
X252028Y791695D03*
X273660Y23037D03*
X268579Y19365D03*
X265934Y16522D03*
X273645Y27712D03*
X268372Y40782D03*
X265872D03*
X272010Y40553D03*
X274510D03*
X273873Y63167D03*
X269793D03*
X261750Y75886D03*
X274580Y74281D03*
X269920Y74318D03*
X272440Y76177D03*
X268080Y76416D03*
X267703Y89397D03*
X271133Y92787D03*
X265830Y102566D03*
X264210Y96914D03*
X273973Y97645D03*
X263683Y99902D03*
X268702Y107928D03*
X269010Y121648D03*
X269620Y243240D03*
X269192Y248209D03*
X272242Y244842D03*
X272620Y238653D03*
X271458Y241347D03*
X266187Y249852D03*
X267020Y257079D03*
X263029Y259139D03*
X265073Y266697D03*
X263029Y265139D03*
X271811Y256687D03*
X271898Y263173D03*
X260068Y262187D03*
X263268Y262370D03*
X269263Y252800D03*
X271944Y278363D03*
X264386Y280407D03*
X265944Y278363D03*
X274886Y272587D03*
X273386Y280407D03*
X270444Y270543D03*
X271886Y272587D03*
X265886Y271718D03*
X268886Y272587D03*
X268944Y278363D03*
X263029Y271139D03*
Y268139D03*
X273444Y270543D03*
X274944Y278363D03*
X270386Y280407D03*
X267386D03*
X262886Y288227D03*
X264386Y296047D03*
X267386D03*
X265825Y293987D03*
X268867Y293942D03*
X265768Y287546D03*
X273444Y286183D03*
X273618Y295387D03*
X271811Y303313D03*
X271944Y309643D03*
X262944D03*
X261386Y311687D03*
X260045Y309615D03*
X268944Y309643D03*
X265944Y309640D03*
X269380Y302736D03*
X264501Y303109D03*
X266939Y303281D03*
X274303Y303413D03*
X259820Y303800D03*
X267268Y311642D03*
X264287Y311687D03*
X270518Y311637D03*
X274832Y309687D03*
X262035Y322679D03*
X267883Y325837D03*
X265318Y326487D03*
X270525Y325754D03*
X262201Y328491D03*
X272967Y325842D03*
X275517D03*
X267030Y330147D03*
X268502Y344181D03*
X263576Y340898D03*
X274701Y333804D03*
X270326Y335795D03*
X270485Y339030D03*
X264015Y336151D03*
X267943Y339617D03*
X270293Y330540D03*
X272964Y330669D03*
X262379Y338103D03*
X262247Y334502D03*
X270071Y333021D03*
X272263Y334222D03*
X272352Y340900D03*
X269456Y355353D03*
X269117Y352876D03*
X273477Y385100D03*
X261663Y385193D03*
X267993Y390695D03*
X266882Y388165D03*
X261539Y387755D03*
X264421Y384812D03*
X275497Y390758D03*
X262798Y417886D03*
X271720Y422587D03*
X265532Y422648D03*
X269630Y424884D03*
X275256Y445753D03*
X271035Y443051D03*
X273735Y443034D03*
X273509Y471649D03*
X260609Y472453D03*
X264909Y472553D03*
X269109Y472353D03*
X275452Y483219D03*
X267741Y491608D03*
X269609Y588653D03*
X268717Y606015D03*
X261967Y608638D03*
Y605638D03*
X260064Y602993D03*
X261967Y614638D03*
X263467Y626638D03*
X261967Y617638D03*
X263467Y623638D03*
X273938Y633084D03*
X273674Y640095D03*
X273548Y636471D03*
X270040Y651241D03*
X269640Y655290D03*
X270430Y665576D03*
X269709Y672575D03*
X265913Y671772D03*
X270140Y691038D03*
X272460Y687889D03*
X265300Y702131D03*
X272650Y693742D03*
X269410Y706003D03*
X270940Y722080D03*
X275440Y735626D03*
X261940Y735878D03*
X266440Y736030D03*
X270940Y735642D03*
X271713Y788695D03*
Y791695D03*
X259902D03*
X280699Y13908D03*
X278199D03*
X282180Y10253D03*
X285703Y9813D03*
X278660Y10073D03*
X278305Y23057D03*
X280699Y16408D03*
X278199D03*
X278307Y27707D03*
X287476Y37125D03*
X277472Y34959D03*
Y37459D03*
X280072Y34330D03*
X275766Y52772D03*
X275800Y50212D03*
X290823Y63167D03*
X282023D03*
X277853D03*
X287270Y75018D03*
X283870Y74724D03*
X279100Y74447D03*
X289738Y76173D03*
X285543Y76867D03*
X281400Y75938D03*
X276969Y76247D03*
X277000Y88323D03*
X286263Y88677D03*
X287595Y106109D03*
X279010Y104889D03*
X286710Y95717D03*
X281200Y98369D03*
X289720Y96094D03*
X278760Y101061D03*
X287599Y108831D03*
X278880Y108482D03*
X278354Y244281D03*
X290154Y244007D03*
X285934Y243931D03*
X282178Y244005D03*
X289254Y255688D03*
X286492Y258364D03*
X283660Y251542D03*
X281954Y255588D03*
X288954Y260788D03*
X276328Y264687D03*
X281945Y260231D03*
X279336Y264795D03*
X277886Y272587D03*
X280886D03*
X286010Y276042D03*
X282867Y281142D03*
X276444Y270543D03*
X282309Y270435D03*
X279444Y270543D03*
X277944Y278363D03*
X279386Y280407D03*
X276386D03*
X276507Y295816D03*
X286132Y285953D03*
X278918Y286887D03*
X276444Y286183D03*
X279386Y311687D03*
X285890Y311357D03*
X277020Y302298D03*
X282337Y308217D03*
X281859Y310862D03*
X277816Y309678D03*
X279754Y303269D03*
X276386Y311687D03*
X281461Y321744D03*
X280776Y326412D03*
X286071Y329184D03*
X278067Y325842D03*
X282167Y324242D03*
X288466Y325343D03*
X285704Y321809D03*
X275660Y338857D03*
X281212Y338079D03*
X277288Y334282D03*
X282234Y333792D03*
X285794Y339063D03*
X279718Y333694D03*
X275602Y343811D03*
X290190Y352480D03*
X278943Y346914D03*
X277718Y352687D03*
X282818D03*
X286711Y352668D03*
X283140Y346082D03*
X286020Y356454D03*
X279863Y367513D03*
X276687Y385100D03*
X288687Y385290D03*
X281864Y386178D03*
X284687Y386769D03*
X288220Y389630D03*
X283820Y396266D03*
X281142Y402379D03*
X280730Y393856D03*
X276400Y422341D03*
X280010Y422279D03*
X281190Y424966D03*
X278080Y424760D03*
X286210Y444926D03*
X289630Y444828D03*
X283212Y442286D03*
X286100Y442298D03*
X288742Y442090D03*
X287970Y446705D03*
X282000Y444966D03*
X279112Y444954D03*
X279990Y442071D03*
X276809Y471853D03*
X280210Y460762D03*
X287567Y470649D03*
Y467649D03*
X280380Y467284D03*
X278990Y464793D03*
X284332Y472834D03*
X282298Y483803D03*
X277470Y481197D03*
X280970D03*
X288009Y495653D03*
X280874Y556139D03*
X291066Y590488D03*
Y593088D03*
X278109Y589238D03*
X289171Y661908D03*
X279090Y668504D03*
X279785Y663876D03*
X289365Y665845D03*
X288880Y689467D03*
X278350Y687309D03*
X275560Y697804D03*
X279060Y693306D03*
X284760Y707022D03*
X278341Y717269D03*
X289060Y722193D03*
X281830Y722184D03*
X289150Y718548D03*
X279940Y724126D03*
X289240Y724687D03*
X283990Y734977D03*
X284020Y724956D03*
X279587Y791695D03*
X295307Y41260D03*
X295390Y44017D03*
X295610Y50299D03*
X295560Y52907D03*
X294903Y63167D03*
X306693D03*
X303053D03*
X298883D03*
X292313Y76345D03*
X305880Y76361D03*
X299220Y76196D03*
X302953Y76167D03*
X295867Y76567D03*
X296093Y88477D03*
X302853Y89057D03*
X294800Y100593D03*
X295490Y97209D03*
X302370Y95215D03*
X293505Y94965D03*
X303220Y98397D03*
X299590Y121289D03*
X299850Y124708D03*
X293873Y130357D03*
X300118Y250987D03*
X296176Y249585D03*
X295910Y266706D03*
X295110Y262961D03*
X300477Y265010D03*
X300310Y253842D03*
Y257242D03*
X295307Y275439D03*
X294510Y280709D03*
X301473Y282650D03*
X301723Y279150D03*
X297782Y291966D03*
X295010Y286767D03*
X301182Y291966D03*
X305132Y286867D03*
X298332D03*
X301732D03*
X297668Y300709D03*
X294888Y304456D03*
X294781Y309788D03*
X301795Y310398D03*
X296639Y308057D03*
X305250Y310342D03*
X300201Y300874D03*
X303197Y304297D03*
X295200Y321473D03*
X294596Y328129D03*
X297073Y329159D03*
X294218Y343587D03*
X294888Y335326D03*
X298452Y340487D03*
X306820Y342146D03*
X303759Y331478D03*
X294618Y348287D03*
X293467Y352442D03*
X305446Y359450D03*
X298202Y374572D03*
X303171Y374224D03*
X291686Y375177D03*
X295388Y375644D03*
X303722Y385367D03*
X291382Y385457D03*
X291860Y442927D03*
X292170Y445986D03*
X301240Y470885D03*
X291327Y466811D03*
X306220Y477125D03*
X303631Y475607D03*
Y472607D03*
X301209Y488853D03*
X303709Y489353D03*
X300209Y495853D03*
X296913Y514460D03*
X301457Y513837D03*
X295047Y554565D03*
X291357Y586128D03*
X299121Y597542D03*
X306229Y600263D03*
X305602Y620685D03*
Y618185D03*
X299629Y623877D03*
X299090Y634421D03*
X302870Y633981D03*
X297162Y642065D03*
X303110Y639381D03*
X305200Y652883D03*
X301070Y655920D03*
X292850Y656359D03*
X304870Y655747D03*
X306294Y659156D03*
X301360Y652183D03*
X306294Y667156D03*
Y663156D03*
Y675156D03*
Y671156D03*
X294120Y668391D03*
X297770Y674720D03*
X305979Y691156D03*
X306145Y683156D03*
X305979Y687156D03*
X306294Y679156D03*
X292970Y682450D03*
X301696Y701851D03*
Y699351D03*
X293286Y703504D03*
X305990Y697189D03*
X303681Y714421D03*
X305213Y720393D03*
X296885Y718059D03*
X297223Y715523D03*
X291318Y713875D03*
X291790Y735976D03*
X306540Y724266D03*
X297940Y724377D03*
X302660Y736359D03*
X298160Y736489D03*
X302810Y733807D03*
X295700Y733133D03*
X291398Y792234D03*
X299272Y791695D03*
X317334Y10955D03*
X322640Y9774D03*
X317334Y28955D03*
X314640Y63167D03*
X310483D03*
X318543D03*
X322713D03*
X318910Y74595D03*
X314310Y74540D03*
X307740Y74263D03*
X309730Y76232D03*
X321283Y76327D03*
X316623Y76047D03*
X312402Y76587D03*
X314830Y92851D03*
X312183Y88837D03*
X321463Y88517D03*
X315083Y90207D03*
X312223Y96407D03*
X317970Y95961D03*
X313583Y122387D03*
X311420Y250230D03*
X315410Y258656D03*
X312680Y258353D03*
X307204Y304212D03*
X310623Y313589D03*
X313123D03*
X320623D03*
X318123D03*
X315623D03*
X321643Y321928D03*
X309143D03*
X311643D03*
X314143D03*
X316643D03*
X319143D03*
X322765Y327721D03*
X322210Y336696D03*
X319323Y338320D03*
X309510Y344127D03*
X313980Y335813D03*
X321130Y342418D03*
X309190Y336959D03*
X319666Y354376D03*
X319807Y346376D03*
X321150Y357730D03*
X309131Y374573D03*
X314860Y367656D03*
X322255Y371935D03*
X319363Y372149D03*
X315383Y387863D03*
X307116Y385979D03*
X315533Y384749D03*
X321144Y399643D03*
X318644D03*
X316190Y413299D03*
X311610Y432528D03*
X313530Y436460D03*
X315940Y438104D03*
X319478Y429389D03*
X308220Y432552D03*
X322599Y432505D03*
X309440Y426404D03*
X318950Y432473D03*
X316963Y467655D03*
X321357Y456709D03*
X307800Y467859D03*
X310380Y473942D03*
X316956Y478833D03*
X321246Y472669D03*
X315980Y472128D03*
X307670Y473605D03*
X318968Y536052D03*
X318678Y540966D03*
X321828Y541682D03*
X313888Y566003D03*
X313141Y550821D03*
X313075Y553755D03*
X313108Y556556D03*
X313275Y559590D03*
X316788Y572903D03*
X316688Y569603D03*
X313347Y570695D03*
X319135Y591407D03*
X313419Y594040D03*
X313227Y590232D03*
X310919Y594040D03*
X310627Y590232D03*
X315957Y594127D03*
X312641Y611556D03*
X307996Y611536D03*
X312656Y606881D03*
X307994Y606886D03*
X308102Y620685D03*
Y618185D03*
X320367Y618071D03*
X314910Y627222D03*
X317722Y614646D03*
X317492Y618193D03*
X307574Y633762D03*
X314940Y642067D03*
X310453Y642451D03*
X320360Y642275D03*
X311382Y635432D03*
X314790Y652049D03*
X317130Y653628D03*
X314614Y690767D03*
X322440Y700130D03*
X320110Y703093D03*
X313230Y702465D03*
X317580Y719996D03*
X307113Y713003D03*
X321820Y712680D03*
X311990Y717601D03*
X309531Y714298D03*
X312972Y712693D03*
X318090Y712846D03*
X307940Y736445D03*
X311440Y735831D03*
X315940Y735924D03*
X320440Y736031D03*
X307280Y733705D03*
X311083Y791871D03*
X318957Y791695D03*
X323334Y12377D03*
X323871Y25812D03*
Y16812D03*
Y19812D03*
Y28812D03*
X336316Y31815D03*
X327117Y31840D03*
X326353Y63167D03*
X323640Y74393D03*
X326140Y76196D03*
X336024Y88176D03*
X329643Y89887D03*
X324070Y88861D03*
X336340Y99265D03*
X327950Y101057D03*
X323000Y94337D03*
X327430Y108208D03*
X332453Y122297D03*
X323032Y122237D03*
X336495Y290569D03*
X331376Y299883D03*
X328526Y308696D03*
X334478Y299604D03*
X323123Y313589D03*
X333540Y315590D03*
X332700Y333089D03*
X333726Y353801D03*
X333440Y349221D03*
X323040Y354485D03*
X334816Y367787D03*
X337316Y367758D03*
X337330Y372679D03*
X334816Y372609D03*
X326282Y399743D03*
X323644Y399643D03*
X325749Y418701D03*
X328290Y424304D03*
X324940Y413899D03*
X336218Y424850D03*
X325180Y432577D03*
X334420Y428660D03*
X336088Y454511D03*
X326190Y448621D03*
X329120Y449203D03*
X327780Y445819D03*
X331360Y447306D03*
X325040Y480129D03*
X336010Y531598D03*
X324927Y546013D03*
X328592Y541146D03*
X328352Y545412D03*
X325588Y541447D03*
X323154Y556367D03*
Y558867D03*
Y553867D03*
X337550Y558618D03*
Y556118D03*
Y553618D03*
X323088Y561503D03*
X323188Y564503D03*
X330388Y565803D03*
X332388Y567703D03*
X328088Y567503D03*
X329260Y603381D03*
X328930Y611691D03*
X329110Y623514D03*
X330440Y639504D03*
X328032Y642674D03*
X332710Y642694D03*
X328760Y657144D03*
X327540Y653432D03*
X335610Y658177D03*
X332747Y655636D03*
X332190Y659883D03*
X329912Y662383D03*
X335915Y675011D03*
X335390Y667895D03*
X326890Y676159D03*
X327257Y672408D03*
X333180Y665611D03*
X335130Y670744D03*
X334313Y663113D03*
X327500Y667244D03*
X324970Y665128D03*
X337030Y677894D03*
X337798Y686721D03*
X336110Y693934D03*
X331520Y701642D03*
X332720Y698170D03*
X325841Y719731D03*
X330410Y712895D03*
X336990Y735701D03*
X324940Y736067D03*
X329440Y735814D03*
X333940Y735895D03*
X329590Y724283D03*
X334640Y725035D03*
X338270Y733387D03*
X339162Y9304D03*
Y11904D03*
X350411Y21277D03*
X339239Y24232D03*
X339471Y19373D03*
Y16773D03*
X339239Y26832D03*
X346600Y38561D03*
X346150Y36030D03*
X353060Y61504D03*
X350198Y88277D03*
X343111Y88429D03*
X340543Y88647D03*
X345463Y90837D03*
X344770Y101718D03*
X351793Y105404D03*
X343070Y99372D03*
X344073Y124397D03*
X351533Y124697D03*
X351373Y134367D03*
X351503Y130972D03*
X345297Y284849D03*
X342955Y291523D03*
X354170Y308924D03*
X351500Y301795D03*
X353903Y314077D03*
X353841Y306194D03*
X339370Y329176D03*
X341910Y325739D03*
X344720D03*
X339600Y332076D03*
X343880Y356989D03*
X349110Y375767D03*
X352420Y375672D03*
X346020Y374075D03*
X343430Y385937D03*
X343770Y382166D03*
X346862Y424850D03*
X346750Y466532D03*
X352890Y479656D03*
X348000Y479150D03*
X352260Y483029D03*
X338762Y479636D03*
X352160Y502138D03*
X351250Y499752D03*
X353400Y507260D03*
X353460Y504536D03*
X348190Y511550D03*
X353120Y510003D03*
X350690Y516376D03*
X352940Y518025D03*
X340182Y531787D03*
X351110Y531835D03*
X340330Y541931D03*
X341011Y537828D03*
X342190Y565848D03*
X342759Y599193D03*
X339616Y603438D03*
Y605938D03*
X339384Y611544D03*
X339600Y621293D03*
Y618693D03*
X339384Y614144D03*
X353298Y633903D03*
X340340Y638054D03*
X340669Y644827D03*
X345580Y638109D03*
X347670Y642285D03*
X351728Y653860D03*
X351722Y659319D03*
X340630Y655093D03*
X339930Y661219D03*
X353902Y667128D03*
X340530Y675658D03*
X338970Y670776D03*
X340870Y665042D03*
X340525Y686600D03*
X353260Y688757D03*
X351810Y706800D03*
X339750Y695271D03*
X339010Y700406D03*
X338926Y697752D03*
X344780Y713349D03*
X352400Y722132D03*
X341190Y712379D03*
X352010Y713968D03*
X342230Y709384D03*
X343730Y724581D03*
X350180Y735880D03*
X350580Y724427D03*
X345610Y733982D03*
X354060Y734790D03*
X350720Y745722D03*
X346516Y790294D03*
X358285Y21325D03*
X356550Y74767D03*
X365670Y64458D03*
X366733Y88477D03*
X359646Y88174D03*
X362133Y90877D03*
X360827Y108541D03*
X362300Y98674D03*
X369670Y99845D03*
X354943Y104191D03*
X354448Y108092D03*
X367560Y120823D03*
X365283Y128125D03*
X354580Y298101D03*
X364220Y296795D03*
X357400Y307608D03*
X365970Y299194D03*
X369280Y300916D03*
X362660Y316986D03*
X357110Y329210D03*
X359410Y317080D03*
X369040Y316735D03*
X359120Y331164D03*
X357040Y332970D03*
X365026Y332478D03*
X362540Y361443D03*
X354690Y377000D03*
X364645Y377065D03*
X360960Y389080D03*
X364880Y384455D03*
X366140Y407639D03*
X360350Y395873D03*
X369280Y415600D03*
X355250Y420679D03*
X368660Y449478D03*
X369500Y445873D03*
X355150Y486758D03*
X368787Y472998D03*
X368943Y506356D03*
X366426Y527722D03*
Y530222D03*
Y532722D03*
X368238Y522673D03*
X358182Y531231D03*
X357820Y534561D03*
X365329Y546121D03*
X368694Y546159D03*
X369918Y592253D03*
X369848Y588903D03*
X360647Y602636D03*
X354973Y605588D03*
Y602588D03*
Y611588D03*
Y614588D03*
Y620588D03*
Y623588D03*
X361562Y645175D03*
X363530Y629727D03*
X367858Y657573D03*
X365070Y658065D03*
X361650Y658537D03*
X361580Y652755D03*
X362173Y665128D03*
X368200Y672132D03*
X368100Y668133D03*
X361810Y675011D03*
X361660Y671306D03*
X365160Y672922D03*
X361760Y668716D03*
X367399Y684652D03*
X367866Y677326D03*
X361646Y689228D03*
X367066Y681094D03*
X364320Y680434D03*
X367496Y690248D03*
X361510Y680886D03*
X362040Y684875D03*
X364649Y684022D03*
X364844Y698332D03*
X361786Y699128D03*
X361717Y695128D03*
X367480Y705169D03*
X367614Y693053D03*
X361580Y703860D03*
X363590Y702324D03*
X366510Y723622D03*
X361350Y720720D03*
X361490Y712505D03*
X367350Y713661D03*
X363162Y739537D03*
X366430Y731459D03*
X357096Y732976D03*
X360246Y730819D03*
X354520Y728701D03*
X363460Y735388D03*
X363359Y743537D03*
X354420Y749198D03*
X366860Y739956D03*
X366201Y787976D03*
X354390Y790294D03*
X366201Y790976D03*
X379940Y17789D03*
X382990Y17519D03*
X371180Y17789D03*
X370960Y20577D03*
X383247Y64141D03*
X373560Y63973D03*
X380906Y88134D03*
X373820Y88400D03*
X384450Y108830D03*
X372620Y98355D03*
X384090Y98743D03*
X379160Y102923D03*
X374030Y95000D03*
X382087Y103647D03*
X376100Y108780D03*
X376723Y94178D03*
X377363Y121108D03*
X374040Y304980D03*
X373640Y301078D03*
X370460Y305908D03*
X371090Y303487D03*
X384248Y319157D03*
X379560Y374955D03*
X379720Y372257D03*
X378830Y386352D03*
X382620Y391882D03*
X379300Y380862D03*
X379286Y378015D03*
X379750Y383965D03*
X376600Y408045D03*
X382680Y408202D03*
X374560Y412421D03*
X376150Y430405D03*
X383750Y437058D03*
X372320Y439514D03*
X378910Y430874D03*
X371080Y448276D03*
X372710Y445705D03*
X374203Y482079D03*
X377284Y473374D03*
X374207Y479329D03*
X373850Y496585D03*
X381760Y496004D03*
X374203Y491029D03*
X379177Y509798D03*
X383924Y514797D03*
X385040Y521754D03*
X384588Y526069D03*
X382632Y530322D03*
Y527822D03*
Y532822D03*
X373538Y520213D03*
X377150Y543151D03*
X376490Y540574D03*
X382596Y537379D03*
X384485Y552365D03*
X382595Y554166D03*
X385410Y566122D03*
X383344Y590662D03*
Y593262D03*
X373448Y589053D03*
X373518Y592403D03*
X371407Y641507D03*
X383034Y640267D03*
X380101Y660239D03*
X379093Y657739D03*
X376650Y654157D03*
X377211Y673197D03*
X379791Y679454D03*
X376946Y689985D03*
X377100Y697218D03*
X371170Y711574D03*
X382960Y711431D03*
X372110Y720308D03*
X376190Y711259D03*
X375575Y739459D03*
X375548Y731459D03*
X375834Y727459D03*
X377840Y724388D03*
X370430Y749138D03*
X376960Y788580D03*
Y791580D03*
X399002Y17519D03*
X392600Y20548D03*
X389240D03*
X392250Y59899D03*
X389690Y60665D03*
X401310Y61439D03*
X393371Y72919D03*
X397790Y69610D03*
X401220Y65155D03*
X399804Y88778D03*
X397442Y90667D03*
X389400Y89232D03*
X399653Y108357D03*
X391536Y108990D03*
X398820Y95823D03*
X391190Y104173D03*
X388860Y98010D03*
X399613Y104657D03*
X391233Y96093D03*
X399150Y131773D03*
X391880Y131692D03*
X399858Y249711D03*
X399298Y257231D03*
X391998Y258251D03*
X392668Y272511D03*
X399608Y275211D03*
X400928Y293151D03*
X396098Y283931D03*
X399880Y319568D03*
X389740Y404725D03*
X393370Y411618D03*
X399060Y454322D03*
X399050Y450968D03*
X398800Y462248D03*
Y458058D03*
X387080Y486400D03*
X385940Y482478D03*
X388890Y480439D03*
X386410Y477576D03*
X389670Y477262D03*
X389107Y492097D03*
X395690Y512774D03*
X396350Y532016D03*
X396048Y540127D03*
X395922Y536127D03*
X390000Y567345D03*
X396520Y567444D03*
X391630Y597900D03*
X401091Y587054D03*
X398386Y587126D03*
X401422Y597270D03*
X400589Y611672D03*
X400587Y607022D03*
X401422Y599770D03*
X398822Y600399D03*
X398195Y620821D03*
X400695Y618321D03*
X398195D03*
X400695Y620821D03*
X392063Y624109D03*
X401353Y624007D03*
X395701Y637430D03*
X399440Y637340D03*
X396940Y658078D03*
X396366Y653229D03*
X399363Y653588D03*
X396478Y661529D03*
X399911Y661325D03*
X386173Y665065D03*
X391938Y672320D03*
X392097Y676231D03*
X399873Y666411D03*
X400267Y684029D03*
X390000Y689724D03*
X389961Y682218D03*
X396550Y680266D03*
X399829Y690191D03*
X400968Y686699D03*
X400408Y681193D03*
X390660Y686923D03*
X391910Y696742D03*
X392080Y692796D03*
X391740Y705957D03*
X398620Y701411D03*
X390950Y701922D03*
X389350Y711288D03*
X396150Y708926D03*
X394840Y711437D03*
X414949Y75291D03*
X403739Y72783D03*
X404310Y65213D03*
X401670Y93807D03*
X404528Y88702D03*
X409060Y92095D03*
X404813Y93887D03*
X407303Y95117D03*
X408072Y109146D03*
X405688Y253581D03*
X402948Y253251D03*
X405970Y256489D03*
X405038Y267521D03*
X401728Y277251D03*
X401618Y267351D03*
X405248Y272731D03*
X405878Y294071D03*
X408790Y317049D03*
X411240Y316482D03*
X403130Y418091D03*
X406200Y417755D03*
X405980Y414630D03*
X405930Y411386D03*
X406140Y424766D03*
X406150Y433203D03*
X406530Y440667D03*
X406000Y444755D03*
X402900Y444842D03*
X414870Y455166D03*
Y450976D03*
X409054Y483084D03*
X412260Y482881D03*
X413607Y485620D03*
X413733Y490781D03*
X410733D03*
X407733D03*
Y493781D03*
Y496781D03*
Y499781D03*
X410733Y493781D03*
X413733D03*
X410733Y496781D03*
X413733D03*
X410733Y499781D03*
X413733D03*
X409985Y508431D03*
X413222Y508054D03*
X411439Y516956D03*
X405348Y506316D03*
X402458Y505903D03*
X401556Y508937D03*
X409251Y521763D03*
X416515Y547602D03*
X402499Y554143D03*
X404578Y551838D03*
X410522Y593947D03*
X413022D03*
X406884Y594176D03*
X406881Y591322D03*
X405234Y611692D03*
X405249Y607017D03*
X412960Y618207D03*
X405426Y626809D03*
X410315Y614782D03*
X410085Y618329D03*
X413930Y639810D03*
X409520Y637387D03*
X414760Y636225D03*
X410989Y652957D03*
X410918Y649363D03*
X413966Y675624D03*
X411862Y688027D03*
X412250Y683196D03*
X411149Y678387D03*
X415834Y693272D03*
X412878Y693183D03*
X414550Y707464D03*
X414810Y696968D03*
X409581Y711643D03*
X402540Y710649D03*
X412080Y719034D03*
X415730Y710897D03*
X406720Y723395D03*
X413940Y735665D03*
X421473Y160556D03*
Y157556D03*
X421640Y228403D03*
X422698Y244301D03*
X422288Y250661D03*
X419038Y242611D03*
X427768Y253569D03*
X422178Y266891D03*
X428208Y262109D03*
X418575Y263691D03*
X418597Y273538D03*
X418698Y279631D03*
X426948Y281051D03*
X418998Y289871D03*
X422918Y289501D03*
X418718Y301181D03*
X421710Y424527D03*
X430340Y416573D03*
X432450Y418766D03*
X422120Y418288D03*
X432960Y414886D03*
X422080Y414644D03*
Y410454D03*
X421770Y433187D03*
X422860Y441790D03*
X422760Y445581D03*
X425870Y449509D03*
X422460Y449467D03*
X429670Y449552D03*
X419420Y453168D03*
Y457358D03*
X419071Y509283D03*
X431280Y514223D03*
X431356Y516836D03*
X425999Y516211D03*
X424873Y513921D03*
X423278Y525160D03*
X428874Y525193D03*
X417520Y525128D03*
X428874Y530627D03*
X417520Y531177D03*
X428745Y536999D03*
X423332Y536763D03*
X417617Y536773D03*
X426068Y546048D03*
X417979Y545352D03*
X428039Y556539D03*
X423861Y556535D03*
X424904Y586283D03*
X422210Y605343D03*
X419221Y612253D03*
X425151Y608429D03*
X422221Y619873D03*
X420245Y636004D03*
X417422Y637592D03*
X422470Y647852D03*
X422007Y652732D03*
X423623Y645396D03*
X422026Y656883D03*
X429820Y656709D03*
X425146Y672426D03*
X430140Y665660D03*
X417974Y663446D03*
X422222Y675226D03*
X426100Y667884D03*
X422510Y677836D03*
X430873Y684536D03*
X425173Y688588D03*
X427900Y679709D03*
X430861Y679156D03*
X422981Y690351D03*
X430862Y691156D03*
X430813Y687156D03*
X427210Y691934D03*
X423317Y705344D03*
X423055Y696713D03*
X430618Y699156D03*
X430667Y703156D03*
X430731Y707156D03*
X430813Y695156D03*
X426391Y701173D03*
X423242Y707949D03*
X425590Y695895D03*
X421350Y694003D03*
X422940Y723802D03*
X430738Y711156D03*
X427130Y717871D03*
X421730Y717398D03*
X424410Y718429D03*
X417330Y717420D03*
X431440Y723955D03*
X420160Y724309D03*
X430940Y735895D03*
X426430Y735126D03*
X418440Y735930D03*
X420290Y733741D03*
X423900Y736055D03*
X424200Y733399D03*
X426440Y724240D03*
X421321Y791476D03*
X417384D03*
X446268Y69074D03*
X442380Y75513D03*
X439670Y70044D03*
X446088Y90159D03*
Y85159D03*
Y87659D03*
X434158Y122272D03*
X443448Y124552D03*
X441518Y122242D03*
X434158Y125092D03*
X444828Y122132D03*
X446522Y146932D03*
X433253Y160737D03*
X433363Y157607D03*
X442520Y223623D03*
X442580Y236459D03*
X447900Y265292D03*
X441498Y266731D03*
X442148Y279361D03*
X442165Y271284D03*
X441076Y294906D03*
X445540Y288853D03*
X441361Y300812D03*
X438340Y403375D03*
X439150Y400930D03*
X446830Y400551D03*
X445900Y403460D03*
X436370Y410543D03*
X444020Y410374D03*
X439830D03*
X446660Y413325D03*
X446950Y417162D03*
X440900Y446260D03*
X436710D03*
X444850Y446337D03*
X438390Y456129D03*
X438520Y452324D03*
X433720Y449467D03*
X447770Y485290D03*
X445366Y490657D03*
X447781Y523888D03*
X442763Y549595D03*
X435998Y539726D03*
X434203Y542897D03*
X438722Y538842D03*
X448329Y534995D03*
X441326Y556050D03*
X434187Y556444D03*
X437516Y587579D03*
X441230Y587341D03*
X447830Y588739D03*
X446378Y582681D03*
X440040Y608537D03*
X440135Y615808D03*
X445604Y629045D03*
X433872Y645119D03*
X446980Y638774D03*
X437100Y643793D03*
X446500Y645075D03*
X443850Y634754D03*
X439250Y630973D03*
X434681Y642639D03*
X435420Y647117D03*
X446799Y657526D03*
X435972Y655595D03*
X445270Y660832D03*
X444403Y665963D03*
X436000Y675706D03*
X435539Y671628D03*
X436445Y667628D03*
X446900Y714648D03*
X442650Y719485D03*
X446260Y722014D03*
X444530Y723917D03*
X439200Y722093D03*
X447240Y724780D03*
X439940Y735507D03*
X443940Y735681D03*
X435440Y735928D03*
X436440Y724710D03*
X442120Y724781D03*
X447680Y733564D03*
X441006Y791476D03*
X437069D03*
X450618Y69004D03*
X457583Y66384D03*
X454263Y77675D03*
X458598Y77967D03*
X462294Y87759D03*
Y85259D03*
Y90259D03*
X461516Y78275D03*
X450917Y97566D03*
X453168Y105144D03*
X460412Y105704D03*
X457912D03*
X462912D03*
X453298Y122254D03*
X450798D03*
X452158Y124582D03*
X458818Y122065D03*
Y125422D03*
X455292Y162797D03*
X455470Y166963D03*
X452669Y157140D03*
X455913Y178698D03*
X454763Y183503D03*
X453340Y185670D03*
X457482Y183523D03*
X452115Y195057D03*
X459000Y200500D03*
X454150Y249053D03*
X459990Y245930D03*
X457165Y262368D03*
X456800Y259233D03*
X459108Y253181D03*
X449860Y267121D03*
X456530Y256034D03*
X449290Y276227D03*
X449860Y272121D03*
X452900Y281647D03*
X453780Y292411D03*
X453810Y289325D03*
X461130Y408318D03*
X448970Y403846D03*
X451950Y402434D03*
X461080Y411451D03*
X463690Y451813D03*
X461590Y446700D03*
X461540Y449833D03*
X457702Y475480D03*
X460702D03*
X454702D03*
X463702D03*
X450899Y483452D03*
X463540Y495717D03*
X457537Y495546D03*
X454770Y495587D03*
X450813Y492993D03*
X463565Y515723D03*
X452895Y510061D03*
X449402Y515514D03*
X451325Y525981D03*
X454022Y541052D03*
X460236Y581679D03*
X455890Y592792D03*
X450778Y583106D03*
X458600Y599200D03*
X453775Y600614D03*
X453935Y624739D03*
X459690Y626423D03*
X456342Y649436D03*
X461997Y654507D03*
X458650Y666543D03*
X463020Y661023D03*
X464330Y663251D03*
X458820Y674137D03*
X463120Y681992D03*
X460530Y681874D03*
X459650Y685993D03*
X457730Y682010D03*
X456960Y685581D03*
X461960Y684394D03*
X459950Y722720D03*
X453960Y723142D03*
X457060Y722427D03*
X460822Y712620D03*
X451820Y712210D03*
X454070Y714226D03*
X453530Y736212D03*
X458050Y725053D03*
X462440Y735687D03*
X455410Y734113D03*
X450410Y733682D03*
X451320Y725044D03*
X460691Y791476D03*
X456754D03*
X475310Y59746D03*
X464767Y78145D03*
X479450Y63721D03*
X466647Y91224D03*
X466682Y102410D03*
X474381Y125310D03*
X478088Y125219D03*
X471500Y138000D03*
X473200Y140300D03*
X468400Y135800D03*
X475760Y168747D03*
X472670Y166398D03*
X473580Y177859D03*
X474630Y174843D03*
X480220Y185766D03*
X468452Y197934D03*
X476400Y203100D03*
X478000Y212500D03*
X471795Y267941D03*
X470090Y332824D03*
X475190Y339013D03*
X474140Y408318D03*
X469590D03*
X465330D03*
X468210Y401505D03*
X465913Y402659D03*
X465883Y399834D03*
X474080Y411451D03*
X469530D03*
X465270D03*
X480050Y419556D03*
X471540Y437214D03*
X473140Y439971D03*
X469500Y447730D03*
X467920Y451667D03*
X472210Y450267D03*
X465730Y449833D03*
X465790Y446700D03*
X479575Y467597D03*
X479754Y462988D03*
X466702Y475480D03*
X466307Y495676D03*
X467677Y510055D03*
X467496Y513179D03*
X466587Y515764D03*
X467586Y506807D03*
X474130Y553659D03*
X474290Y563565D03*
X471190Y593964D03*
X473294Y613207D03*
X473153Y622451D03*
X465580Y641417D03*
X478905Y659426D03*
X470190Y648693D03*
X474946Y659376D03*
X468540Y655799D03*
X479353Y668666D03*
X466049Y675327D03*
X469977Y676496D03*
X468260Y664366D03*
X469467Y679915D03*
X479409Y682305D03*
X477710Y722299D03*
X466620Y714137D03*
X473940Y714184D03*
X471450Y736368D03*
X466440Y735987D03*
X471310Y733811D03*
X466440Y724465D03*
X470550Y724034D03*
X473560Y724951D03*
X465850Y733428D03*
X476980Y736594D03*
X476160Y734205D03*
X474940Y747192D03*
X476439Y791476D03*
X483240Y60546D03*
X487030Y68075D03*
X488438Y100123D03*
X484068Y99980D03*
X492955Y99440D03*
X491875Y125222D03*
X487140Y123397D03*
X487020Y119754D03*
X494910Y133316D03*
X490760Y154771D03*
X488570Y147486D03*
X487740Y161235D03*
X488220Y157515D03*
X482500Y184169D03*
X487080Y180918D03*
X494210Y175035D03*
X495300Y201600D03*
X487464Y198566D03*
X491046Y207506D03*
X486738Y210434D03*
X487168Y214568D03*
X491320Y231809D03*
X488816Y242877D03*
X484780Y314090D03*
X494850Y315733D03*
X480830Y333921D03*
X495140Y385762D03*
X486670Y426196D03*
X495500Y447465D03*
X483685Y473522D03*
X483641Y479628D03*
X492260Y482826D03*
X494980Y482979D03*
X486640Y543687D03*
X485510Y536673D03*
X489938Y563425D03*
X486720Y563730D03*
X481380Y553210D03*
X490658Y579025D03*
X487398Y576665D03*
X490693Y570770D03*
X490538Y567825D03*
X481410Y573563D03*
X485890Y590563D03*
X489380Y590839D03*
X485380Y596505D03*
X490040Y622140D03*
X491100Y644351D03*
X491380Y639279D03*
X495900Y641804D03*
X491930Y654203D03*
X495622Y660178D03*
X492310Y650516D03*
X482180Y646278D03*
X493020Y646701D03*
X491157Y675604D03*
X491044Y667604D03*
X491060Y671604D03*
X492770Y665090D03*
X491189Y679656D03*
X494323Y687669D03*
X492294Y682347D03*
X483056Y679628D03*
X491167Y687507D03*
X494340Y691623D03*
X491067Y699656D03*
X491380Y694656D03*
X496000Y736152D03*
X483180Y736506D03*
X487940Y735681D03*
X491890Y735740D03*
X494850Y733252D03*
X480620Y734244D03*
X480376Y791476D03*
X496955Y99958D03*
X508955Y99978D03*
X500955Y100139D03*
X504955Y99830D03*
X508904Y124063D03*
X499456Y128666D03*
X502132Y146686D03*
X500963Y162261D03*
X501040Y177297D03*
X502999Y180541D03*
X499154Y194198D03*
X505580Y192555D03*
X498875Y217172D03*
X499075Y235575D03*
X496123Y233500D03*
X504941Y227859D03*
X499405Y242877D03*
X507000Y239000D03*
X511070Y310719D03*
X509140Y338005D03*
X504897Y390481D03*
X510577Y417741D03*
X502687Y417453D03*
X497818Y440265D03*
X509464Y450265D03*
X505442Y458719D03*
X505843Y465018D03*
X511070Y493380D03*
X511520Y496255D03*
X505740Y495880D03*
X511560Y513792D03*
X504613Y522050D03*
X498920Y523803D03*
X503958Y529405D03*
X501331Y528932D03*
X500138Y543225D03*
X503448Y540235D03*
X505718Y542865D03*
X500038Y555925D03*
Y550725D03*
X500138Y563025D03*
Y558625D03*
X500338Y566425D03*
X510338Y571325D03*
X500438Y574925D03*
X500419Y578644D03*
X500538Y572025D03*
X500338Y569425D03*
X499868Y585725D03*
X505738Y590525D03*
Y600425D03*
X496140Y608883D03*
X504268Y608625D03*
X500098Y608885D03*
X509238Y608515D03*
X508024Y613598D03*
X504980Y616425D03*
X498350Y627580D03*
X505780Y642543D03*
X501120Y633249D03*
X510700Y634300D03*
X496690Y633589D03*
X501940Y644073D03*
X498666Y653012D03*
X504836Y657097D03*
X503680Y659666D03*
X498040Y675306D03*
X498870Y668324D03*
X506376Y687436D03*
X506470Y683512D03*
X500710Y706582D03*
X510608Y717448D03*
X499842Y710582D03*
X499452Y714582D03*
X502890Y736349D03*
X506105Y724132D03*
X498080Y733252D03*
X509855Y724107D03*
X500260Y729094D03*
X500061Y791476D03*
X496124D03*
X512955Y100428D03*
X524955Y99359D03*
X516955Y100333D03*
X520955Y100444D03*
X525570Y124623D03*
X518248Y137692D03*
X518477Y141401D03*
X527349Y152246D03*
X526875Y161838D03*
X518725Y170525D03*
X512600Y178900D03*
X512200Y204200D03*
X526443Y194116D03*
X514500Y194300D03*
X525293Y191705D03*
X511997Y207730D03*
X512160Y217073D03*
X526657Y207363D03*
X524405Y212531D03*
X514766Y208222D03*
X519183Y224173D03*
X519300Y220500D03*
X516625Y230075D03*
X515675Y234555D03*
X524675Y234766D03*
X517189Y226229D03*
X518590Y310129D03*
X526250Y310940D03*
X519650Y320384D03*
X522420Y315475D03*
X517260Y315978D03*
X523930Y321642D03*
X514400Y340829D03*
X520510Y337299D03*
X526440Y432077D03*
X515780Y434039D03*
X523667Y438452D03*
X522379Y431974D03*
X513140Y452621D03*
X519440Y452321D03*
X526340D03*
X516353Y443517D03*
X523838Y442723D03*
X513140Y459721D03*
Y466021D03*
X525640Y473021D03*
X519640D03*
X513140D03*
X516353Y480708D03*
X525603Y480187D03*
X519490Y496645D03*
X525698Y496724D03*
X519938Y493125D03*
X524938D03*
X522250Y513692D03*
X514430Y511801D03*
X519430D03*
X527138Y529525D03*
X523938Y528725D03*
X515110Y528785D03*
X519438Y543025D03*
X513480Y541499D03*
X518938Y540425D03*
X521938Y540325D03*
X516380Y540364D03*
X525338Y540125D03*
X513838Y556925D03*
X516738Y562425D03*
X513738D03*
X512354Y590825D03*
X515413Y590950D03*
X524638Y590225D03*
X520228Y590335D03*
X519638Y600425D03*
X523538Y600325D03*
X527438D03*
X525570Y602466D03*
X523800Y611145D03*
X520370Y625158D03*
X519830Y634663D03*
X511910Y638722D03*
X515371Y658880D03*
X515438Y649996D03*
X517806Y670102D03*
X526610Y672286D03*
X515425Y685783D03*
X518382Y678247D03*
X518947Y685122D03*
X518500Y723073D03*
X514620Y713193D03*
X517443Y717011D03*
X517775Y711203D03*
X522865Y711178D03*
X514498Y716473D03*
X519440Y735681D03*
X512140Y736554D03*
X514901Y724120D03*
X523370Y724131D03*
X516940Y735683D03*
X521800Y732667D03*
X514420Y733131D03*
X524576Y733227D03*
X519746Y791476D03*
X515809D03*
X542180Y93534D03*
X542248Y106333D03*
X532955Y108669D03*
X528955Y99781D03*
X532955Y100604D03*
X542700Y112881D03*
X527898Y147146D03*
X538655Y151415D03*
X538294Y159415D03*
X533483Y177449D03*
X533797Y180764D03*
X529272Y178311D03*
X542002Y180100D03*
X538525Y213425D03*
X532500Y206500D03*
X536676Y234993D03*
X536576Y246993D03*
X539438Y250323D03*
X536972Y242993D03*
X536476Y238993D03*
X529527Y265584D03*
X532794Y282068D03*
X528680Y317349D03*
X541380Y340358D03*
X543110Y333848D03*
X536180Y341432D03*
X536170Y336603D03*
X531795Y340409D03*
X531430Y337074D03*
X527603Y337208D03*
X529910Y419478D03*
X540700Y418852D03*
X536440Y421973D03*
X530940Y422207D03*
X541440Y431787D03*
X536440Y431923D03*
X531440Y432178D03*
X542738Y455823D03*
X530038Y444323D03*
X533040Y453221D03*
X534738Y445523D03*
X541838Y450723D03*
X533740Y458021D03*
Y465021D03*
X542738Y463123D03*
X533740Y473021D03*
X540938Y473623D03*
X535729Y476632D03*
X539419Y491107D03*
X532934Y491384D03*
X538038Y488323D03*
X533038D03*
X543280Y491040D03*
X530438Y529525D03*
X541538Y529625D03*
X534401Y529562D03*
X530638Y539525D03*
X534638Y539825D03*
X541238Y539625D03*
X528138Y539925D03*
X533038Y590325D03*
X540701Y590162D03*
X527638Y590325D03*
X535776Y590487D03*
X530338Y590325D03*
X536438Y600425D03*
X542438Y613723D03*
X540540Y601008D03*
X538828Y602945D03*
X538400Y613804D03*
X541980Y620227D03*
X527828Y615387D03*
X540048Y629641D03*
X539471Y632476D03*
X530779Y637354D03*
X532479Y633588D03*
X535230Y648711D03*
X541440Y647594D03*
X531970Y650491D03*
X539120Y670129D03*
X539830Y667332D03*
X531599Y689838D03*
X533270Y679351D03*
X531597Y697509D03*
X535485Y715182D03*
X535272Y711217D03*
X535062Y708679D03*
X530012Y708618D03*
X543193Y710787D03*
X537503Y710088D03*
X528388Y722903D03*
X537702Y735662D03*
X541940Y735681D03*
X528440D03*
X531845Y724095D03*
X532940Y734810D03*
X531029Y733142D03*
X539431Y791476D03*
X535494D03*
X547248Y106582D03*
X555938Y97292D03*
X551454Y97154D03*
X547480Y96632D03*
X546306Y110193D03*
X548367Y135415D03*
X548007Y139415D03*
X547543Y143415D03*
X558845Y158697D03*
X555510Y173872D03*
X555836Y179259D03*
X546000Y180000D03*
X558768Y191223D03*
X553909Y207401D03*
X547927Y212190D03*
X558416Y210682D03*
X544700Y216100D03*
X549909Y207060D03*
X555750Y212029D03*
X544500Y207000D03*
X545424Y226722D03*
X546690Y233066D03*
X544990Y231086D03*
X549488Y233003D03*
X549358Y230153D03*
X552120Y232388D03*
X552050Y229124D03*
X550040Y243929D03*
X550090Y247079D03*
X557207Y274828D03*
X551341Y274262D03*
X557222Y285109D03*
X553690Y340829D03*
X547340Y339103D03*
X555707Y389146D03*
X548470Y378127D03*
X549760Y407251D03*
X553750Y410420D03*
X544500Y422583D03*
X557017Y438968D03*
X543381Y448428D03*
X556771Y456156D03*
X556959Y443009D03*
X551140Y445789D03*
X555140Y445940D03*
X556971Y460656D03*
X543338Y459323D03*
X547340Y484025D03*
X548000Y509493D03*
X547880Y515743D03*
X544370Y510267D03*
Y515267D03*
X544138Y530125D03*
X545413Y547950D03*
X551161Y547148D03*
X545138Y539725D03*
X551538Y540325D03*
X551338Y544225D03*
X551438Y561225D03*
X551338Y551100D03*
X551438Y563825D03*
X551538Y568525D03*
X551238Y571725D03*
X550938Y587325D03*
X547000Y590163D03*
X551238Y584025D03*
X543850Y590313D03*
X548138Y600425D03*
X544638Y600525D03*
X553619Y601204D03*
X546938Y613828D03*
X552849Y631652D03*
X545377Y647594D03*
X555356Y665156D03*
Y669156D03*
X555308Y673156D03*
X555357Y689156D03*
X555284Y685156D03*
X555235Y681156D03*
X555308Y677156D03*
X547346Y697581D03*
X544984Y699419D03*
X555150Y697156D03*
X555271Y693156D03*
X547542Y711523D03*
X555148Y735583D03*
X550940Y735681D03*
X546440D03*
X553193Y724847D03*
X546566Y724119D03*
X544082Y724460D03*
X549049Y724412D03*
X557426Y724436D03*
X555179Y791476D03*
X566090Y109136D03*
X560938Y97195D03*
X565938Y96820D03*
X563230Y150222D03*
X563274Y162169D03*
X559646Y174476D03*
X572782Y195199D03*
X561909Y207393D03*
X569874Y231795D03*
X572690Y226569D03*
X572020Y222393D03*
X567980Y222353D03*
X568410Y226647D03*
X561258Y230153D03*
X566248Y230283D03*
X563506Y232027D03*
X571576Y246693D03*
X564676D03*
X571476Y260093D03*
X564676D03*
Y253693D03*
X566774Y275195D03*
X566876Y289890D03*
X567320Y415088D03*
X565977Y456156D03*
X566059Y460956D03*
X561610Y503885D03*
X560960Y510151D03*
X571830Y509411D03*
X573840Y512108D03*
X564370Y504117D03*
Y509117D03*
X568068Y525306D03*
X567493Y532225D03*
X561065Y543998D03*
X560838Y540325D03*
X574738Y587425D03*
X574645Y583525D03*
X566053Y627509D03*
X571650Y625998D03*
X563850Y659575D03*
X563840Y653515D03*
X563586Y682137D03*
X563577Y692284D03*
X563441Y676872D03*
X563393Y686908D03*
X568215Y702343D03*
X568288Y715547D03*
X568908Y735883D03*
X573440Y735681D03*
X564438Y735853D03*
X560350Y735807D03*
X573440Y724053D03*
X568940Y724090D03*
X562395Y724557D03*
X571232Y732545D03*
X559116Y791476D03*
X588943Y98963D03*
X589308Y103990D03*
X583829Y117732D03*
X583661Y121836D03*
X583547Y128232D03*
X583970Y144589D03*
X580180Y148894D03*
X579540Y143304D03*
X584438Y160933D03*
X582920Y194220D03*
X579707Y220662D03*
X583707Y220762D03*
X587707Y220728D03*
X576105Y231626D03*
X578076Y246693D03*
Y253393D03*
Y260093D03*
X575874Y282395D03*
X581474Y274795D03*
X575874Y289895D03*
Y285995D03*
X575880Y293016D03*
X575908Y295606D03*
X583853Y313783D03*
X585584Y308881D03*
X579168Y313641D03*
X583737Y321204D03*
X579788Y354743D03*
X575550Y463784D03*
X575650Y469996D03*
X588153Y459599D03*
X579600Y508878D03*
X578840Y512108D03*
X575438Y545425D03*
X589036Y548825D03*
X583890Y537093D03*
X575238Y552025D03*
X588540Y557418D03*
X584413Y563198D03*
X583538Y552225D03*
X575038Y554725D03*
X575138Y559825D03*
X575038Y567725D03*
X575538Y571725D03*
X574876Y575625D03*
X578110Y582149D03*
X582023Y571242D03*
X586369Y585801D03*
X578399Y585696D03*
X579500Y625963D03*
X577000Y620029D03*
X585500Y620926D03*
X587440Y656958D03*
X576700Y655594D03*
X588950Y650070D03*
X579020Y658250D03*
X580740Y653286D03*
X584903Y663828D03*
X576846Y675985D03*
X579076Y669603D03*
X576520Y667750D03*
X586060Y682582D03*
X587040Y688218D03*
X589050Y680160D03*
X579980Y683140D03*
X576644Y679562D03*
X578030Y690236D03*
X577010Y682718D03*
X576519Y687665D03*
X589500Y690546D03*
X586995Y694080D03*
X579151Y707857D03*
X588151D03*
X584101Y707893D03*
X576442Y705492D03*
X585400Y697289D03*
X579220Y720776D03*
X585693Y722428D03*
X583440Y735856D03*
X587940Y735681D03*
X587963Y724108D03*
X577940Y724127D03*
X580510Y724421D03*
X578802Y791476D03*
X574864D03*
X603158Y91535D03*
X601374Y94048D03*
X604543Y94886D03*
X598123Y102023D03*
X595318Y98854D03*
X593850Y103755D03*
X592392Y100623D03*
X594920Y123370D03*
X595345Y120216D03*
X595438Y138130D03*
X593537Y161023D03*
X592917Y171906D03*
X592491Y175906D03*
X593277Y179955D03*
X595707Y220995D03*
X591707Y221095D03*
X597074Y239995D03*
X600874Y239795D03*
X604774Y249795D03*
X596774D03*
X600874D03*
X604674Y239995D03*
X592874Y250995D03*
X605674Y236295D03*
X592858Y247079D03*
X593459Y240780D03*
X594067Y265168D03*
X594174Y256695D03*
X593874Y262395D03*
X596574Y268695D03*
X600674Y268795D03*
X604574D03*
X604926Y278476D03*
X604774Y271893D03*
X590874Y275195D03*
X592201Y308988D03*
X591977Y319360D03*
X598551Y329541D03*
X601450Y326509D03*
X600770Y358702D03*
X605746Y387837D03*
X605573Y393920D03*
X594860Y395088D03*
X600680Y412780D03*
X598670Y508170D03*
X596560Y536108D03*
X606300Y551844D03*
X604437Y557956D03*
X596050Y557563D03*
X596530Y574903D03*
X596495Y578903D03*
X596484Y582903D03*
X596209Y586903D03*
X590898Y597158D03*
X605290Y594166D03*
X596401Y589852D03*
X605521Y601097D03*
X590842Y608112D03*
X591023Y600384D03*
X605362Y609413D03*
X590646Y618751D03*
X605010Y641435D03*
X600980Y641533D03*
X594733Y653385D03*
X591840Y659568D03*
X596470Y655231D03*
X601588Y664798D03*
X602332Y671156D03*
X593142Y663828D03*
X602020Y679156D03*
X600650Y707835D03*
X592440Y723768D03*
X596860Y723422D03*
X606146Y713145D03*
X601813Y715579D03*
X598880Y719232D03*
X601440Y735681D03*
X605938Y735665D03*
X596940Y735681D03*
X593004Y735662D03*
X598487Y791476D03*
X594550D03*
X618623Y108918D03*
X608274Y249795D03*
X608774Y239995D03*
X608274Y268795D03*
X612974Y269095D03*
X609150Y328514D03*
X616490Y327534D03*
X619190Y336986D03*
X608306Y359971D03*
X617592Y362539D03*
X608869Y396959D03*
X608821Y403445D03*
X619014Y408353D03*
X621399Y420400D03*
X611130Y417928D03*
X609370Y452974D03*
X609300Y531638D03*
X613541Y546764D03*
X616320Y537066D03*
X609168Y554851D03*
X621937Y558276D03*
X621840Y555040D03*
X609060Y552101D03*
X607077Y566915D03*
X612270Y586543D03*
X612493Y607666D03*
X612370Y614143D03*
X614579Y645072D03*
X608310Y641603D03*
X620510Y639427D03*
X616471Y636215D03*
X607620Y647169D03*
X615700Y657757D03*
X610651Y675156D03*
X614909Y671938D03*
X617235Y689036D03*
X610693Y679333D03*
X610570Y691156D03*
X610550Y686640D03*
X610810Y683933D03*
X621410Y696941D03*
X607020Y704644D03*
X608975Y708094D03*
X612914Y707630D03*
X610540Y697964D03*
X618020Y700000D03*
X610570Y695156D03*
X611244Y709830D03*
X621254Y713788D03*
X617093Y709167D03*
X616070Y720838D03*
X620830Y717516D03*
X609840Y713617D03*
X619590Y735383D03*
X614732Y735517D03*
X608791Y735775D03*
X618172Y791476D03*
X614235D03*
X610298D03*
X626380Y85117D03*
X624020Y83243D03*
X623750Y87130D03*
X626380Y88518D03*
X623725Y90422D03*
X626180Y91919D03*
X623820Y93654D03*
X626320Y96084D03*
X623610Y97125D03*
X626180Y99276D03*
X624358Y176090D03*
X632483Y192781D03*
X624950Y189801D03*
X632485Y202077D03*
X622470Y261628D03*
X635000Y265400D03*
X624101Y296525D03*
X632376Y305257D03*
X631702Y307880D03*
X632122Y312898D03*
X635652Y313118D03*
X636962Y310928D03*
X623820Y321062D03*
X633470Y326710D03*
X628140Y317610D03*
X631860Y321455D03*
X627000Y327926D03*
X622890Y325227D03*
X633652Y315198D03*
X630190Y336986D03*
X625190D03*
X624889Y357778D03*
X637738Y392034D03*
X636990Y386464D03*
X627022Y383713D03*
X633633Y403717D03*
X637614Y397259D03*
X636938Y402885D03*
X633663Y411009D03*
X633455Y427209D03*
X634578Y424964D03*
X626250Y450248D03*
X631280Y446007D03*
X635120Y456136D03*
X630570Y451450D03*
X635545Y465888D03*
X622100Y465822D03*
X625900Y461769D03*
X632680Y466669D03*
X636010Y469995D03*
X622798Y546764D03*
X632362Y565543D03*
X627047Y581066D03*
X636868Y593141D03*
X630768Y593241D03*
X624468D03*
Y612141D03*
X624368Y605941D03*
Y599741D03*
X629868Y612241D03*
X635968D03*
X627986Y625895D03*
X630984Y624829D03*
X623290Y641222D03*
X634137Y639352D03*
X630137Y639312D03*
X631930Y655254D03*
X634251Y683493D03*
X623940Y723503D03*
X622290Y708516D03*
X623960Y735141D03*
X628380Y735476D03*
X631690Y733744D03*
X635460Y735130D03*
X630040Y745114D03*
X636390Y775395D03*
X632030Y779137D03*
X632000Y775400D03*
X629983Y791476D03*
X633920D03*
X643957Y53688D03*
X639957Y53849D03*
X638970Y132241D03*
X640448Y294422D03*
X643170Y294282D03*
X641227Y297070D03*
X644113Y297071D03*
X653352Y291388D03*
X642932Y284768D03*
X640112Y285042D03*
X640171Y311965D03*
X644105D03*
X652362Y306598D03*
X651352Y323938D03*
X653162Y318398D03*
X650162D03*
X648450Y338711D03*
X646013Y358110D03*
X648838Y349785D03*
X642863Y358010D03*
X646171Y364676D03*
X647440Y386383D03*
X647340Y393283D03*
X647440Y408383D03*
X647340Y400083D03*
X651138Y417385D03*
X648493Y417221D03*
X641480Y430289D03*
X650079D03*
X648208Y427819D03*
X643208D03*
X653070Y427500D03*
X641690Y443656D03*
X653360Y446280D03*
X651840Y460012D03*
X648920Y457851D03*
X646381Y478679D03*
X651395Y487265D03*
X650150Y494337D03*
X638350Y507893D03*
X641842Y516730D03*
X640470Y523266D03*
X645150Y535704D03*
X638166Y560972D03*
X638286Y557415D03*
X643012Y565243D03*
X651437Y569676D03*
X646732Y580781D03*
X641870Y580743D03*
X646870Y569443D03*
Y576243D03*
X643568Y593241D03*
Y612341D03*
Y606641D03*
Y599541D03*
X642795Y624818D03*
X648701Y624774D03*
X638470Y639290D03*
X650928D03*
X646737Y639413D03*
X642737D03*
X651226Y666288D03*
X639940Y687841D03*
X640330Y684439D03*
X642999Y685781D03*
X648077Y713569D03*
X644950Y719110D03*
X653500Y732583D03*
X639928Y738905D03*
X638890Y734879D03*
X639920Y753526D03*
X650400Y770522D03*
X649640Y757527D03*
X646370Y759252D03*
X652212Y786700D03*
X659947Y53722D03*
X658769Y143630D03*
X658767Y151013D03*
X658959Y165625D03*
X658972Y158337D03*
X667300Y188112D03*
X660700Y203282D03*
X669250Y203317D03*
X665320Y203247D03*
X664560Y195018D03*
Y191443D03*
X660770Y214951D03*
X665390Y214916D03*
X661160Y235485D03*
X658582Y222614D03*
X658601Y229770D03*
X661190Y246085D03*
X656270Y299379D03*
X654060Y302459D03*
X659350Y298810D03*
X654352Y323938D03*
X655122Y315070D03*
X656730Y338633D03*
X666270Y359134D03*
X660138Y365885D03*
X659543Y377086D03*
X662390Y377039D03*
X653938Y364885D03*
X654340Y386283D03*
X661140D03*
X654840Y408483D03*
X661940Y408383D03*
X666312Y417742D03*
X658295Y417662D03*
X653649Y417582D03*
X668779Y417135D03*
X663674Y417999D03*
X656021Y427864D03*
X665766Y427868D03*
X663339Y425601D03*
X658339D03*
X658680Y446610D03*
X667428Y463432D03*
X666928Y468132D03*
X662630Y500823D03*
X664024Y513414D03*
X668823Y532470D03*
X668627Y527718D03*
X665170Y595943D03*
X661396Y588900D03*
X655445Y591918D03*
X664603Y601976D03*
X655978Y609635D03*
X656070Y612743D03*
X655688Y601761D03*
X664870Y614543D03*
X654645Y627064D03*
X667610Y617197D03*
X659600Y623785D03*
X655873Y615540D03*
X655170Y639432D03*
X656971Y660492D03*
X668000Y676595D03*
X656254Y683277D03*
X663040Y688057D03*
X665050Y680648D03*
X655610Y706309D03*
X656505Y701191D03*
X654514Y720674D03*
X657320Y723584D03*
X654050Y718086D03*
X656650Y713057D03*
X659200Y721454D03*
X654000Y736400D03*
X656660Y736218D03*
X655574Y728674D03*
X657570Y730414D03*
X658860Y727383D03*
X656000Y732400D03*
X664460Y785890D03*
X657010Y786039D03*
X661479Y791476D03*
X665416D03*
X679927Y53881D03*
X675927Y53779D03*
X670980Y77061D03*
X671810Y106472D03*
X670280Y188112D03*
X676590Y188198D03*
X680100Y188182D03*
X680220Y200725D03*
X678650Y203480D03*
X681770Y203514D03*
X682140Y191214D03*
Y194615D03*
X680310Y217357D03*
X678750Y214908D03*
X681870Y214942D03*
X669320Y214986D03*
X671129Y305579D03*
X671166Y302550D03*
X679430Y350013D03*
X672752Y366160D03*
X679552Y372873D03*
X669540Y386283D03*
X678099Y389915D03*
X674235Y379364D03*
X677946Y387211D03*
X678986Y392661D03*
X669440Y395183D03*
Y408483D03*
X669540Y402783D03*
X678338Y405185D03*
X679138Y397985D03*
X680017Y403143D03*
X678838Y407785D03*
X683128Y451332D03*
X680228Y451432D03*
X672660Y441007D03*
X670428Y463532D03*
X669728Y468032D03*
X672628D03*
X672190Y457216D03*
X683112Y479786D03*
X684876Y497385D03*
X678450Y508438D03*
X680790Y504521D03*
X678315Y540752D03*
X684620Y535923D03*
X678217Y536752D03*
X678360Y557426D03*
X673950Y557314D03*
X677850Y562515D03*
X673700D03*
X677730Y567706D03*
X673590Y567696D03*
X670940Y612070D03*
X683720Y631732D03*
X681310Y666671D03*
X671400Y666151D03*
X669390Y695406D03*
X672630Y720752D03*
X675100Y749300D03*
X672710Y746235D03*
X672500Y749179D03*
X684500Y786665D03*
X676390Y778439D03*
X677490Y782114D03*
X673290Y782855D03*
X677227Y786454D03*
X669320Y783845D03*
X683520Y789080D03*
Y792080D03*
X688160Y64459D03*
X689500Y120441D03*
X691148Y140140D03*
X698150Y136791D03*
X691280Y149571D03*
X691314Y145071D03*
X699990Y149631D03*
X700060Y144981D03*
X687571Y172292D03*
X693520Y186376D03*
X697850Y186441D03*
X689820Y200159D03*
Y203491D03*
X689480Y191144D03*
X691970Y216820D03*
X691690Y212100D03*
X693540Y205721D03*
X697800Y205879D03*
X692010Y221158D03*
X687584Y233034D03*
Y251770D03*
X689864Y392130D03*
X686686Y392522D03*
X687121Y407004D03*
X689864Y398141D03*
X686686Y397522D03*
X689527Y407843D03*
X686731Y413349D03*
X689527Y412843D03*
X687130Y464132D03*
X691070Y464058D03*
X691161Y518684D03*
X692520Y506898D03*
X696494Y513677D03*
X700719Y516954D03*
X686661Y519199D03*
X698438Y524890D03*
X694150Y536155D03*
X690040Y535797D03*
X687183Y539585D03*
X691532Y559789D03*
Y567789D03*
Y571789D03*
Y579789D03*
Y587789D03*
X695600Y590788D03*
X685410Y621250D03*
X688340Y621294D03*
X687660Y631799D03*
X692720Y670540D03*
X698830Y670652D03*
X689100Y680291D03*
X688510Y735294D03*
X707176Y50574D03*
X706380Y75482D03*
X708130Y106389D03*
X701687Y212132D03*
X700947Y216868D03*
X700994Y221368D03*
X701770Y331938D03*
X707942Y448676D03*
X714639Y454872D03*
X702730Y455483D03*
X715528Y459332D03*
X710768Y475972D03*
X715328Y481122D03*
X707736Y510140D03*
X712281Y525785D03*
X712820Y519647D03*
X710585Y539103D03*
X701170Y538508D03*
X708258Y549815D03*
X701023Y553658D03*
X710873Y563230D03*
X713300Y578995D03*
X713190Y583032D03*
X715282Y620282D03*
X711612Y620383D03*
X712732Y631749D03*
X716064D03*
X703570Y673036D03*
X707660Y673204D03*
X713910Y681330D03*
X708450Y695489D03*
X705870Y721832D03*
X709500Y736800D03*
X706575Y740425D03*
X716245Y765576D03*
X704786Y791274D03*
X708723Y791092D03*
X709040Y787507D03*
X719800Y24920D03*
X726160Y109316D03*
X726190Y105325D03*
X726160Y112508D03*
X726500Y123466D03*
X726400Y130303D03*
X726470Y126659D03*
X726430Y465371D03*
X731340Y476723D03*
X718431Y483368D03*
X721290Y484381D03*
X719370Y472436D03*
X725730Y486788D03*
X729640Y486848D03*
X727602Y500100D03*
X720150Y491632D03*
X729942Y515757D03*
X719332D03*
X728661Y558934D03*
X731251Y558975D03*
X726154Y559002D03*
X720445Y558990D03*
X723370Y558906D03*
X720052Y620480D03*
X719092Y631682D03*
X717372Y634474D03*
X718510Y681526D03*
X721100Y689400D03*
X731200Y716200D03*
X729500Y737400D03*
X730800Y728400D03*
X729500Y746300D03*
X718150Y763015D03*
X721100Y762903D03*
X721245Y765576D03*
X727570Y775278D03*
X730990Y775334D03*
X726925Y778490D03*
X731925D03*
X721790Y791408D03*
X722590Y787885D03*
X738620Y109351D03*
X738650Y105360D03*
X744760Y103711D03*
X744790Y106938D03*
X747710Y100293D03*
X738620Y112543D03*
X738370Y123395D03*
X745070Y110183D03*
X738270Y130232D03*
X738340Y126588D03*
X747080Y129815D03*
X747600Y323527D03*
X745220Y327250D03*
X741401Y454832D03*
X737350Y459823D03*
X742779Y487639D03*
X743364Y478975D03*
X743150Y483502D03*
X738130Y502748D03*
X732817Y489435D03*
X744090Y575066D03*
X747470Y585542D03*
X747460Y582318D03*
X734460Y788654D03*
Y791654D03*
X762590Y106529D03*
X762630Y103302D03*
X751080Y100293D03*
X754580Y124020D03*
X748070Y110209D03*
X751180D03*
X754610Y127247D03*
X750930Y129815D03*
X750430Y314330D03*
X750350Y311343D03*
X750700Y323771D03*
X753230Y328262D03*
X759400Y334839D03*
X754850Y335055D03*
X755500Y337791D03*
X757823Y451032D03*
X758494Y455532D03*
X758500Y469500D03*
X757500Y474000D03*
X748300Y496800D03*
X751730Y583047D03*
X749520Y658372D03*
X765250Y357789D03*
X765610Y361194D03*
X766840Y561290D03*
X766920Y564080D03*
X766950Y558318D03*
X766820Y569897D03*
X766900Y567233D03*
Y572869D03*
X770850Y575760D03*
X770710Y584054D03*
G36*
G01X-36897Y131113D02*
G02X-34847I1025J-400D01*
G01X-33897D01*
G02Y130313I1025J-400D01*
G01X-34847D01*
G02X-36897I-1025J400D01*
G01X-37847D01*
G02Y131113I-1025J400D01*
G01X-36897D01*
G37*
G36*
G01Y238433D02*
G02X-34847I1025J-400D01*
G01X-33897D01*
G02Y237633I1025J-400D01*
G01X-34847D01*
G02X-36897I-1025J400D01*
G01X-37847D01*
G02Y238433I-1025J400D01*
G01X-36897D01*
G37*
G54D31*
X86880Y143269D03*
X749968Y29361D03*
G54D40*
X154307Y507507D03*
X154517Y513931D03*
X154038Y511386D03*
X153967Y517186D03*
X159185Y531356D03*
X153731Y520734D03*
X162335Y521906D03*
X155400Y533436D03*
X154246Y527468D03*
X162335Y528206D03*
X159186Y534504D03*
X159185Y543953D03*
X155060Y545526D03*
X154945Y542383D03*
Y536083D03*
Y539233D03*
X159185Y547103D03*
X154900Y548682D03*
X162315Y553391D03*
X154900Y551832D03*
X159186Y553402D03*
X157611Y557468D03*
X154410Y557990D03*
X178818Y274540D03*
X178085Y518755D03*
X168617Y525756D03*
X172371Y519783D03*
X174720Y531356D03*
X171606Y527511D03*
X178117Y528187D03*
X178082Y537654D03*
X178099Y550267D03*
X174105Y542290D03*
X167027Y539526D03*
Y536376D03*
X173217Y536556D03*
X181818Y274540D03*
X186417Y518526D03*
X186467Y514036D03*
X184920Y508626D03*
X181232Y515607D03*
X187417Y508756D03*
X189007Y514846D03*
X181232Y528205D03*
X187875Y534128D03*
X181232Y543953D03*
X184384Y537656D03*
X181232Y537654D03*
X184384Y543955D03*
X188927Y537836D03*
X190434Y546870D03*
X188383Y556895D03*
X184386Y553406D03*
X208050Y528883D03*
X209886Y539962D03*
X201509Y539853D03*
X207309Y539953D03*
X199709Y551653D03*
X208109Y551053D03*
X202486Y551130D03*
X216184Y268587D03*
X214626Y516492D03*
X227326Y505741D03*
X227329Y508894D03*
X223709Y505353D03*
X216564Y528902D03*
X214118Y528583D03*
X218751Y543835D03*
X233626Y502591D03*
X230476D03*
X243075D03*
X230476Y505741D03*
X236776Y508891D03*
Y518339D03*
X233626Y508891D03*
Y515190D03*
X230476D03*
X233626Y518339D03*
X236776Y512040D03*
X243075Y508891D03*
X230476D03*
X236776Y515190D03*
X230476Y518339D03*
Y512040D03*
X233626D03*
X239925Y518339D03*
X233626Y521489D03*
X236776Y534087D03*
X233626Y527788D03*
X230476Y534087D03*
X236776Y521489D03*
Y527788D03*
X233626Y524639D03*
X236776D03*
X230476D03*
X233626Y534087D03*
X239925Y527788D03*
Y524639D03*
X230476Y527788D03*
Y521489D03*
X239925Y534087D03*
Y521489D03*
X233626Y543536D03*
X239925Y540386D03*
Y543536D03*
X236776Y540386D03*
Y537236D03*
X230476D03*
Y543536D03*
Y540386D03*
X233626D03*
X236776Y543536D03*
X233626Y537236D03*
X239925D03*
X243075Y559284D03*
Y552984D03*
X231209Y566282D03*
X252524Y502591D03*
X255673D03*
X249374D03*
X246224D03*
X255673Y512040D03*
X252524D03*
X255673Y508891D03*
Y505741D03*
X249374D03*
Y508891D03*
X252524Y505741D03*
Y508891D03*
X249374Y512040D03*
X246224D03*
X252524Y527789D03*
Y524639D03*
X255673Y534088D03*
X252524D03*
X249374D03*
X255673Y524639D03*
Y527789D03*
X249374D03*
Y524639D03*
X255673Y537237D03*
X249374D03*
X252524D03*
X255673Y540387D03*
X249374D03*
X252524D03*
Y549835D03*
X255673D03*
X249374D03*
X255673Y565580D03*
Y552984D03*
Y556133D03*
Y559282D03*
Y562431D03*
X249344Y552984D03*
Y556134D03*
X246224Y559284D03*
Y556134D03*
Y562434D03*
X252554Y559314D03*
X262904Y293850D03*
X268943Y291086D03*
X265122Y502591D03*
X274582D03*
X271402Y499441D03*
X271429Y496295D03*
X261972Y502591D03*
X268272Y505741D03*
Y508891D03*
Y512040D03*
X271422D03*
X265121Y508891D03*
X261972D03*
Y505741D03*
X265122Y512040D03*
X261972D03*
X265122Y505741D03*
X261972Y521489D03*
X268272Y534088D03*
X265122D03*
X261972D03*
X268272Y524639D03*
Y527789D03*
X265122D03*
Y524639D03*
X261972D03*
Y527789D03*
X268272Y521489D03*
X265122D03*
X268272Y540387D03*
X265122D03*
X261972D03*
X265122Y537237D03*
X268272D03*
X261972D03*
X268272Y549836D03*
X271421D03*
X265122D03*
X261972D03*
X274571Y552985D03*
X265122D03*
X268272Y559291D03*
X271422Y562434D03*
X271421Y556135D03*
X271422Y559291D03*
X261973Y552985D03*
X262009Y556153D03*
X261972Y562431D03*
X271422Y565583D03*
X271421Y552985D03*
X274572Y556142D03*
X284024Y499445D03*
X287173D03*
X277712Y502595D03*
X290323Y534092D03*
X280874D03*
X287174D03*
X284024D03*
X277725D03*
Y527792D03*
Y521493D03*
X280874Y537241D03*
Y543541D03*
X284024D03*
X287174Y540391D03*
Y543541D03*
X290323Y540391D03*
Y543541D03*
X277725Y540391D03*
Y543541D03*
Y537241D03*
X290322Y549841D03*
X280872D03*
X287174Y559289D03*
X290323Y565589D03*
X284024Y565588D03*
X287174D03*
X290323Y559289D03*
Y562439D03*
Y556140D03*
X287174Y562438D03*
X280874D03*
X284024D03*
Y559289D03*
X277725Y552989D03*
X280874Y559289D03*
X277725Y556135D03*
Y559289D03*
X287174Y556139D03*
X280874Y552989D03*
X284024Y556139D03*
X287174Y552989D03*
X284024D03*
X293473Y534092D03*
Y540391D03*
Y565589D03*
Y562439D03*
Y559290D03*
X679175Y464038D03*
X674353Y463842D03*
X683112Y464038D03*
Y483723D03*
X683113Y471941D03*
X683112Y487660D03*
X687049Y467975D03*
X698860D03*
X690986D03*
X698860Y471912D03*
X690986D03*
Y479786D03*
X687049Y483723D03*
X698860Y479786D03*
Y483723D03*
X687049Y479786D03*
X690986Y483723D03*
X687049Y471912D03*
X698683Y487517D03*
X690986Y487660D03*
X687049D03*
X692955Y502112D03*
X702797Y464038D03*
Y467975D03*
X706734Y471913D03*
Y483723D03*
X710671Y479786D03*
X706734Y475850D03*
X710671Y471913D03*
X702585Y483749D03*
X702797Y471912D03*
Y479786D03*
X706734D03*
G54D22*
X40749Y150808D03*
Y249194D03*
G54D32*
X98426Y105512D03*
Y719685D03*
G54D41*
X161109Y564853D03*
X155309D03*
X203012Y492651D03*
X208812D03*
X227734Y486164D03*
X221934D03*
X254413Y117582D03*
X260213D03*
X271977Y546643D03*
X277777D03*
X323957Y117410D03*
X329757D03*
X424400Y541007D03*
X430200D03*
X492380Y594236D03*
X507902Y455990D03*
X504538Y556925D03*
X510338D03*
Y562425D03*
X504538D03*
X498180Y594236D03*
X513702Y455990D03*
X542879Y411620D03*
X548679D03*
X683395Y468030D03*
X677595D03*
X679461Y485834D03*
X673661D03*
X679461Y480334D03*
X673661D03*
X679461Y474834D03*
X673661D03*
X697759Y475492D03*
X686720Y475042D03*
X692520D03*
X706395Y468130D03*
X712195D03*
X706395Y462530D03*
X712195D03*
X703559Y475492D03*
G54D23*
X43898Y168544D03*
Y231457D03*
G54D14*
X-36758Y240533D03*
X-34986D03*
G54D50*
X277590Y580834D03*
G54D33*
X102362Y247244D03*
Y349606D03*
X354331Y247244D03*
Y349606D03*
G54D60*
X507489Y281538D03*
G54D24*
X41930Y184229D03*
G54D51*
X354348Y38554D03*
X393718D03*
X605796Y189845D03*
Y204845D03*
X611702Y185690D03*
Y178997D03*
Y200690D03*
Y193997D03*
G36*
G01X-39730Y241133D02*
Y238722D01*
G03X-37950Y237433I858J-689D01*
G01X-36794D01*
G03X-34950I922J600D01*
G01X-33794D01*
G03X-32014Y238722I922J600D01*
G01Y241133D01*
X-33714D01*
Y239433D01*
X-38030D01*
Y241133D01*
X-39730D01*
G37*
G54D42*
X160181Y639044D03*
X165803Y643805D03*
X274538Y562523D03*
X284168Y547993D03*
X296338Y548763D03*
X300848Y556253D03*
X399606Y377165D03*
X413386Y363385D03*
X403543Y367322D03*
Y387008D03*
X413386Y390945D03*
X427166Y377165D03*
X423229Y367322D03*
Y387008D03*
X631522Y782841D03*
X635662Y772045D03*
X643417Y568945D03*
X651262Y783605D03*
X654141Y571687D03*
X657482Y782805D03*
G54D34*
X97627Y426943D03*
X90147D03*
X97627Y435943D03*
X90147D03*
X97627Y444943D03*
X90147D03*
X113858Y453636D03*
X106378D03*
X202207Y222117D03*
X209687D03*
X351910Y331176D03*
X344430D03*
X417881Y412830D03*
X410401D03*
X417881Y420830D03*
X410401D03*
X417881Y428830D03*
X410401D03*
X417881Y436830D03*
X410401D03*
X410551Y452830D03*
X403071D03*
X417881Y444830D03*
X410401D03*
X410551Y460574D03*
X403071D03*
X447841Y424629D03*
Y432798D03*
X455321Y424629D03*
Y432798D03*
X478955Y132391D03*
X486435D03*
G54D61*
X502390Y628829D03*
X506390Y637629D03*
X498390D03*
X520782Y629598D03*
X524782Y638398D03*
X528782Y629598D03*
X619202Y651970D03*
X636938Y653637D03*
X623202Y660770D03*
X627202Y651970D03*
X632938Y662437D03*
X640938D03*
G36*
G01X-34847Y748593D02*
G02X-36897I-1025J400D01*
G01X-37847D01*
G02Y749393I-1025J400D01*
G01X-36897D01*
G02X-34847I1025J-400D01*
G01X-33897D01*
G02Y748593I1025J-400D01*
G01X-34847D01*
G37*
G54D25*
X45282Y338300D03*
G54D70*
X605796Y174845D03*
G54D43*
X193856Y252341D03*
G54D52*
X378012Y805904D03*
X736282D03*
G54D80*
G01X244099Y284248D02*
X244763Y284912D01*
X247018D01*
G01X402193Y676183D02*
Y679408D01*
X400408Y681193D01*
G01X497213Y575625D02*
X499738D01*
X500438Y574925D01*
G01X497213Y579525D02*
X499538D01*
X500419Y578644D01*
G01X497213Y571725D02*
X497513Y572025D01*
X500538D01*
G54D26*
X45554Y488557D03*
X57154D03*
X116984Y461818D03*
X105384D03*
X195789Y450513D03*
X184189D03*
X295177Y595628D03*
X306777D03*
X387677Y591821D03*
X399277D03*
G54D35*
X118755Y409613D03*
Y417093D03*
X132760Y409149D03*
Y416629D03*
X132135Y497682D03*
Y505162D03*
X140603Y408965D03*
Y416445D03*
X184390Y573395D03*
Y580875D03*
X304851Y323383D03*
Y315903D03*
X501641Y485334D03*
Y492814D03*
X534805Y417861D03*
Y410381D03*
G54D53*
X401329Y650598D03*
Y658078D03*
X391683D03*
Y654338D03*
Y650598D03*
G54D71*
X638148Y419286D03*
Y426372D03*
G54D17*
X10859Y109561D03*
X73740Y20708D03*
X703661D03*
G54D62*
X514780Y28803D03*
X524780D03*
X514780Y38803D03*
X524780D03*
X534780Y28803D03*
X544780D03*
X534780Y38803D03*
X544780D03*
X554780Y28803D03*
X577371D03*
X587371D03*
X577371Y38803D03*
X587371D03*
X597371Y28803D03*
X607371D03*
X597371Y38803D03*
X607371D03*
X617371Y28803D03*
X639963D03*
Y38803D03*
X649963Y28803D03*
Y38803D03*
X659963Y28803D03*
X669963D03*
X659963Y38803D03*
X669963D03*
X679963Y28803D03*
G54D44*
X197073Y265022D03*
G54D81*
G01X144058Y373230D02*
Y376025D01*
G01X160058Y373230D02*
Y375818D01*
G01X152058Y373230D02*
Y376016D01*
G01X168058Y373230D02*
Y376035D01*
G01X176058Y373230D02*
Y376568D01*
G01X195473Y108767D02*
X193148Y111092D01*
Y112977D01*
G01X189055Y311603D02*
Y309932D01*
X187907Y308784D01*
G01X184058Y373230D02*
Y376479D01*
G01X188383Y556895D02*
X188962Y556316D01*
Y553996D01*
X188886Y553920D01*
G01X187744Y708356D02*
X187944Y708156D01*
X193865D01*
G01X210203Y108457D02*
X207848Y110812D01*
Y114957D01*
G01X202558Y277609D02*
Y280507D01*
X203149Y281098D01*
G01X203880Y385272D02*
X203887D01*
X204687Y384472D01*
Y382271D01*
G01X200687D02*
X204687D01*
G01X208050Y528883D02*
Y526087D01*
X209637Y523557D01*
X211423Y521467D01*
G01X228745Y265718D02*
X226494D01*
X225973Y265197D01*
G01X226995Y269007D02*
X226423D01*
X225047Y267631D01*
X224801D01*
X224200Y267030D01*
G01X213265Y271280D02*
Y274060D01*
X213138Y274187D01*
G01X214008Y385165D02*
X212687Y383844D01*
Y382271D01*
G01X221438Y390655D02*
X220687Y389904D01*
Y382271D01*
G01X216564Y528902D02*
Y527592D01*
X218867Y525289D01*
Y524238D01*
G01X240355Y108757D02*
X242195Y110597D01*
X255098D01*
G01X237800Y299998D02*
X237214Y300584D01*
X235107D01*
G01X262132Y245889D02*
X262125Y245896D01*
X258263D01*
G01X255209Y260639D02*
X254934Y260914D01*
X252399D01*
G01X254022Y255117D02*
X254063Y255158D01*
Y257530D01*
X252399Y259194D01*
Y260914D01*
G01D02*
Y262158D01*
G01X254022Y251117D02*
Y255117D01*
G01X255205Y272755D02*
X255794Y273344D01*
X255912D01*
X258189Y275621D01*
X260143D01*
G01X250466Y344381D02*
X251756Y343091D01*
X251717Y341125D01*
G01X259444Y354291D02*
X260350Y355197D01*
Y363837D01*
G01X250661Y384780D02*
X252687Y382754D01*
Y382271D01*
G01X249344Y556134D02*
X249374D01*
X249580Y555928D01*
X251809D01*
G01X264953Y114152D02*
X262903D01*
X260213Y116842D01*
G01D02*
Y117582D01*
G01X264953Y114152D02*
X268953D01*
G01X269620Y243240D02*
X268568D01*
X268315Y242987D01*
X264975D01*
X262132Y245830D01*
Y245889D01*
G01X276809Y471853D02*
Y472568D01*
X274399Y474978D01*
X273209D01*
G01X278354Y244281D02*
X280067Y245994D01*
Y247678D01*
G01X282298Y483803D02*
Y485113D01*
X279004Y488407D01*
Y489155D01*
G01X298202Y374572D02*
X297131Y373501D01*
Y372171D01*
G01X301457Y510979D02*
X301468Y510968D01*
X305708D01*
G01X301457Y513837D02*
Y510979D01*
G01X296913Y510981D02*
Y514460D01*
G01X321987Y536052D02*
X318968D01*
G01X332453Y122297D02*
X331777D01*
X329757Y120277D01*
Y117410D01*
G01X330665Y311864D02*
Y311079D01*
X328526Y308940D01*
Y308696D01*
G01X344073Y124397D02*
X340073D01*
X338948Y123272D01*
Y117297D01*
G01X347950Y280101D02*
Y284101D01*
G01X345297Y284849D02*
X345456Y284690D01*
X347361D01*
X347950Y284101D01*
G01X342955Y291523D02*
X344377Y290101D01*
X347950D01*
G01Y294101D02*
Y290101D01*
G01X354580Y298101D02*
X351100D01*
G01X354170Y308924D02*
X352993Y310101D01*
X351100D01*
G01X351500Y301795D02*
X351412Y301883D01*
X347670D01*
G01X359105Y665128D02*
Y669128D01*
G01X367399Y684652D02*
X370283Y681768D01*
Y681656D01*
G01X377211Y673197D02*
X375152Y675256D01*
X371929D01*
X370283Y676902D01*
Y677656D01*
G01X401329Y658078D02*
X396940D01*
G01X396478Y661529D02*
X390947D01*
X389999Y662477D01*
Y665278D01*
G01X399911Y661325D02*
X403164Y664578D01*
X403989D01*
G01X407506Y653413D02*
Y653407D01*
X410444D01*
X410894Y652957D01*
X410989D01*
G01X446980Y638774D02*
Y638824D01*
X447015Y638789D01*
X451221D01*
Y638786D01*
G01X456342Y649436D02*
X458938Y652032D01*
Y652048D01*
G01X477640Y139364D02*
Y143364D01*
G01Y147364D02*
Y143364D01*
G01Y147364D02*
Y151364D01*
G01D02*
Y154440D01*
X484435Y161235D01*
X487740D01*
G01X470190Y648693D02*
X471728D01*
X472683Y649648D01*
X473898D01*
G01X478905Y659426D02*
X476513Y661818D01*
Y663623D01*
G01X476366Y656713D02*
Y657956D01*
X474946Y659376D01*
G01X489938Y563425D02*
X490338Y563025D01*
X493963D01*
G01X490658Y579025D02*
X493563D01*
X494063Y579525D01*
G01X487398Y576665D02*
X488438Y575625D01*
X494063D01*
G01X490693Y570770D02*
X491648Y571725D01*
X494063D01*
G01Y567825D02*
X490538D01*
G01X505124Y146686D02*
X502132D01*
G01X501938Y534030D02*
X503958Y532010D01*
Y529405D01*
G01X500138Y543225D02*
X499513Y543850D01*
X495738D01*
G01X503448Y540235D02*
X501938Y538725D01*
Y537180D01*
G01X500038Y555925D02*
X499863Y555750D01*
X496338D01*
G01X510338Y556925D02*
X513838D01*
G01X497113Y563025D02*
X500138D01*
G01X496338Y558900D02*
X499863D01*
X500138Y558625D01*
G01X504538Y556925D02*
X502838Y558625D01*
X500138D01*
G01X507528Y571790D02*
X503628D01*
G01X510338Y571325D02*
X509873Y571790D01*
X507528D01*
G01X497213Y567825D02*
X498813Y569425D01*
X500338D01*
G01X497213Y567825D02*
X498613Y566425D01*
X500338D01*
G01X515438Y137692D02*
Y142169D01*
X515458Y142189D01*
G01X518248Y137692D02*
X515438D01*
G01X518477Y141401D02*
X517689Y142189D01*
X515458D01*
G01X526875Y161838D02*
X528183Y163146D01*
X530696D01*
G01X527138Y529525D02*
Y532850D01*
X526638Y533350D01*
G01X522738D02*
X526638D01*
G01X515110Y528785D02*
X514930Y528965D01*
Y532417D01*
X514938Y532425D01*
Y533350D01*
G01X518838D02*
X514938D01*
G01X521963Y543025D02*
X519438D01*
G01X518838Y536500D02*
Y539625D01*
X518938Y539725D01*
Y540425D01*
G01X514938Y536500D02*
Y538924D01*
X516378Y540364D01*
X516380D01*
G01X522738Y536500D02*
X521938Y537300D01*
Y540325D01*
G01X512354Y590825D02*
X512263Y590916D01*
Y594625D01*
G01X523538Y597300D02*
Y600325D01*
G01X519638Y597200D02*
Y600425D01*
G01X515413Y594625D02*
Y590950D01*
G01X519638Y594050D02*
Y590925D01*
X520228Y590335D01*
G01X523538Y594150D02*
Y591455D01*
X524638Y590355D01*
Y590225D01*
G01X530696Y155146D02*
X530249D01*
X527349Y152246D01*
G01D02*
X528449Y151146D01*
X530696D01*
G01Y147146D02*
X527898D01*
G01X530538Y533350D02*
Y529625D01*
X530438Y529525D01*
G01X541538Y533250D02*
Y529625D01*
G01X534438Y533350D02*
Y529599D01*
X534401Y529562D01*
G01X530638Y539525D02*
X530538Y539425D01*
Y536500D01*
G01X534638Y539825D02*
X534438Y539625D01*
Y536500D01*
G01X541238Y539625D02*
X541538Y539325D01*
Y536400D01*
G01X527438Y597300D02*
X531438D01*
G01X527438Y600325D02*
Y597300D01*
G01X536438Y597200D02*
X540338D01*
G01X536438Y600425D02*
Y597200D01*
G01X540338Y594050D02*
Y590525D01*
X540701Y590162D01*
G01X527438Y594150D02*
Y590525D01*
X527638Y590325D01*
G01X536438Y594050D02*
Y591149D01*
X535776Y590487D01*
G01X531438Y594150D02*
X530338Y593050D01*
Y590325D01*
G01X544764Y139415D02*
Y135415D01*
G01X548007Y139415D02*
X544764D01*
G01X548367Y135415D02*
X544764D01*
G01Y143415D02*
X547543D01*
G01X544138Y530125D02*
X545438Y531425D01*
Y533250D01*
G01X557713Y548125D02*
X557613Y548025D01*
Y544225D01*
G01X561065Y543998D02*
X560838Y544225D01*
X557613D01*
G01X548238Y547950D02*
X545413D01*
G01X557613Y540325D02*
X560838D01*
G01X554563Y548125D02*
X552138D01*
X551161Y547148D01*
G01X545438Y536400D02*
Y539425D01*
X545138Y539725D01*
G01X551338Y544225D02*
X554463D01*
G01X551538Y540325D02*
X554463D01*
G01D02*
Y544225D01*
G01X551438Y561225D02*
X554913D01*
X555138Y561450D01*
G01X551338Y551100D02*
X548238D01*
G01X555138Y564600D02*
X552213D01*
X551438Y563825D01*
G01X551538Y568525D02*
X551713Y568350D01*
X555138D01*
G01Y571500D02*
X551463D01*
X551238Y571725D01*
G01X550938Y587325D02*
X551013Y587400D01*
X555138D01*
G01X544638Y600525D02*
X544238Y600125D01*
Y597200D01*
G01X548138D02*
Y600425D01*
G01Y594050D02*
Y591301D01*
X547000Y590163D01*
G01X555138Y584250D02*
X551463D01*
X551238Y584025D01*
G01X544238Y594050D02*
Y590701D01*
X543850Y590313D01*
G01X545377Y647594D02*
X544772Y646989D01*
Y644931D01*
G01X698860Y467975D02*
X696695Y470140D01*
X694833D01*
G54D45*
X205940Y690317D03*
Y687758D03*
Y685199D03*
Y682640D03*
Y680081D03*
Y705672D03*
Y703113D03*
Y700554D03*
Y697995D03*
Y695436D03*
Y692876D03*
Y708231D03*
X228940Y680081D03*
Y682640D03*
Y685199D03*
Y687758D03*
Y690317D03*
Y692876D03*
Y695436D03*
Y697995D03*
Y700554D03*
Y703113D03*
Y705672D03*
Y708231D03*
X322468Y644505D03*
Y659860D03*
Y657301D03*
Y654742D03*
Y652182D03*
Y649623D03*
Y647064D03*
Y662419D03*
X322440Y673699D03*
Y671140D03*
Y668581D03*
Y691613D03*
Y689054D03*
Y686495D03*
Y683936D03*
Y681376D03*
Y678817D03*
Y676258D03*
Y696731D03*
Y694172D03*
X345468Y644505D03*
Y647064D03*
Y649623D03*
Y652182D03*
Y654742D03*
Y657301D03*
Y659860D03*
Y662419D03*
X345440Y668581D03*
Y671140D03*
Y673699D03*
Y676258D03*
Y678817D03*
Y681376D03*
Y683936D03*
Y686495D03*
Y689054D03*
Y691613D03*
Y694172D03*
Y696731D03*
X383940Y691317D03*
Y688758D03*
Y686199D03*
Y683640D03*
Y681081D03*
Y706672D03*
Y704113D03*
Y701554D03*
Y698995D03*
Y696436D03*
Y693876D03*
Y709231D03*
X406940Y681081D03*
Y683640D03*
Y686199D03*
Y688758D03*
Y691317D03*
Y693876D03*
Y696436D03*
Y698995D03*
Y701554D03*
Y704113D03*
Y706672D03*
Y709231D03*
X446940Y691258D03*
Y688699D03*
Y686140D03*
Y683581D03*
Y706613D03*
Y704054D03*
Y701495D03*
Y698936D03*
Y696376D03*
Y693817D03*
Y711731D03*
Y709172D03*
X469940Y683581D03*
Y686140D03*
Y688699D03*
Y691258D03*
Y693817D03*
Y696376D03*
Y698936D03*
Y701495D03*
Y704054D03*
Y706613D03*
Y709172D03*
Y711731D03*
X571440Y674199D03*
Y671640D03*
Y669081D03*
Y689554D03*
Y686995D03*
Y684436D03*
Y681876D03*
Y679317D03*
Y676758D03*
Y697231D03*
Y694672D03*
Y692113D03*
X594440Y669081D03*
Y671640D03*
Y674199D03*
Y676758D03*
Y679317D03*
Y681876D03*
Y684436D03*
Y686995D03*
Y689554D03*
Y692113D03*
Y694672D03*
Y697231D03*
X627463Y675600D03*
Y690954D03*
Y688395D03*
Y685836D03*
Y683277D03*
Y680718D03*
Y678159D03*
Y706309D03*
Y703750D03*
Y701191D03*
Y698632D03*
Y696073D03*
Y693514D03*
Y708868D03*
X650463Y675600D03*
Y678159D03*
Y680718D03*
Y683277D03*
Y685836D03*
Y688395D03*
Y690954D03*
Y693514D03*
Y696073D03*
Y698632D03*
Y701191D03*
Y703750D03*
Y706309D03*
Y708868D03*
G54D72*
X688977Y105315D03*
Y719488D03*
G54D54*
X396411Y664578D03*
Y669696D03*
X403989Y664578D03*
Y667137D03*
Y669696D03*
X523611Y218900D03*
Y216341D03*
Y221459D03*
X531189Y216341D03*
Y221459D03*
G54D27*
X49835Y494618D03*
X52985D03*
X65554Y527977D03*
X62404D03*
X105639Y611918D03*
X102489D03*
X105639Y616418D03*
X102489D03*
X105639Y620918D03*
X102489D03*
X105371Y644345D03*
X102221D03*
X105405Y648617D03*
X102255D03*
X126925Y739100D03*
X130075D03*
Y743200D03*
X126925D03*
X139645Y250914D03*
X142795D03*
X139556Y266048D03*
X142706D03*
X139556Y261548D03*
X142706D03*
X139645Y254914D03*
X142795D03*
X146542Y540950D03*
X146642Y537008D03*
X146634Y550353D03*
Y544853D03*
X147735Y581013D03*
Y573105D03*
Y577105D03*
X147688Y594137D03*
X147753Y610702D03*
X147655Y598135D03*
X147753Y619035D03*
Y614735D03*
X152443Y271487D03*
X155593D03*
X152443Y267487D03*
X155593D03*
X149692Y540950D03*
X149792Y537008D03*
X149784Y550353D03*
Y544853D03*
X152234Y555253D03*
X155384D03*
X150885Y581013D03*
Y573105D03*
Y577105D03*
X150838Y594137D03*
X160538Y596933D03*
X157388D03*
X154755Y588235D03*
X157905D03*
X150903Y610702D03*
X150805Y598135D03*
X160538Y610933D03*
X157388D03*
X160505Y605135D03*
X157355D03*
X160538Y600933D03*
X157388D03*
X150903Y619035D03*
Y614735D03*
X160538Y620933D03*
X157388D03*
X160605Y616735D03*
X157455D03*
X165952Y285347D03*
X169102D03*
X165952Y289347D03*
X169102D03*
X180634Y520053D03*
X178396Y524137D03*
X175954Y539647D03*
X172804D03*
X189998Y112977D03*
X193148D03*
X192205Y311603D03*
X189055D03*
X189182Y305819D03*
X192332D03*
X196372Y313617D03*
X196354Y331014D03*
X184634Y505353D03*
X187784D03*
X185134Y511353D03*
X188284D03*
X183784Y520053D03*
X181546Y524137D03*
X185634Y540853D03*
X188784D03*
X190355Y594735D03*
X193505D03*
X190388Y603833D03*
X193538D03*
X190355Y607835D03*
X193505D03*
X190388Y598933D03*
X193538D03*
X190355Y614735D03*
X193505D03*
X190388Y623033D03*
X193538D03*
X190355Y627135D03*
X193505D03*
X188795Y701936D03*
X191945D03*
X193865Y708156D03*
X210998Y114957D03*
X207848D03*
X205708Y277609D03*
X202558D03*
X211872Y284617D03*
X208022D03*
X204872D03*
X199522Y313617D03*
X209165Y300444D03*
X206015D03*
X206680Y320800D03*
X203530D03*
X199504Y331014D03*
X211423Y521467D03*
X197015Y708156D03*
X224740Y84629D03*
X221590D03*
X226847Y216901D03*
Y220901D03*
X221872Y243617D03*
X225022D03*
X225445Y247519D03*
X222295D03*
Y251519D03*
X225445D03*
X224093Y276987D03*
X220943D03*
X217072Y277567D03*
X213922D03*
X215022Y284617D03*
X218175Y297031D03*
X221325D03*
X218150Y293088D03*
X221300D03*
X216022Y313117D03*
X212872D03*
X216022Y309117D03*
X212872D03*
X219572Y319617D03*
X222722D03*
X219572Y315617D03*
X222722D03*
X227872Y316617D03*
X217134Y502853D03*
X220284D03*
X224193Y498103D03*
X227343D03*
X217134Y506853D03*
X220284D03*
X217134Y510853D03*
X220284D03*
X224529Y511865D03*
X227679D03*
X227784Y515853D03*
X224634D03*
X214573Y521467D03*
X219685Y574231D03*
X222835D03*
X219694Y570116D03*
X222844D03*
X229997Y216901D03*
Y220901D03*
X242064Y242228D03*
Y246228D03*
X231022Y316617D03*
X238022Y324117D03*
X234872D03*
X238022Y320117D03*
X234872D03*
X240913Y377150D03*
X241599Y381197D03*
X242993Y511465D03*
X239843D03*
X243018Y515449D03*
X239868D03*
X243230Y527737D03*
X243240Y519714D03*
X243230Y523732D03*
X243280Y531781D03*
X243266Y535789D03*
X242384Y543962D03*
X243420Y539789D03*
X241348Y703150D03*
X258248Y110597D03*
X255098D03*
X245214Y242228D03*
Y246228D03*
X250837Y246929D03*
X253987D03*
X254022Y251117D03*
X250872D03*
X254022Y255117D03*
X250872D03*
X250943Y277987D03*
X254093D03*
X250516Y294009D03*
X247366D03*
X252943Y284402D03*
X256093D03*
X250454Y299348D03*
X247304D03*
X244063Y377150D03*
X244749Y381197D03*
X246380Y527737D03*
X246390Y519714D03*
X246380Y523732D03*
X246430Y531781D03*
X246416Y535789D03*
X245534Y543962D03*
X246570Y539789D03*
X253293Y546912D03*
X256443D03*
X253273Y542889D03*
X256423D03*
X253239Y561853D03*
X250089D03*
X253239Y566153D03*
X250089D03*
X244498Y703150D03*
X263093Y306987D03*
X259943D03*
X275113Y387669D03*
X271363Y529422D03*
X274513D03*
X271134Y522353D03*
X274284D03*
X271363Y533422D03*
X274513D03*
X260320Y547112D03*
X263470D03*
X260334Y543253D03*
X263484D03*
X271398Y541430D03*
X274548D03*
X271363Y537422D03*
X274513D03*
X280067Y247678D03*
X276917D03*
X286563Y250180D03*
X286809Y246800D03*
X288942Y306875D03*
X280494Y330552D03*
X283644D03*
X277821Y349730D03*
X280971D03*
X278263Y387669D03*
X293725Y124910D03*
X296875D03*
X293725Y120910D03*
X296875D03*
X292092Y306875D03*
X300375Y344346D03*
X303525D03*
X306464Y330406D03*
X304970Y334380D03*
X306284Y497853D03*
X303134D03*
X306284Y493853D03*
X303134D03*
X300575Y642208D03*
X303725D03*
Y646192D03*
X300575D03*
X317568Y302798D03*
X314418D03*
X317607Y306876D03*
X314457D03*
X319225Y326386D03*
X316075D03*
X309614Y330406D03*
X308120Y334380D03*
X316331Y378971D03*
X313181D03*
X312675Y639136D03*
X309525D03*
X308785Y651156D03*
X311935D03*
X308785Y659156D03*
X311935D03*
X308785Y655156D03*
X311935D03*
Y647156D03*
X308785D03*
Y675156D03*
X311935D03*
X308785Y663156D03*
X311935D03*
X308785Y671156D03*
X311935D03*
Y667156D03*
X308785D03*
Y683156D03*
X311935D03*
X308785Y687156D03*
X311935D03*
X308785Y691156D03*
X311935D03*
X308785Y679156D03*
X311935D03*
X308785Y699156D03*
X311935D03*
X308785Y695156D03*
X311935D03*
X335798Y117297D03*
X330665Y311864D03*
X327515D03*
X338948Y117297D03*
X351100Y280101D03*
X347950D03*
X351100Y290101D03*
X347950D03*
X351100Y284101D03*
X347950D03*
X351100Y294101D03*
X347950D03*
Y298101D03*
X351100D03*
X344520Y301883D03*
X347670D03*
X351100Y306101D03*
X347950D03*
X350872Y314102D03*
X347722D03*
X347950Y310101D03*
X351100D03*
X351342Y318230D03*
X348192D03*
X361705Y280317D03*
X358555D03*
X361705Y290317D03*
X358555D03*
X361705Y284317D03*
X358555D03*
X361705Y294317D03*
X358555D03*
X361705Y298317D03*
X358555D03*
X359105Y637128D03*
X355955D03*
X359105Y641128D03*
X355955D03*
X359105Y657128D03*
X355955D03*
X359105Y653128D03*
X355955D03*
X359105Y649128D03*
X355955D03*
X359105Y645175D03*
X355955D03*
Y665128D03*
X359105D03*
Y673128D03*
X355955D03*
X359105Y669128D03*
X355955D03*
X359105Y661128D03*
X355955D03*
X359105Y689128D03*
X355955D03*
X359105Y685128D03*
X355955D03*
X359105Y681128D03*
X355955D03*
X359105Y677128D03*
X355955D03*
X359105Y701128D03*
X355955D03*
X359105Y697128D03*
X355955D03*
X359105Y693128D03*
X355955D03*
X357096Y723537D03*
X360246D03*
X369428Y727622D03*
X369336Y735459D03*
X357096Y735537D03*
X360246D03*
X369336Y731459D03*
X357096Y727537D03*
X360246D03*
Y739537D03*
X357096D03*
X369336Y743459D03*
Y739459D03*
X360246Y743537D03*
X357096D03*
X378508Y117817D03*
X375358D03*
X373433Y685656D03*
X370283D03*
Y681656D03*
X373433D03*
Y677656D03*
X370283D03*
X373485Y715026D03*
X376635D03*
X384333Y715248D03*
X372578Y727622D03*
X372486Y735459D03*
Y731459D03*
Y743459D03*
Y739459D03*
X398016Y676213D03*
X394866D03*
X399443Y716254D03*
X387483Y715248D03*
X412631Y264679D03*
X409481D03*
Y260489D03*
X412631D03*
Y256489D03*
X409481D03*
Y252489D03*
X412631D03*
Y272731D03*
X409481D03*
Y268679D03*
X412631D03*
X405343Y676183D03*
X402193D03*
X402593Y716254D03*
X418063Y681569D03*
X421213D03*
X418852Y685654D03*
X422002D03*
X433265Y687156D03*
X436415D03*
Y679156D03*
X433265D03*
Y683156D03*
X436415D03*
X433265Y691156D03*
X436415D03*
X433265Y707156D03*
X436415D03*
X433265Y703156D03*
X436415D03*
X433265Y699156D03*
X436415D03*
X433265Y695156D03*
X436415D03*
X433265Y711156D03*
X436415D03*
X433265Y715156D03*
X436415D03*
X434280Y719128D03*
X437430D03*
X454371Y638786D03*
X451221D03*
X451226Y642685D03*
X454376D03*
X453233Y657403D03*
X450083D03*
X477640Y139364D03*
Y143364D03*
Y147364D03*
Y151364D03*
X479125Y172113D03*
Y164113D03*
Y168113D03*
X478535Y180383D03*
X475385D03*
X479125Y176113D03*
X476385Y556648D03*
X479535D03*
X476385Y560648D03*
X479535D03*
X476385Y566694D03*
X479535D03*
X476385Y570694D03*
X479535D03*
X476366Y656713D03*
X473216D03*
X473363Y663623D03*
X476513D03*
X482126Y126402D03*
X485276D03*
X480790Y139364D03*
X492699Y128666D03*
X480790Y143364D03*
Y147364D03*
Y151364D03*
X482275Y172113D03*
Y164113D03*
Y168113D03*
X494644Y157761D03*
Y162261D03*
X482275Y176113D03*
X493963Y563025D03*
X494063Y567825D03*
Y571725D03*
Y579525D03*
Y575625D03*
X485465Y678656D03*
X488615D03*
X485465Y682656D03*
X488615D03*
Y686656D03*
X485465D03*
X488615Y690656D03*
X485465D03*
X488615Y694656D03*
X485465D03*
X488615Y698656D03*
X485465D03*
X508274Y137686D03*
X505124D03*
X495849Y128666D03*
X508274Y150686D03*
X505124D03*
Y146686D03*
X508274D03*
Y142186D03*
X505124D03*
X497794Y157761D03*
Y162261D03*
X504550Y201800D03*
X507700D03*
X508663Y463223D03*
Y468723D03*
X497113Y563025D03*
X497213Y567825D03*
Y571725D03*
Y579525D03*
Y575625D03*
X509917Y655007D03*
X508578Y666397D03*
X509884Y670488D03*
X511293Y674660D03*
X508143D03*
X509823Y679002D03*
X512465Y120512D03*
X515615D03*
X515438Y137692D03*
X512288D03*
X515401Y153797D03*
X518551D03*
X515458Y142189D03*
X512308D03*
X515375Y159940D03*
X518525D03*
X516875Y182600D03*
X513725D03*
X511813Y463223D03*
Y468723D03*
X521963Y543025D03*
X525113D03*
X512263Y594625D03*
X515413D03*
X524399Y645214D03*
X513067Y655007D03*
X511728Y666397D03*
X513034Y670488D03*
X512973Y679002D03*
X533846Y135146D03*
X530696D03*
X541614Y135415D03*
Y139415D03*
X533846Y139146D03*
X530696D03*
X541614Y151415D03*
X530696Y151146D03*
X533846D03*
X541614Y155415D03*
X530696Y155146D03*
X533846D03*
X541614Y147415D03*
X533846Y143146D03*
X530696D03*
Y147146D03*
X533846D03*
X541614Y143415D03*
X530559Y167329D03*
X533709D03*
X541614Y163415D03*
X530696Y163146D03*
X533846D03*
X541614Y159415D03*
X541675Y216100D03*
X538525D03*
X535763Y452423D03*
X538913D03*
X535363Y470423D03*
X538513D03*
X535763Y460123D03*
X538913D03*
X531527Y483627D03*
X534677D03*
X541622Y644931D03*
X527549Y645214D03*
X541882Y650277D03*
X544764Y135415D03*
Y139415D03*
Y151415D03*
Y155415D03*
Y147415D03*
Y143415D03*
X556699Y149274D03*
X544764Y163415D03*
X551604Y162541D03*
X554754D03*
X544764Y159415D03*
X555863Y183023D03*
X555706Y239501D03*
X552556D03*
X555749Y243395D03*
X552599D03*
X555749Y247595D03*
X552599D03*
X555749Y258095D03*
X552599D03*
X557613Y544225D03*
X554463D03*
X557713Y548125D03*
X554563D03*
X557613Y540325D03*
X554463D03*
X548493Y643163D03*
X551643D03*
X544772Y644931D03*
X545032Y650277D03*
X557765Y669156D03*
Y673156D03*
Y665156D03*
Y677156D03*
Y689156D03*
Y685156D03*
Y681156D03*
Y693156D03*
Y701156D03*
Y697156D03*
X572083Y136404D03*
X568933D03*
X572083Y140404D03*
X568933D03*
X572083Y144404D03*
X568933D03*
X572083Y148404D03*
X568933D03*
X572083Y152404D03*
X568933D03*
X572083Y156404D03*
X568933D03*
X559849Y149274D03*
X568933Y160404D03*
X572083D03*
X559013Y183023D03*
X559333Y643123D03*
X562483D03*
X560915Y669156D03*
Y673156D03*
Y665156D03*
Y677156D03*
Y689156D03*
Y685156D03*
Y681156D03*
Y693156D03*
Y701156D03*
Y697156D03*
X586999Y240895D03*
X590149D03*
X578366Y278093D03*
X581516D03*
Y282093D03*
X578366D03*
Y286093D03*
X581516D03*
X578366Y290093D03*
X581516D03*
Y294093D03*
X578366D03*
X587420Y663828D03*
X590570D03*
X604965Y675156D03*
Y679156D03*
Y683156D03*
Y687156D03*
Y691156D03*
Y695156D03*
X619012Y589645D03*
X615862D03*
X619045Y585543D03*
X615895D03*
X619045Y597943D03*
X615895D03*
X619012Y608845D03*
X615862D03*
X619045Y617943D03*
X615895D03*
X619012Y613745D03*
X615862D03*
X608115Y675156D03*
Y679156D03*
Y683156D03*
Y687156D03*
Y691156D03*
X613086Y697395D03*
X616236D03*
X608115Y695156D03*
X630716Y195307D03*
X627566D03*
X630716Y199307D03*
X627566D03*
X640663Y387285D03*
X643813D03*
X640663Y392085D03*
X643813D03*
X640663Y396985D03*
X643813D03*
Y401583D03*
X640663D03*
Y405883D03*
X643813D03*
X648862Y591745D03*
X652012D03*
X648795Y595943D03*
X651945D03*
X648862Y611745D03*
X652012D03*
X648895Y607543D03*
X652045D03*
X648862Y601745D03*
X652012D03*
X651495Y624443D03*
X648862Y615745D03*
X652012D03*
X651227Y720674D03*
X648077D03*
Y716674D03*
X651227D03*
X649027Y728674D03*
X652177D03*
X648077Y724674D03*
X651227D03*
X661545Y596443D03*
X658395D03*
X661545Y592143D03*
X658395D03*
X661647Y601976D03*
X658497D03*
X664307Y609468D03*
X667457D03*
X661712Y618541D03*
X658562D03*
X654645Y624443D03*
X661745Y614543D03*
X658595D03*
X660889Y676595D03*
X664039D03*
X672363Y388185D03*
X675513D03*
Y392385D03*
X672363D03*
X675513Y401785D03*
X672363D03*
Y406785D03*
X675513D03*
Y397585D03*
X672363D03*
G54D63*
X554780Y38803D03*
X617371D03*
X679963D03*
G54D36*
X151969Y98622D03*
G54D18*
X20859Y109561D03*
X83740Y20708D03*
X78740Y30708D03*
X507489Y360278D03*
X713661Y20708D03*
X708661Y30708D03*
G54D82*
G01X-41265Y641923D02*
X-42472D01*
G01X179693Y726467D02*
X176767D01*
X175500Y725200D01*
X171900D01*
X169700Y727400D01*
Y730200D01*
X172800Y733300D01*
Y748700D01*
X171000Y750500D01*
X135500D01*
X132900Y747900D01*
Y736400D01*
X130300Y733800D01*
Y725800D01*
X134000Y722100D01*
Y716000D01*
X127200Y709200D01*
Y671400D01*
X124000Y668200D01*
Y664700D01*
X126800Y661900D01*
Y611300D01*
X120100Y604600D01*
X92100D01*
X81200Y593700D01*
X58100D01*
X45300Y580900D01*
Y562000D01*
X55100Y552200D01*
Y541400D01*
X46600Y532900D01*
X33300D01*
X24100Y523700D01*
Y418000D01*
X40400Y401700D01*
X51200D01*
X60400Y392500D01*
Y354200D01*
X111700Y302900D01*
Y257400D01*
X122200Y246900D01*
Y161400D01*
X112900Y152100D01*
X63398D01*
X20859Y109561D01*
G01X76880Y143269D02*
Y126528D01*
G01X89810Y765905D02*
X89800D01*
Y763571D01*
X123870Y729501D01*
Y672892D01*
X121487Y670509D01*
X121070D01*
G01X177920Y739302D02*
Y753280D01*
X164700Y766500D01*
X111100D01*
Y766535D01*
X111000Y766435D01*
X97390D01*
G01X131900Y760900D02*
X130000Y762800D01*
X96750D01*
X93925Y765625D01*
Y771575D01*
X97950Y775600D01*
X143800D01*
X147600Y779400D01*
Y782370D01*
X146150Y783820D01*
G01X130075Y743200D02*
Y759025D01*
X127325Y761775D01*
X96325D01*
X92900Y765200D01*
Y772000D01*
X97600Y776700D01*
X141690D01*
X145570Y780580D01*
G01X102421Y782191D02*
X100240Y784372D01*
Y788862D01*
X102421Y791043D01*
Y807872D01*
G01X97180Y786472D02*
X97184D01*
X98484Y787772D01*
Y807872D01*
G01X179693Y729617D02*
Y754573D01*
X175202Y759064D01*
X175136D01*
X166100Y768100D01*
X109385D01*
X104300Y773185D01*
Y773100D01*
G01X110295Y782191D02*
X108595Y783891D01*
Y788768D01*
X110295Y790468D01*
Y807872D01*
G01X106358D02*
Y785790D01*
G01X168040Y61462D02*
X163077Y66425D01*
X134178D01*
X127010Y59257D01*
Y34740D01*
X134417Y27333D01*
X144229D01*
X146373Y25189D01*
X154276D01*
X158165Y21300D01*
G01X147427Y30367D02*
X145641Y32153D01*
X135520D01*
X128910Y38763D01*
Y58462D01*
X134973Y64525D01*
X161264D01*
X164550Y61239D01*
G01X131960Y720941D02*
X126228D01*
X126220Y720949D01*
G01X125600Y759000D02*
X126900Y757700D01*
Y755900D01*
X126925Y755875D01*
Y743200D01*
G01X119900Y754021D02*
Y754000D01*
X125300Y748600D01*
Y740725D01*
X126925Y739100D01*
G01X130075D02*
X131900Y740925D01*
Y760900D01*
G01X118169Y807872D02*
Y783857D01*
G01X129980Y807872D02*
Y786281D01*
X130660Y785601D01*
G01X127290Y781982D02*
X128140Y782832D01*
Y786497D01*
X126043Y788594D01*
Y807872D01*
G01X122720Y785051D02*
X122697D01*
X122106Y785642D01*
Y807872D01*
G01X174078Y271435D02*
X172861Y272667D01*
X172863Y273068D01*
Y274426D01*
X173540Y275103D01*
Y277536D01*
X172611Y278465D01*
X170780D01*
X170580Y278665D01*
X170480D01*
G01X170829Y271452D02*
X172061Y272670D01*
X172063Y273070D01*
Y274758D01*
X172740Y275435D01*
Y277204D01*
X172279Y277665D01*
X170780D01*
X170580Y277465D01*
X170480D01*
G01X148058Y373230D02*
X149090Y374262D01*
Y376279D01*
X147999Y377370D01*
Y380582D01*
G01X148058Y370080D02*
X144058D01*
G01D02*
Y367508D01*
X151636Y359930D01*
X155006D01*
X169655Y345281D01*
Y321614D01*
X178093Y313176D01*
X180741D01*
X183254Y310663D01*
G01X150902Y379714D02*
X150034Y380582D01*
X147999D01*
G01X133917Y807872D02*
Y786214D01*
X135610Y784521D01*
G01X139680Y784596D02*
Y785238D01*
X137854Y787064D01*
Y807872D01*
G01X145728D02*
Y784242D01*
X146150Y783820D01*
G01X181818Y274540D02*
X180796Y273518D01*
Y272874D01*
X179754Y271832D01*
X177909D01*
X175061Y268984D01*
X170517D01*
X170452Y268921D01*
X170384D01*
X170383Y268920D01*
X170051D01*
X169346Y268921D01*
X168991Y268922D01*
X168956Y268887D01*
X168886D01*
X168850Y268923D01*
G01X158605Y364565D02*
X171531Y351639D01*
Y328067D01*
X178742Y320856D01*
Y315184D01*
X179630Y314296D01*
X183227D01*
X186254Y311269D01*
Y310663D01*
G01X156058Y370080D02*
X152058D01*
G01D02*
Y367558D01*
X155051Y364565D01*
X158605D01*
G01X164058Y370080D02*
X160058D01*
G01D02*
Y368183D01*
X173193Y355048D01*
Y332141D01*
X183228Y322106D01*
Y317023D01*
G01X164058Y373230D02*
X163735Y373553D01*
Y380294D01*
G01X156058Y373230D02*
X156104Y373276D01*
Y380583D01*
G01X163735Y380294D02*
X160886D01*
G01X156104Y380583D02*
X157249D01*
X160710Y384044D01*
G01X150885Y577105D02*
X153430D01*
X154140Y577815D01*
G01X150885Y573105D02*
Y577105D01*
G01Y581013D02*
X154178D01*
X156480Y583315D01*
G01X165803Y643805D02*
X163100D01*
X162530Y643235D01*
G01X160181Y639044D02*
Y638784D01*
X162530Y636435D01*
G01X163138Y778565D02*
Y779421D01*
X157539Y785020D01*
Y807872D01*
G01X160480Y777583D02*
Y780186D01*
X153602Y787064D01*
Y807872D01*
G01X149665D02*
Y784003D01*
X149810Y783858D01*
G01X164630Y781222D02*
Y784993D01*
X161476Y788147D01*
Y807872D01*
G01X175110Y260412D02*
X171752D01*
X170501Y259161D01*
G01X169699Y269772D02*
X169750Y269721D01*
X170127D01*
X170192Y269784D01*
X174729D01*
X177577Y272632D01*
X179422D01*
X179996Y273206D01*
Y273953D01*
X179409Y274540D01*
X178818D01*
G01X188979Y273444D02*
X184332D01*
X181048Y270160D01*
X178941D01*
G01X169102Y285347D02*
X176894D01*
X178810Y287263D01*
G01X169102Y289347D02*
X174148Y289289D01*
G01X174860Y362416D02*
X176673Y360603D01*
X178567D01*
X180551Y358619D01*
Y326334D01*
X185728Y321157D01*
Y317736D01*
X186348Y317116D01*
X186350D01*
G01X172058Y373230D02*
X171934Y373354D01*
Y380727D01*
G01X172058Y370080D02*
X168058D01*
G01D02*
Y366888D01*
X172530Y362416D01*
X174860D01*
G01X180058Y370080D02*
X176058D01*
G01D02*
Y367178D01*
X182788Y360448D01*
Y352108D01*
G01X171934Y380727D02*
X175155D01*
G01X175663Y386424D02*
Y384972D01*
X179801Y380834D01*
Y380622D01*
G01X180058Y373230D02*
Y380365D01*
X179801Y380622D01*
G01X171180Y683815D02*
X176571D01*
X188380Y695624D01*
X190375D01*
G01X179693Y726467D02*
Y719041D01*
X180820Y717914D01*
G01X205940Y695436D02*
X193066D01*
X190553Y697949D01*
X189892D01*
X185890Y701951D01*
Y708214D01*
X183360Y710744D01*
Y712348D01*
X175463Y720245D01*
G01X179693Y729617D02*
X176167D01*
X174954Y728404D01*
G01X185440Y742231D02*
Y751629D01*
X180830Y756239D01*
Y777482D01*
X177070Y781242D01*
Y785736D01*
G01X177224Y807872D02*
Y785890D01*
X177070Y785736D01*
G01X169350Y807872D02*
Y788096D01*
X172600Y784846D01*
Y780150D01*
G01X167350Y778074D02*
Y784545D01*
X165413Y786482D01*
Y807872D01*
G01X189998Y112977D02*
Y106362D01*
X188203Y104567D01*
G01X194205Y271034D02*
Y279325D01*
X193245Y280285D01*
G01X189689Y268237D02*
X191600Y270148D01*
X191860D01*
G01X197847Y297731D02*
X191970D01*
G01X184953Y361563D02*
Y339843D01*
X188213Y336583D01*
Y328981D01*
X188199Y328967D01*
Y322893D01*
X190446Y320646D01*
X193293D01*
X196476Y317463D01*
Y317042D01*
G01X182788Y352108D02*
Y338476D01*
X182767Y338455D01*
Y326465D01*
X189623Y319609D01*
X193198D01*
X193957Y318850D01*
Y317064D01*
G01X192230Y337322D02*
Y337316D01*
X193810D01*
X195530Y339036D01*
Y340946D01*
G01X194185Y346834D02*
Y342291D01*
X195530Y340946D01*
G01X190058Y346744D02*
Y343934D01*
X189250Y343126D01*
Y337580D01*
X192040Y334790D01*
Y333606D01*
G01X188058Y370080D02*
X184058D01*
G01D02*
Y362458D01*
X184953Y361563D01*
G01X188058Y373230D02*
Y380638D01*
X187970Y380726D01*
G01X185074D02*
X187970D01*
G01X188640Y530667D02*
Y526848D01*
X189252Y526236D01*
G01X229199Y642180D02*
X221450Y634431D01*
Y627590D01*
X222153Y626887D01*
X225407D01*
X226110Y626184D01*
Y625190D01*
X225407Y624487D01*
X222153D01*
X221450Y623784D01*
Y622790D01*
X222153Y622087D01*
X225407D01*
X226110Y621384D01*
Y620390D01*
X225407Y619687D01*
X222153D01*
X221450Y618984D01*
Y616505D01*
X209390Y604445D01*
Y587711D01*
X207380Y585701D01*
Y577470D01*
X200422Y570512D01*
X192940D01*
X191500Y571952D01*
Y571956D01*
G01X205940Y687758D02*
X200993D01*
X200418Y687183D01*
X193377D01*
X188864Y682670D01*
X185993D01*
G01X191945Y701936D02*
X195735D01*
X196966Y700705D01*
G01X194440Y718048D02*
Y718733D01*
X196079Y720372D01*
Y723943D01*
G01X189940Y718081D02*
Y720573D01*
X191150Y721783D01*
Y724108D01*
G01X185440Y718081D02*
Y720573D01*
X186164Y721297D01*
Y724134D01*
G01X194440Y730731D02*
Y732625D01*
X192060Y735005D01*
Y739851D01*
X194440Y742231D01*
G01X189940Y730731D02*
Y732625D01*
X187450Y735115D01*
Y739741D01*
X189940Y742231D01*
G01X185440Y730731D02*
Y732121D01*
X182938Y734623D01*
Y740504D01*
X184665Y742231D01*
X185440D01*
G01X194440Y727581D02*
Y726548D01*
X196079Y724909D01*
Y723943D01*
G01X189940Y727581D02*
Y725318D01*
X191150Y724108D01*
G01X185440Y727581D02*
Y724858D01*
X186164Y724134D01*
G01X191081Y785766D02*
X192949Y783898D01*
Y777402D01*
X195060Y775291D01*
Y752608D01*
X198940Y748728D01*
Y742231D01*
G01X187570Y770605D02*
X188977Y769198D01*
Y753123D01*
X194440Y747660D01*
Y742231D01*
G01X183650Y774332D02*
X185075Y772907D01*
Y754415D01*
X189940Y749550D01*
Y742231D01*
G01X187570Y770605D02*
X187770Y770805D01*
Y786118D01*
X185098Y788790D01*
Y807872D01*
G01X181161D02*
Y785548D01*
X185070Y781639D01*
Y775752D01*
X183650Y774332D01*
G01X189035Y807872D02*
Y787812D01*
X191081Y785766D01*
G01X192972Y807872D02*
Y789201D01*
X196886Y785287D01*
Y779156D01*
G01X210998Y114957D02*
Y120892D01*
X210623Y121267D01*
G01X217072Y277567D02*
Y278443D01*
X216286Y279229D01*
X210915D01*
X208835Y277149D01*
Y273741D01*
X208101Y273007D01*
G01X205708Y277609D02*
Y274238D01*
X203787Y272317D01*
X198199D01*
X197850Y272666D01*
G01X203530Y320800D02*
Y324809D01*
X203520Y324819D01*
G01D02*
X207619D01*
X208000Y325200D01*
G01X208700Y328000D02*
Y327935D01*
X208400Y327635D01*
X207265D01*
X205500Y329400D01*
Y334169D01*
X206318Y334987D01*
G01X222911Y333155D02*
X218787Y337279D01*
Y348351D01*
X217319Y349819D01*
Y356596D01*
X214845Y359070D01*
X213061D01*
X200687Y371444D01*
Y374520D01*
G01D02*
Y379121D01*
G01X223095Y336241D02*
X219667Y339669D01*
Y348716D01*
X218319Y350064D01*
Y357599D01*
X215666Y360252D01*
X213518D01*
X208529Y365241D01*
Y366783D01*
G01X204687Y379121D02*
Y370641D01*
X208529Y366799D01*
Y366783D01*
G01X208687Y379121D02*
Y370866D01*
X219438Y360115D01*
Y352656D01*
X221280Y350814D01*
Y350255D01*
G01X203509Y481453D02*
Y476112D01*
X203628Y475993D01*
G01X229269Y597682D02*
X230990D01*
X231693Y598385D01*
Y616454D01*
X232396Y617157D01*
X233390D01*
X234093Y616454D01*
Y598385D01*
X234796Y597682D01*
X235922D01*
X237710Y595894D01*
Y591084D01*
X236084Y589458D01*
X226750D01*
X215026Y577734D01*
X214057D01*
X213353Y578438D01*
X213350D01*
Y579454D01*
X228060Y594164D01*
Y595188D01*
X228063Y595191D01*
X227359Y595895D01*
X226395D01*
X211610Y581110D01*
Y578463D01*
X210040Y576893D01*
G01X219685Y574231D02*
X216769D01*
X210790Y568252D01*
Y566926D01*
G01X209940Y584893D02*
Y586164D01*
X210820Y587044D01*
Y603213D01*
X211523Y603916D01*
X212517D01*
X213220Y603213D01*
Y587708D01*
X213820Y587108D01*
X214817D01*
X214818Y587116D01*
X215620Y587918D01*
Y608288D01*
X216894Y609562D01*
X221753D01*
X223150Y608165D01*
Y600571D01*
X223853Y599868D01*
X224847D01*
X225550Y600571D01*
Y615634D01*
X226253Y616337D01*
Y616334D01*
X227240D01*
X227950Y615624D01*
Y600303D01*
X225100Y597453D01*
G01X211560Y670575D02*
Y674456D01*
X208883Y677133D01*
X204248D01*
X202290Y679091D01*
Y681675D01*
X203255Y682640D01*
X205940D01*
G01Y690317D02*
X208875D01*
X210824Y692266D01*
G01X218240Y674433D02*
X217853D01*
X212205Y680081D01*
X205940D01*
G01Y685199D02*
X201921D01*
X199590Y682868D01*
G01X205940Y703113D02*
X203287D01*
X202555Y702381D01*
X198675D01*
X197582Y703474D01*
G01X205940Y705672D02*
X202283D01*
X200692Y704081D01*
G01X205940Y700554D02*
X197117D01*
X196966Y700705D01*
G01X228940Y705672D02*
X221458D01*
X216340Y700554D01*
X205940D01*
G01X203440Y718048D02*
Y718330D01*
X205883Y720773D01*
Y724373D01*
G01X198940Y718081D02*
Y718531D01*
X200817Y720408D01*
Y724180D01*
G01X207940Y718081D02*
X208787D01*
X211897Y721191D01*
Y723870D01*
G01X198940Y730731D02*
Y733125D01*
X196240Y735825D01*
Y739531D01*
X198940Y742231D01*
G01X207940Y730731D02*
Y733085D01*
X205320Y735705D01*
Y739611D01*
X207940Y742231D01*
G01X212440Y730731D02*
Y731304D01*
X210230Y733514D01*
Y740021D01*
X212440Y742231D01*
G01X203440Y730731D02*
Y733125D01*
X200890Y735675D01*
Y739681D01*
X203440Y742231D01*
G01Y727581D02*
Y727315D01*
X205883Y724872D01*
Y724373D01*
G01X198940Y727581D02*
Y727005D01*
X200817Y725128D01*
Y724180D01*
G01X207940Y727581D02*
Y726759D01*
X210829Y723870D01*
X211897D01*
G01X207940Y742231D02*
Y749016D01*
X202980Y753976D01*
Y769616D01*
X200550Y772046D01*
G01X206180Y777654D02*
Y775178D01*
X208697Y772661D01*
Y755623D01*
X212440Y751880D01*
Y742231D01*
G01X203440D02*
Y749796D01*
X196886Y756350D01*
Y779156D01*
G01X210250Y784919D02*
Y757099D01*
X216940Y750409D01*
Y742231D01*
G01X210250Y784919D02*
Y785101D01*
X208720Y786631D01*
Y807872D01*
G01X196909D02*
Y788272D01*
X199046Y786135D01*
Y773550D01*
X200550Y772046D01*
G01X206180Y777654D02*
X204780Y779054D01*
Y782154D01*
X204783D01*
Y807872D01*
G01X224740Y84629D02*
Y87505D01*
X226620Y89385D01*
G01X228745Y262568D02*
X226344D01*
X225973Y262197D01*
G01X219199Y288344D02*
X219737Y287806D01*
Y282974D01*
X221799Y280912D01*
X222018D01*
G01X222974Y356134D02*
X224837Y354271D01*
Y340529D01*
X223166Y338858D01*
Y338842D01*
G01X223831Y359027D02*
X226089Y356769D01*
Y339128D01*
X224996Y338035D01*
Y334617D01*
G01X221280Y350255D02*
Y340579D01*
G01X212687Y379121D02*
Y370171D01*
X223831Y359027D01*
G01X230725Y334547D02*
Y336236D01*
X229445Y337516D01*
Y351962D01*
X229657Y352174D01*
Y355264D01*
X230419Y356026D01*
Y357569D01*
X225951Y362037D01*
Y363369D01*
X221831Y367489D01*
X218768D01*
X216687Y369570D01*
Y374434D01*
G01D02*
Y379121D01*
G01X231144Y338225D02*
X230873Y338496D01*
Y355065D01*
X231419Y355611D01*
Y358027D01*
X227528Y361918D01*
Y364016D01*
X220687Y370857D01*
G01D02*
Y379121D01*
G01X232769Y333207D02*
Y333873D01*
X235455Y336559D01*
Y343617D01*
X233200Y345872D01*
Y351201D01*
X235862Y353863D01*
Y360500D01*
X230358Y366004D01*
Y368526D01*
X224759Y374125D01*
G01X224687Y379121D02*
X224364Y378798D01*
Y374520D01*
X224759Y374125D01*
G01X228820Y467780D02*
Y472843D01*
X226309Y475354D01*
X225070D01*
X223786Y476638D01*
G01X219694Y570116D02*
Y566333D01*
X218950Y565589D01*
G01X222844Y570116D02*
X224635D01*
X227838Y566913D01*
G01X235307Y566357D02*
X233141Y568523D01*
X230308D01*
X224600Y574231D01*
X222835D01*
G01X228940Y690317D02*
X224060D01*
G01X228940Y687758D02*
X224336D01*
G01X228940Y695436D02*
X223707D01*
G01X228940Y692876D02*
X220580D01*
G01X228940Y700554D02*
X223741D01*
G01X228940Y697995D02*
X221340D01*
G01X212440Y727581D02*
Y727540D01*
X214040Y725940D01*
Y723075D01*
X219209Y717906D01*
X225271D01*
Y717899D01*
X225591Y717579D01*
X248966D01*
X250740Y719353D01*
Y719457D01*
X250630D01*
G01X221440Y727581D02*
Y724789D01*
X223944Y722285D01*
X224596D01*
X225020Y721861D01*
X226584D01*
X227650Y720795D01*
Y720791D01*
G01X221440Y730731D02*
Y730914D01*
X219170Y733184D01*
Y739961D01*
X221440Y742231D01*
G01X216820Y723301D02*
X216940Y723421D01*
Y727581D01*
G01Y739081D02*
X214690Y736831D01*
Y729831D01*
X216940Y727581D01*
G01X225940Y739081D02*
X223950Y737091D01*
Y735661D01*
X225940Y733671D01*
G01D02*
Y730731D01*
G01X221440Y742231D02*
Y750544D01*
X214350Y757634D01*
Y779437D01*
X214160Y779627D01*
G01X225940Y742231D02*
Y749780D01*
X219520Y756200D01*
Y770824D01*
G01X226250Y785923D02*
Y779161D01*
X224670Y777581D01*
Y755858D01*
X230440Y750088D01*
Y742231D01*
G01X214160Y779627D02*
X214168D01*
X214358Y779817D01*
Y793962D01*
X212658Y795662D01*
Y807872D01*
G01X219520Y770824D02*
X216515Y773829D01*
Y783288D01*
X215760Y784043D01*
Y786032D01*
X216594Y786866D01*
Y807872D01*
G01X224469D02*
Y787704D01*
X226250Y785923D01*
G01X230725Y325649D02*
X228432Y323356D01*
Y321468D01*
G01X235518Y329412D02*
X231049D01*
X230253Y328616D01*
G01X235220Y348277D02*
X236338Y347159D01*
Y335932D01*
X238548Y333722D01*
Y333149D01*
G01X246410Y348948D02*
X244628Y344465D01*
X241818Y338690D01*
Y337347D01*
X240598Y336127D01*
Y334642D01*
G01X240218Y338010D02*
X240935Y338727D01*
Y341089D01*
X242301Y342455D01*
X243896Y348494D01*
Y355039D01*
X245258Y358468D01*
G01X240241Y352958D02*
X237359Y345074D01*
Y338302D01*
X238560Y337101D01*
Y336136D01*
G01X232873Y342946D02*
X233170Y342649D01*
X233423D01*
X234655Y341417D01*
Y337995D01*
X232841Y336181D01*
X232804D01*
G01X241179Y347675D02*
X238522Y345018D01*
Y341196D01*
X239290Y340428D01*
G01X238643Y360796D02*
Y359221D01*
X239784Y358080D01*
Y355381D01*
X235220Y350817D01*
Y348277D01*
G01X232687Y377621D02*
X234228Y375821D01*
X238779Y371403D01*
X239603Y370579D01*
Y367574D01*
X240486Y364769D01*
X241084Y359508D01*
Y355138D01*
X240241Y352958D01*
G01X241179Y347675D02*
X242280Y348776D01*
Y366014D01*
X240920Y367374D01*
Y371303D01*
X234430Y377793D01*
Y394401D01*
X236186Y396157D01*
X257310D01*
X258230Y397077D01*
X274160D01*
X276149Y399066D01*
X295391D01*
X297663Y401338D01*
X313663D01*
X317323Y404998D01*
X321840D01*
X337459Y420617D01*
X342714D01*
X345659Y417672D01*
X373210D01*
X382680Y408202D01*
G01X236687Y379121D02*
X236680D01*
Y377611D01*
X245080Y369211D01*
Y368852D01*
X246663Y363650D01*
Y362484D01*
X245263Y358468D01*
X245258D01*
G01X331900Y419317D02*
X331175D01*
X327507Y415649D01*
X322799D01*
X317315Y410165D01*
X314401D01*
X308905Y404669D01*
X262447D01*
X256738Y398960D01*
X232274D01*
X228310Y394996D01*
Y388401D01*
X230540Y386171D01*
Y375884D01*
X232890Y373534D01*
Y371121D01*
X238643Y365368D01*
Y363946D01*
G01X248690Y388933D02*
X243487D01*
X242240Y390180D01*
Y390808D01*
X241451Y391597D01*
Y392147D01*
G01X236687Y382271D02*
Y382829D01*
X238450Y384592D01*
Y385880D01*
X236608Y387722D01*
X236412D01*
G01X236430Y393470D02*
X236500Y393400D01*
Y390604D01*
X239750Y387354D01*
Y379081D01*
X240913Y377918D01*
Y377150D01*
G01X232687Y380771D02*
Y385894D01*
X230153Y388428D01*
Y390354D01*
X231223Y391424D01*
G01X241599Y381197D02*
X241585Y382179D01*
Y387358D01*
X239546Y389397D01*
Y390528D01*
G01X232647Y396011D02*
X234173D01*
X235939Y397777D01*
X257220D01*
X257703Y398260D01*
X273669D01*
X275637Y400228D01*
X294990D01*
X297200Y402438D01*
X310681D01*
X314660Y406417D01*
X318188D01*
X321910Y410139D01*
G01X280210Y460762D02*
X278576D01*
X274960Y464378D01*
X250001D01*
X247486Y466893D01*
X245214D01*
X240683Y462362D01*
X234490D01*
X233319Y463533D01*
X233310D01*
Y466464D01*
X231609Y468165D01*
Y482886D01*
X232759Y484036D01*
Y499967D01*
X233626Y500834D01*
Y502591D01*
G01X235319Y470268D02*
Y476118D01*
X236209Y477008D01*
Y482758D01*
X234909Y484058D01*
Y489653D01*
G01X236909Y494453D02*
Y485777D01*
X239559Y483127D01*
Y468998D01*
X241979Y466578D01*
G01X239700Y486907D02*
Y485603D01*
X241909Y483394D01*
Y478128D01*
G01X246089Y478179D02*
Y481640D01*
X242218Y485511D01*
Y494824D01*
X242502Y495108D01*
Y496300D01*
G01X239700Y486907D02*
X240309Y487516D01*
Y497553D01*
X242609Y499853D01*
Y502125D01*
X243075Y502591D01*
G01Y508891D02*
X242139D01*
X240574Y507326D01*
X239296D01*
X238360Y506390D01*
Y499706D01*
X234909Y496255D01*
Y489653D01*
G01X249374Y508891D02*
X247809Y507326D01*
X242446D01*
X241490Y506370D01*
Y500634D01*
X238509Y497653D01*
Y496053D01*
X236909Y494453D01*
G01X236776Y515190D02*
Y514633D01*
X235196Y513053D01*
Y503634D01*
X236064Y502766D01*
Y500887D01*
X236085Y500866D01*
G01X246224Y502591D02*
X243609Y499976D01*
Y499438D01*
X242502Y498331D01*
Y496300D01*
G01X236776Y515190D02*
Y515886D01*
X235888Y516774D01*
X228330D01*
X227784Y516228D01*
Y515853D01*
G01D02*
Y515278D01*
X229437Y513625D01*
X234302D01*
X235867Y515190D01*
X236776D01*
G01X235209Y522853D02*
Y520404D01*
X234709Y519904D01*
X228709D01*
G01X235209Y526853D02*
Y529853D01*
G01X228709Y523074D02*
X234709D01*
G01X234710Y526223D02*
X229019D01*
G01X228909Y535653D02*
X238609D01*
G01X239925Y537236D02*
X239477D01*
X237911Y538802D01*
X228709D01*
X228676Y538835D01*
G01X242834Y564253D02*
X244384Y562703D01*
Y561962D01*
X246224Y560122D01*
Y559284D01*
G01X236209Y574878D02*
Y570878D01*
X242834Y564253D01*
G01X246224Y556134D02*
X244646Y557712D01*
Y559927D01*
X243023Y561550D01*
X242811D01*
X233858Y570503D01*
X232088D01*
G01X227838Y566913D02*
X232479Y562272D01*
X233787D01*
X243075Y552984D01*
G01X231809Y574878D02*
Y570782D01*
X232088Y570503D01*
G01X240509Y574878D02*
Y572873D01*
X241928Y571454D01*
Y570263D01*
G01D02*
Y567847D01*
X246224Y563551D01*
Y562434D01*
G01X244780Y682521D02*
Y682529D01*
X242110Y685199D01*
X228940D01*
G01Y682640D02*
X231945D01*
X234976Y679609D01*
X237275D01*
G01X228940Y703113D02*
X234235D01*
X236680Y700668D01*
G01X241348Y703150D02*
X239162D01*
X236680Y700668D01*
G01X228940Y708231D02*
X234286D01*
X236120Y706397D01*
Y704173D01*
G01X239440Y727581D02*
X238430D01*
Y721922D01*
X239210Y721142D01*
Y720040D01*
G01X243940Y730731D02*
X242120D01*
X241650Y730261D01*
Y723187D01*
X243008Y721829D01*
X248530D01*
G01X230440Y727581D02*
X232490Y725531D01*
Y723389D01*
X234910Y720969D01*
Y720816D01*
G01X230440Y730731D02*
Y732042D01*
X228170Y734312D01*
Y739961D01*
X230440Y742231D01*
G01X239440Y730731D02*
X237170Y733001D01*
Y739961D01*
X239440Y742231D01*
G01X243940Y739081D02*
X242050Y737191D01*
Y734868D01*
X243940Y732978D01*
Y730731D01*
G01X234940D02*
Y733355D01*
G01Y739081D02*
X233220Y737361D01*
Y735075D01*
X234940Y733355D01*
G01Y742231D02*
Y749512D01*
X231460Y752992D01*
Y780174D01*
G01X238470Y770074D02*
Y766096D01*
X239440Y765126D01*
Y742231D01*
G01X243940D02*
Y757071D01*
X241630Y759381D01*
Y770487D01*
X240080Y772037D01*
Y779908D01*
G01X231460Y780174D02*
Y783139D01*
X228406Y786193D01*
Y807872D01*
G01X232343D02*
Y794807D01*
X234060Y793090D01*
Y784064D01*
X237190Y780934D01*
Y771354D01*
X238470Y770074D01*
G01X240080Y779908D02*
Y785596D01*
X236280Y789396D01*
Y807872D01*
G01X258248Y110597D02*
Y101462D01*
X256133Y99347D01*
G01X244634Y263052D02*
Y261894D01*
X247389Y259139D01*
G01X261024Y280657D02*
Y279609D01*
X258536Y277121D01*
X257567D01*
X255290Y274844D01*
X253205D01*
X252261Y273900D01*
Y272285D01*
G01X258380Y295984D02*
Y294581D01*
X261907Y291054D01*
X266761D01*
X268294Y289521D01*
X269592D01*
X272829Y292758D01*
X290902D01*
X293594Y290066D01*
X304860D01*
X311437Y283489D01*
X340147D01*
X343220Y280416D01*
G01X244099Y299998D02*
Y300218D01*
X245429Y301548D01*
X255200D01*
X256980Y299768D01*
Y299300D01*
G01X247249Y306298D02*
X249969D01*
X250469Y305798D01*
G01X309347Y291940D02*
X307961Y293326D01*
X306126D01*
X304189Y295263D01*
X294443D01*
X291810Y297896D01*
X267691D01*
X266458Y299129D01*
X260939D01*
X257418Y302650D01*
Y303533D01*
G01X254905Y327213D02*
X258901Y331209D01*
Y349610D01*
X258818Y349693D01*
G01X249457Y368527D02*
X249379Y368605D01*
Y346032D01*
X247718Y344371D01*
Y340728D01*
X246685Y339695D01*
Y337357D01*
G01X254998Y329779D02*
X257978Y332759D01*
Y342542D01*
X257602Y342918D01*
X255918Y349218D01*
Y355555D01*
X254870Y356603D01*
Y363785D01*
X254445Y364210D01*
Y364991D01*
G01X255124Y335244D02*
X255771D01*
X256711Y336184D01*
Y341260D01*
X255662Y342309D01*
X253490Y350748D01*
Y356341D01*
X253493D01*
Y358451D01*
X251814Y364337D01*
Y373034D01*
X251126Y373722D01*
G01X256331Y371006D02*
X256588Y370749D01*
Y359005D01*
G01X244063Y377150D02*
X246122Y370422D01*
X247965Y364237D01*
Y355225D01*
X246410Y348948D01*
G01X260350Y366987D02*
X258748D01*
X257731Y365970D01*
Y361068D01*
X258509Y360290D01*
Y356517D01*
X257316Y355324D01*
Y351195D01*
X258818Y349693D01*
G01X244749Y381197D02*
X246260Y379686D01*
Y376620D01*
X247594Y373553D01*
X247647D01*
X249460Y371740D01*
Y368527D01*
X249457D01*
G01D02*
X249410D01*
G01X258687Y388902D02*
Y377746D01*
X256331Y375390D01*
Y371006D01*
G01X252687Y379121D02*
Y375873D01*
X253879Y374681D01*
Y365557D01*
X254445Y364991D01*
G01X248687Y379121D02*
Y376161D01*
X251126Y373722D01*
G01X256687Y379121D02*
X252687D01*
G01X248687Y382271D02*
X248853Y382437D01*
Y388770D01*
X248690Y388933D01*
G01X253762Y385255D02*
Y390859D01*
X258665Y395762D01*
X274705D01*
X276909Y397966D01*
X296149D01*
X298103Y399920D01*
X313806D01*
X317181Y403295D01*
X322966D01*
X336740Y417069D01*
G01X251309Y466078D02*
X248809Y468578D01*
Y481391D01*
X244509Y485691D01*
Y491353D01*
G01X255509Y465978D02*
X253509Y467978D01*
Y482553D01*
X248209Y487853D01*
Y497953D01*
X248609Y498353D01*
G01X255509Y478128D02*
Y482153D01*
X249509Y488153D01*
Y492653D01*
X250322Y493466D01*
G01X264909Y465978D02*
X262609Y468278D01*
Y481053D01*
X258109Y485553D01*
Y487353D01*
X256809Y488653D01*
Y496153D01*
G01X260609Y478128D02*
Y481053D01*
X257109Y484553D01*
Y486553D01*
X254809Y488853D01*
Y491153D01*
G01X251309Y478128D02*
Y481453D01*
X246509Y486253D01*
Y486753D01*
G01X260609Y465978D02*
X258609Y467978D01*
Y481053D01*
X254999Y484663D01*
Y485763D01*
G01D02*
X252309Y488453D01*
Y492453D01*
X253309Y493453D01*
Y500453D01*
X254089Y501233D01*
Y507326D01*
X252524Y508891D01*
G01X255673D02*
Y508089D01*
X258480Y505282D01*
Y501242D01*
X258109Y500871D01*
Y498753D01*
X258809Y498053D01*
Y488753D01*
X260609Y486953D01*
Y486153D01*
G01X252524Y502591D02*
Y502168D01*
X250809Y500453D01*
Y493953D01*
X250322Y493466D01*
G01X255673Y505741D02*
Y504889D01*
X257309Y503253D01*
Y501753D01*
X256809Y501253D01*
Y496153D01*
G01X249374Y505741D02*
X247789Y504156D01*
Y501942D01*
X245309Y499462D01*
Y498353D01*
X244509Y497553D01*
Y491353D01*
G01X255673Y502591D02*
Y500653D01*
X254609Y499589D01*
Y491353D01*
X254809Y491153D01*
G01X249374Y502591D02*
Y502018D01*
X246509Y499153D01*
Y486753D01*
G01X252524Y505741D02*
Y505668D01*
X250939Y504083D01*
Y501942D01*
X248609Y499612D01*
Y498353D01*
G01X257440Y727581D02*
X256570Y726711D01*
Y722151D01*
X257010Y721711D01*
Y707298D01*
X259170Y705138D01*
G01X252940Y727581D02*
X255310Y725211D01*
Y715915D01*
G01X252940Y730731D02*
Y731097D01*
X250780Y733257D01*
Y740071D01*
X252940Y742231D01*
G01X248440Y730731D02*
Y733026D01*
X245770Y735696D01*
Y739561D01*
X248440Y742231D01*
G01Y727581D02*
Y724961D01*
X248770Y724631D01*
G01X257440Y730731D02*
Y733272D01*
X255310Y735402D01*
Y741198D01*
X256150Y742038D01*
X257247D01*
X257440Y742231D01*
G01X252940D02*
Y760649D01*
X249190Y764399D01*
Y769760D01*
G01X244910Y785782D02*
Y761457D01*
X248440Y757927D01*
Y742231D01*
G01X256650Y770638D02*
Y744321D01*
X258090Y742881D01*
X257440Y742231D01*
G01X249190Y769760D02*
X249900Y770470D01*
Y783042D01*
X248091Y784851D01*
Y807872D01*
G01X252028D02*
Y794100D01*
X254630Y791498D01*
Y772658D01*
X256650Y770638D01*
G01X244154Y807872D02*
Y786538D01*
X244910Y785782D01*
G01X260000Y785233D02*
Y787412D01*
X255965Y791447D01*
Y807872D01*
G01X341693Y286010D02*
X311927D01*
X304071Y293866D01*
X274360D01*
X274281Y293787D01*
X272955D01*
X270695Y296047D01*
X267386D01*
G01X259943Y306987D02*
X261775Y305155D01*
X264739D01*
X266576Y306992D01*
X268299D01*
G01X342754Y295326D02*
X341496Y294068D01*
X331353D01*
X330456Y293171D01*
X314017D01*
X311862Y295326D01*
X307733D01*
X306196Y296863D01*
X295107D01*
X292474Y299496D01*
X268355D01*
X264742Y303109D01*
X264501D01*
G01X315019Y295263D02*
X313956Y296326D01*
X308750D01*
X307413Y297663D01*
X295439D01*
X292646Y300456D01*
X268982D01*
X266939Y302499D01*
Y303281D01*
G01X274303Y303413D02*
X275759Y304869D01*
X280650D01*
X282663Y302856D01*
X295551D01*
X295969Y303274D01*
X301530D01*
X304341Y300463D01*
X329472D01*
X331870Y302861D01*
X334622D01*
G01X331867Y291367D02*
X312900D01*
X309941Y294326D01*
X306893D01*
X305156Y296063D01*
X294775D01*
X292142Y298696D01*
X268023D01*
X266790Y299929D01*
X261330D01*
X259820Y301439D01*
Y303800D01*
G01X275832Y329303D02*
Y328944D01*
X275116Y328228D01*
X272677D01*
X270525Y326076D01*
Y325754D01*
G01X262201Y328491D02*
X261055Y329637D01*
Y330052D01*
X260023Y335081D01*
Y342616D01*
X260970Y343563D01*
G01X285390Y390550D02*
X283530Y388690D01*
X281971D01*
X279940Y386659D01*
Y382642D01*
X278312Y381014D01*
X277559D01*
X273145Y376600D01*
Y371907D01*
X272380Y371142D01*
Y343225D01*
X270644Y341489D01*
Y339189D01*
X270485Y339030D01*
G01X270796Y386643D02*
X270629Y386476D01*
Y372503D01*
X266630Y368504D01*
Y357354D01*
X266629Y357344D01*
X266507Y356169D01*
Y356037D01*
X266490Y355855D01*
Y347172D01*
X265302Y345984D01*
Y337438D01*
X264015Y336151D01*
G01X272687Y379121D02*
X271815Y378249D01*
Y372074D01*
X267630Y367889D01*
Y357299D01*
X267507Y356117D01*
Y346581D01*
X266181Y345255D01*
Y334802D01*
X263173Y331794D01*
G01X269716Y349689D02*
X270102Y349303D01*
Y342190D01*
X267943Y340031D01*
Y339617D01*
G01X316331Y378971D02*
Y371187D01*
X314790Y369646D01*
X312525D01*
X310850Y371321D01*
Y380780D01*
X312071Y382001D01*
X315777D01*
X317464Y383688D01*
Y389273D01*
X316664Y390073D01*
X311741D01*
X310941Y390873D01*
Y392673D01*
X311741Y393473D01*
X316664D01*
X318264Y395073D01*
X319494D01*
X320294Y394273D01*
Y379452D01*
X320894Y378852D01*
X322524D01*
X323124Y379452D01*
Y394273D01*
X323924Y395073D01*
X325154D01*
X325954Y394273D01*
Y377815D01*
X326554Y377215D01*
X328184D01*
X328784Y377815D01*
Y394273D01*
X329584Y395073D01*
X330814D01*
X331614Y394273D01*
Y374904D01*
X332414Y374104D01*
X333644D01*
X334444Y374904D01*
Y382805D01*
X340566Y388927D01*
X353156D01*
X354090Y389861D01*
Y391269D01*
X353032Y392327D01*
X341583D01*
X340880Y393030D01*
Y394024D01*
X341583Y394727D01*
X355007D01*
X355710Y395430D01*
Y396424D01*
X355007Y397127D01*
X341583D01*
X340880Y397830D01*
Y398824D01*
X341583Y399527D01*
X361080D01*
X361680Y400127D01*
Y401327D01*
X361080Y401927D01*
X340683D01*
X339980Y402630D01*
Y403624D01*
X340683Y404327D01*
X359367D01*
X360070Y405030D01*
Y406024D01*
X359367Y406727D01*
X339930D01*
X339130Y407527D01*
Y408827D01*
X339930Y409627D01*
X361080D01*
X361880Y410427D01*
Y411727D01*
X361080Y412527D01*
X335446D01*
X332820Y409901D01*
Y398390D01*
X332020Y397590D01*
X299046D01*
X294639Y393183D01*
X284495D01*
X283109Y391797D01*
X279431D01*
X278045Y393183D01*
X267825D01*
X265142Y390500D01*
Y386780D01*
X266397Y385525D01*
Y382375D01*
X264936Y380914D01*
Y372427D01*
X263340Y370831D01*
Y352389D01*
X260970Y343563D01*
G01X268118Y374558D02*
Y372086D01*
X265630Y369598D01*
Y357769D01*
X265472Y356872D01*
Y348100D01*
X264502Y347130D01*
Y344094D01*
X261805Y341397D01*
Y339827D01*
X262379Y339253D01*
Y338103D01*
G01X270071Y333021D02*
Y333787D01*
X268726Y335132D01*
Y336458D01*
X269663Y337395D01*
X271449D01*
X277202Y343148D01*
Y347600D01*
X275902Y348900D01*
Y355665D01*
G01X280971Y349730D02*
Y347635D01*
X280543Y347207D01*
Y346251D01*
X278016Y343724D01*
Y339975D01*
X277260Y339219D01*
Y338194D01*
X276323Y337257D01*
X274466D01*
X273871Y336662D01*
G01D02*
X272263Y335054D01*
Y334222D01*
G01X288220Y389630D02*
Y387897D01*
X279524Y379200D01*
X277179D01*
X274920Y376941D01*
Y368606D01*
X273680Y367366D01*
Y342228D01*
X272352Y340900D01*
G01X260687Y379121D02*
Y378408D01*
X262642Y376453D01*
Y373411D01*
X260350Y371119D01*
Y366987D01*
G01X268687Y379121D02*
X268118Y378552D01*
Y374558D01*
G01X278263Y387669D02*
X278938Y386994D01*
Y383055D01*
X277897Y382014D01*
X275577D01*
X272687Y379124D01*
Y379121D01*
G01X268687Y382271D02*
Y387602D01*
X271843Y390758D01*
X275497D01*
G01X273509Y465978D02*
X271309Y468178D01*
Y481315D01*
X261842Y490782D01*
Y495086D01*
X264909Y498153D01*
G01X269209Y465978D02*
X267034Y468153D01*
Y479586D01*
X263409Y483211D01*
Y486383D01*
X259809Y489983D01*
Y498453D01*
X260109Y498753D01*
Y500153D01*
G01X264909Y478128D02*
Y480247D01*
X260609Y484547D01*
Y486153D01*
G01X261972Y502591D02*
X262409Y502154D01*
Y499553D01*
X260809Y497953D01*
Y490399D01*
X266205Y485003D01*
Y483343D01*
G01X269109Y478128D02*
Y480439D01*
X266205Y483343D01*
G01X272209Y485753D02*
X269653D01*
X265989Y489417D01*
Y495751D01*
X267409Y497171D01*
Y500890D01*
X266687Y501612D01*
Y504176D01*
X265122Y505741D01*
G01X272209Y485753D02*
X273209Y484753D01*
Y478128D01*
G01X278311Y478202D02*
X278237Y478128D01*
X273209D01*
G01X265121Y508891D02*
X264096Y507866D01*
Y507865D01*
X263557Y507326D01*
Y501305D01*
X264909Y499953D01*
Y498153D01*
G01X261972Y505741D02*
X260109Y503878D01*
Y500153D01*
G01X258748Y509415D02*
X261448D01*
X261972Y508891D01*
G01D02*
Y509826D01*
X263537Y511391D01*
Y514083D01*
X265009Y515555D01*
G01X271421Y552985D02*
X266098Y558308D01*
Y561963D01*
G01X277590Y579734D02*
Y577723D01*
X276840Y576973D01*
X276838D01*
Y573603D01*
X266098Y562863D01*
Y561963D01*
G01X266418Y580633D02*
Y572544D01*
X268009Y570953D01*
G01X311935Y675156D02*
Y676827D01*
X311410Y677352D01*
X302159D01*
X292159Y687352D01*
X288590D01*
X280260Y695682D01*
Y695828D01*
X270085Y706003D01*
X269410D01*
G01X261940Y727581D02*
Y722356D01*
X262940Y721356D01*
Y706539D01*
X265648Y703831D01*
X266010D01*
Y703826D01*
X267000Y702836D01*
Y702479D01*
X281501Y687978D01*
X282391D01*
G01X311935Y679156D02*
Y680795D01*
X311510Y681220D01*
X300018D01*
X288638Y692600D01*
X286825D01*
X271533Y707892D01*
X267124D01*
G01X266440Y727581D02*
X266930Y727091D01*
Y719451D01*
X277074Y709307D01*
X281629D01*
X283914Y707022D01*
X284760D01*
G01X271210Y718000D02*
Y719405D01*
X269240Y721375D01*
Y724082D01*
X270940Y725782D01*
Y727581D01*
G01X264600Y723086D02*
Y719377D01*
X276884Y707093D01*
X279200D01*
X294162Y692131D01*
X297500D01*
X304675Y684956D01*
X311332D01*
X311935Y684353D01*
Y683156D01*
G01Y687156D02*
Y687963D01*
X310942Y688956D01*
X305330D01*
X299065Y695221D01*
X296471D01*
X288798Y702894D01*
Y705389D01*
X285465Y708722D01*
X284298D01*
X270940Y722080D01*
G01X266440Y742231D02*
X264220Y740011D01*
Y734986D01*
X266440Y732766D01*
Y730731D01*
G01X275440D02*
Y732157D01*
X273160Y734437D01*
Y739951D01*
X275440Y742231D01*
G01X270940Y739081D02*
X270264D01*
X268640Y737457D01*
Y729881D01*
X270940Y727581D01*
G01X261940Y730731D02*
Y732285D01*
X259620Y734605D01*
Y739911D01*
X261940Y742231D01*
G01X266440D02*
Y785561D01*
X266850Y785971D01*
G01X269890Y773268D02*
Y745940D01*
X270940Y744890D01*
Y742231D01*
G01X260000Y785233D02*
Y746071D01*
X262890Y743181D01*
X261940Y742231D01*
G01X269890Y773268D02*
Y787108D01*
X267776Y789222D01*
Y807872D01*
G01X271713D02*
Y795647D01*
X274260Y793100D01*
Y780128D01*
X272880Y778748D01*
Y774483D01*
X275440Y771923D01*
Y770793D01*
G01X266850Y785971D02*
X263839Y788982D01*
Y807872D01*
G01X282337Y308217D02*
X282666D01*
X284202Y309753D01*
X288658D01*
X291527Y312622D01*
X308031D01*
X309666Y310987D01*
X323273D01*
X324936Y312650D01*
Y316855D01*
X329487Y321406D01*
X344102D01*
X347652Y324956D01*
X360385D01*
X373040Y337611D01*
Y357259D01*
X384580Y368799D01*
Y409394D01*
X389410Y414224D01*
Y465471D01*
X394076Y470137D01*
Y471803D01*
X393990Y471889D01*
Y518546D01*
X396558Y521114D01*
Y522251D01*
G01X277816Y309678D02*
Y308543D01*
X279744Y306615D01*
X283659D01*
X284574Y305700D01*
G01X288942Y306875D02*
X285749D01*
X284574Y305700D01*
G01X339487Y301038D02*
X336353Y297904D01*
X327938D01*
X327279Y298563D01*
X304997D01*
X301086Y302474D01*
X296301D01*
X295883Y302056D01*
X280967D01*
X279754Y303269D01*
G01X274832Y309687D02*
Y308377D01*
X276282Y306927D01*
G01X314418Y302798D02*
X311853D01*
X311418Y302363D01*
X305789D01*
X305132Y303020D01*
Y304931D01*
X304007Y306056D01*
X294043D01*
X291733Y303746D01*
X283073D01*
X281150Y305669D01*
X277540D01*
X276282Y306927D01*
G01X291853Y327033D02*
X291393Y327493D01*
X287575D01*
X286316Y326234D01*
Y322421D01*
X285704Y321809D01*
G01X295388Y375644D02*
X295387Y375643D01*
Y374674D01*
X291508Y370795D01*
Y358611D01*
X288500Y355603D01*
Y350777D01*
X291790Y347487D01*
Y339699D01*
X290809Y338718D01*
X287712D01*
X286457Y337463D01*
X282859D01*
X281875Y336479D01*
X279485D01*
X277288Y334282D01*
G01X296218Y353688D02*
Y350504D01*
X296780Y349942D01*
Y341452D01*
X290537Y335209D01*
X283651D01*
X282234Y333792D01*
G01X283498Y364252D02*
Y363770D01*
X283099Y363371D01*
Y354669D01*
X284418Y353350D01*
Y352698D01*
X289191Y347925D01*
Y341348D01*
G01X286020Y356454D02*
X289371Y359805D01*
Y372616D01*
X288870Y373117D01*
Y380392D01*
X293290Y384812D01*
Y389737D01*
G01X279863Y367513D02*
X280042Y367334D01*
Y358589D01*
G01X277821Y349730D02*
Y350142D01*
X279318Y351639D01*
Y355820D01*
X280042Y356544D01*
Y358589D01*
G01X276825Y363867D02*
Y362932D01*
X275902Y362009D01*
Y355665D01*
G01X276825Y367017D02*
Y371575D01*
X280401Y375151D01*
X285801D01*
X286550Y374402D01*
G01X283498Y367402D02*
X281450Y369450D01*
Y373151D01*
G01X278311Y475052D02*
X280080Y473283D01*
Y467584D01*
X280380Y467284D01*
G01X282368Y475038D02*
X282370D01*
Y466075D01*
X281088Y464793D01*
X278990D01*
G01X282368Y478188D02*
X278325D01*
X278311Y478202D01*
G01X296913Y507831D02*
X289260D01*
X284024Y502595D01*
G01X284168Y547993D02*
X282320Y549841D01*
X280872D01*
G01X294909Y578653D02*
Y576039D01*
X287413Y568543D01*
X283530D01*
X282439Y567452D01*
Y557704D01*
X282095Y557361D01*
Y557360D01*
X280874Y556139D01*
G01X274538Y562523D02*
X274572Y562289D01*
Y556142D01*
G01X300575Y646192D02*
X297276D01*
X296867Y645783D01*
X287767D01*
X285997Y647553D01*
Y662477D01*
X289365Y665845D01*
G01X292420Y649242D02*
X288175D01*
X287997Y649064D01*
G01X282391Y687978D02*
X285415Y684954D01*
X293136D01*
X304734Y673356D01*
X310660D01*
X311935Y672081D01*
Y671156D01*
G01X289060Y722193D02*
X288478Y722775D01*
X288394D01*
X286150Y725019D01*
Y728032D01*
X288630Y730512D01*
G01X281830Y722184D02*
Y722904D01*
X282140Y723214D01*
Y728231D01*
X279940Y730431D01*
G01X275440Y727581D02*
X277230Y725791D01*
Y723620D01*
X277880Y722970D01*
Y721683D01*
X285130Y714433D01*
G01X284020Y724956D02*
X283770Y724706D01*
Y718623D01*
X291584Y710809D01*
Y702801D01*
X294823Y699562D01*
X297864D01*
X300372Y697054D01*
X301990D01*
X305892Y700956D01*
X310711D01*
X311935Y699732D01*
Y699156D01*
G01X287440Y739081D02*
Y737566D01*
X286390Y736516D01*
Y732752D01*
X288630Y730512D01*
G01X279440Y739081D02*
Y738769D01*
X277660Y736989D01*
Y732711D01*
X279940Y730431D01*
G01X275440Y770793D02*
Y742231D01*
G01X279440D02*
Y745006D01*
X279940Y745506D01*
Y756364D01*
X279470Y756834D01*
Y785456D01*
X278549Y786377D01*
G01X283524Y807872D02*
Y782472D01*
X284440Y781556D01*
Y747585D01*
X284532Y747493D01*
G01X283440Y742231D02*
Y744624D01*
X284440Y745624D01*
Y747401D01*
X284532Y747493D01*
G01X287440Y742231D02*
Y743811D01*
X288940Y745311D01*
Y761717D01*
X289020Y761797D01*
Y778372D01*
X289028Y778380D01*
G01D02*
Y787149D01*
X287461Y788716D01*
Y807872D01*
G01X275650D02*
Y789276D01*
X278549Y786377D01*
G01X296639Y308057D02*
X297523Y307173D01*
X307006D01*
X308075Y306104D01*
X309798D01*
G01X292092Y306875D02*
Y309362D01*
X294118Y311388D01*
X298190D01*
X301377Y308201D01*
X307775D01*
X308597Y309023D01*
X324674D01*
X327515Y311864D01*
G01X291853Y327033D02*
X293086Y325800D01*
X299135D01*
G01D02*
X301840Y328505D01*
Y332937D01*
X303283Y334380D01*
X304970D01*
G01X303525Y344346D02*
X304620D01*
X306820Y342146D01*
G01X306464Y330406D02*
X304831D01*
X303759Y331478D01*
G01X296218Y353688D02*
Y356292D01*
X299564Y359638D01*
Y364656D01*
X297131Y367089D01*
Y369021D01*
G01D02*
X301131D01*
G01X301457Y507829D02*
Y505346D01*
X298706Y502595D01*
X290323D01*
G01X305708Y507818D02*
Y503043D01*
G01X296338Y548763D02*
X295260Y549841D01*
X290322D01*
G01X300848Y556253D02*
X296735D01*
X295047Y554565D01*
G01X294909Y578653D02*
Y582978D01*
G01X303725Y646192D02*
Y642208D01*
G01D02*
X306587D01*
X308683Y644304D01*
X315893D01*
X316183Y644594D01*
G01X296453Y649199D02*
X297634D01*
X299470Y651035D01*
Y654320D01*
X301070Y655920D01*
G01X292420Y652392D02*
Y655929D01*
X292850Y656359D01*
G01X296453Y652349D02*
Y656092D01*
X297394Y657033D01*
G01X303538Y710198D02*
Y711873D01*
X304668Y713003D01*
X307113D01*
G01X299638Y710198D02*
Y713303D01*
X300756Y714421D01*
X303681D01*
G01X301450Y726195D02*
Y721413D01*
X304170Y718693D01*
X308430D01*
G01X299440Y742231D02*
X301140Y740531D01*
Y737891D01*
X300860Y737611D01*
Y729935D01*
X301450Y729345D01*
G01X303440Y742231D02*
Y742056D01*
X305240Y740256D01*
Y731342D01*
X305640Y730942D01*
G01Y727792D02*
X305895D01*
X311544Y722143D01*
X319182D01*
X324470Y716855D01*
X326340D01*
X328700Y714495D01*
Y709992D01*
X332666Y706026D01*
G01X292840Y732672D02*
X295239D01*
X295700Y733133D01*
G01X295440Y739081D02*
X295700Y738821D01*
Y733133D01*
G01X291398Y807872D02*
Y794639D01*
X293100Y792937D01*
Y785459D01*
X293340Y785219D01*
Y748480D01*
X293440Y748380D01*
G01X291440Y742231D02*
Y746380D01*
X293440Y748380D01*
G01X295440Y742231D02*
Y745869D01*
X297940Y748369D01*
Y751139D01*
X297249Y751830D01*
Y773447D01*
X297280Y773478D01*
Y778936D01*
G01X302440Y784731D02*
Y745231D01*
X299440Y742231D01*
G01X303440D02*
Y743045D01*
X306940Y746545D01*
Y764145D01*
X309260Y766465D01*
Y785133D01*
X310050Y785923D01*
G01X297280Y778936D02*
Y787757D01*
X295335Y789702D01*
Y807872D01*
G01X302440Y784731D02*
Y785350D01*
X303209Y786119D01*
Y807872D01*
G01X315019Y295263D02*
X337184D01*
X340022Y298101D01*
X347950D01*
G01X309347Y291940D02*
X312918Y288369D01*
X342163D01*
X343662Y286870D01*
X350331D01*
X351100Y286101D01*
Y284101D01*
G01X317607Y306876D02*
X323155D01*
X323935Y306096D01*
X329603D01*
X333270Y309763D01*
Y310225D01*
X337441Y314396D01*
X339480D01*
X342670Y317586D01*
X345980D01*
X346624Y318230D01*
X348192D01*
G01X314457Y306876D02*
X310570D01*
X309798Y306104D01*
G01X317568Y302798D02*
X329029D01*
X335715Y309484D01*
Y309841D01*
X336720Y310846D01*
G01X316075Y326386D02*
X312287D01*
X311740Y325839D01*
G01X313181Y378971D02*
Y374270D01*
X313222Y374229D01*
G01X311935Y651156D02*
Y647156D01*
G01X316190Y649621D02*
X318794Y652225D01*
X318810D01*
Y653178D01*
X320374Y654742D01*
X322468D01*
G01X316190Y649621D02*
X313725Y647156D01*
X311935D01*
G01X316183Y644594D02*
X318180Y646591D01*
Y649122D01*
X318681Y649623D01*
X322468D01*
G01Y657301D02*
X316585D01*
X314440Y655156D01*
X311935D01*
G01Y659156D02*
X314980D01*
X315684Y659860D01*
X322468D01*
G01X322440Y668581D02*
X318650D01*
X318303Y668928D01*
X316250D01*
X316190Y668868D01*
Y668863D01*
G01X311935Y667156D02*
X314483D01*
X316190Y668863D01*
G01X322440Y678817D02*
X317371D01*
X313710Y675156D01*
X311935D01*
G01Y671156D02*
X314710D01*
X319812Y676258D01*
X322440D01*
G01X322468Y662419D02*
X316395D01*
X316184Y662630D01*
G01X311935Y663156D02*
X315658D01*
X316184Y662630D01*
G01X322440Y683936D02*
X317063D01*
X316283Y683156D01*
X311935D01*
G01Y691156D02*
X314225D01*
X314614Y690767D01*
G01X322440Y689054D02*
X317595D01*
X315882Y690767D01*
X314614D01*
G01X316184Y687630D02*
X313896D01*
X313422Y687156D01*
X311935D01*
G01X322440Y686495D02*
X317319D01*
X316184Y687630D01*
G01X322440Y681376D02*
X318410D01*
X316190Y679156D01*
X311935D01*
G01Y695156D02*
X314413D01*
X316165Y693404D01*
G01X322440Y691613D02*
X320282D01*
X318491Y693404D01*
X316165D01*
G01X322440Y694172D02*
X319973D01*
X314989Y699156D01*
X311935D01*
G01X319620Y716403D02*
X320120Y715903D01*
Y710153D01*
X327840Y702433D01*
Y691444D01*
X340467Y678817D01*
X345440D01*
G01Y689054D02*
X342147D01*
X340679Y690522D01*
X337117D01*
X334410Y693229D01*
Y697455D01*
X334420Y697465D01*
Y701148D01*
X327700Y707868D01*
Y714080D01*
X325925Y715855D01*
X323100D01*
X320552Y718403D01*
X318798D01*
X318691Y718296D01*
X314209D01*
X313204Y719301D01*
X311280D01*
X310672Y718693D01*
X308430D01*
G01X309530Y730942D02*
Y733372D01*
X309740Y733582D01*
Y739831D01*
X309710Y739861D01*
Y741184D01*
X308663Y742231D01*
X307940D01*
G01X309530Y727792D02*
Y726541D01*
X311538Y724533D01*
X314930D01*
G01X311940Y742231D02*
X312423D01*
X314050Y740604D01*
Y734685D01*
X313410Y734045D01*
Y732276D01*
G01Y729126D02*
X321304D01*
X330940Y719490D01*
Y719125D01*
G01X307940Y742231D02*
Y744595D01*
X311440Y748095D01*
Y774049D01*
G01X311940Y742231D02*
Y744975D01*
X315570Y748605D01*
Y776923D01*
X317020Y778373D01*
Y786486D01*
G01X311440Y774049D02*
Y782396D01*
X312783Y783739D01*
Y792576D01*
X311083Y794276D01*
Y807872D01*
G01X317020Y786486D02*
Y788128D01*
X315020Y790128D01*
Y807872D01*
G01X307146D02*
Y788827D01*
X310050Y785923D01*
G01X335798Y117297D02*
Y124502D01*
X331583Y128717D01*
G01X331867Y291367D02*
X333299Y292799D01*
X339148D01*
X343546Y288401D01*
X349400D01*
X351100Y290101D01*
G01X334622Y302861D02*
X337452Y305691D01*
Y306596D01*
X340019Y309163D01*
X344407D01*
X345345Y310101D01*
X347950D01*
G01X327515Y311864D02*
Y316524D01*
X330477Y319486D01*
X345183D01*
X348581Y322884D01*
X361001D01*
X374940Y336823D01*
Y356471D01*
X386480Y368011D01*
Y396593D01*
X387720Y397833D01*
Y409549D01*
X391310Y413139D01*
Y464137D01*
X396470Y469297D01*
Y511018D01*
X399070Y513618D01*
Y525247D01*
X396470Y527847D01*
G01X347722Y314102D02*
X345456D01*
X345450Y314096D01*
X343950D01*
X341920Y312066D01*
X337940D01*
X336720Y310846D01*
G01X322468Y647064D02*
X324569D01*
X329440Y651935D01*
Y655016D01*
X328760Y655696D01*
Y657144D01*
G01X329912Y662383D02*
X330490Y661805D01*
Y659173D01*
X330640Y659023D01*
Y650342D01*
X324803Y644505D01*
X322468D01*
G01X333180Y665611D02*
X334220D01*
X336020Y663811D01*
Y660553D01*
X338230Y658343D01*
Y653481D01*
X339529Y652182D01*
X345468D01*
G01Y649623D02*
X339179D01*
X335910Y652892D01*
Y654978D01*
X333910Y656978D01*
Y659903D01*
X334313Y660306D01*
Y663113D01*
G01X327500Y667244D02*
Y658554D01*
X326247Y657301D01*
X322468D01*
G01X335915Y675011D02*
X336580D01*
X339092Y672499D01*
X340001D01*
X341360Y671140D01*
X345440D01*
G01X335390Y667895D02*
X337420Y665865D01*
Y661133D01*
X341252Y657301D01*
X345468D01*
G01X327257Y672408D02*
X334443Y679594D01*
X338269D01*
X340046Y677817D01*
X340993D01*
X342552Y676258D01*
X345440D01*
G01X322440Y673699D02*
X326567D01*
X327257Y673009D01*
Y672408D01*
G01X322440Y671140D02*
X326773D01*
X327257Y671624D01*
Y672408D01*
G01X335130Y670744D02*
X338940Y666934D01*
Y664567D01*
X340576Y662931D01*
X340623D01*
X341630Y661924D01*
Y661416D01*
X343164Y659882D01*
Y659860D01*
X345468D01*
G01X324970Y665128D02*
X326300Y663798D01*
Y660969D01*
X325191Y659860D01*
X322468D01*
G01X337030Y677894D02*
Y676753D01*
X340084Y673699D01*
X345440D01*
G01X331520Y701642D02*
X331020Y701142D01*
Y691094D01*
X338178Y683936D01*
X345440D01*
G01X332720Y698170D02*
Y693504D01*
X337232Y688992D01*
X340680D01*
X343177Y686495D01*
X345440D01*
G01Y681376D02*
Y681373D01*
X339326D01*
X328840Y691859D01*
Y703032D01*
X325920Y705952D01*
Y713031D01*
X325560Y713391D01*
G01X330410Y712895D02*
X341660Y701645D01*
Y694876D01*
X342364Y694172D01*
X345440D01*
G01X332666Y706026D02*
X335890Y702802D01*
Y696726D01*
X341009Y691607D01*
X345440D01*
Y691613D01*
G01X330940Y719125D02*
Y716041D01*
X342929Y704052D01*
X354924D01*
X355955Y703021D01*
Y701128D01*
G01X352400Y722132D02*
X349644D01*
X344898Y726878D01*
X329034D01*
X322871Y733039D01*
Y785090D01*
G01X328280Y770057D02*
X327643Y769420D01*
Y735206D01*
X334285Y728564D01*
X348874D01*
X351617Y725821D01*
X365579D01*
X367220Y727462D01*
Y728534D01*
X369336Y730650D01*
Y731459D01*
G01X354520Y728701D02*
X353457Y729764D01*
X337666D01*
X332240Y735190D01*
Y756433D01*
X335610Y759803D01*
Y782568D01*
X338642Y785600D01*
Y785716D01*
G01X322894Y807872D02*
Y785113D01*
X322871Y785090D01*
G01X328280Y770057D02*
Y785064D01*
X326831Y786513D01*
Y807872D01*
G01X358555Y280317D02*
X358339Y280101D01*
X351100D01*
G01D02*
X348706Y277707D01*
X345929D01*
X343220Y280416D01*
G01X342754Y295326D02*
X346285D01*
X346760Y295801D01*
X349140D01*
X349550Y295391D01*
Y295326D01*
X349875D01*
X351100Y294101D01*
G01X358555Y294317D02*
X358339Y294101D01*
X351100D01*
G01X358555Y284317D02*
X358339Y284101D01*
X351100D01*
G01X358555Y290317D02*
X358339Y290101D01*
X351100D01*
G01X344520Y301883D02*
X340332D01*
X339487Y301038D01*
G01X358555Y298317D02*
X357984D01*
X356409Y299892D01*
X350567D01*
X350476Y299801D01*
X349910D01*
X348210Y298101D01*
X347950D01*
G01Y310101D02*
Y306101D01*
G01X348192Y318230D02*
Y319107D01*
X349621Y320536D01*
X364571D01*
X371590Y327555D01*
X373710D01*
X376840Y330685D01*
Y355683D01*
X388380Y367223D01*
Y395805D01*
X392390Y399815D01*
Y408311D01*
X393997Y409918D01*
X394075D01*
X395070Y410913D01*
Y412323D01*
X394080Y413313D01*
Y463985D01*
X398372Y468277D01*
Y510230D01*
X400972Y512830D01*
Y534493D01*
X403812Y537333D01*
X408486D01*
G01X345468Y644505D02*
X348444D01*
X351821Y641128D01*
X355955D01*
G01X348480Y638558D02*
Y638552D01*
X349900Y637132D01*
X355955D01*
Y637128D01*
G01Y645175D02*
X352704D01*
X351720Y644191D01*
G01D02*
X351127D01*
X348254Y647064D01*
X345468D01*
G01Y652182D02*
X349737D01*
X349759Y652160D01*
X354188D01*
X355156Y653128D01*
X355955D01*
G01X345468Y659860D02*
X347692D01*
X350424Y657128D01*
X355955D01*
G01Y649128D02*
X354033Y647206D01*
X350760D01*
X348343Y649623D01*
X345468D01*
G01X345440Y676258D02*
X350529D01*
X351730Y675057D01*
G01D02*
X353378Y673409D01*
Y672420D01*
X355955Y669843D01*
Y669128D01*
G01X345468Y662419D02*
X342843D01*
X340870Y664392D01*
Y665042D01*
G01X355955Y661128D02*
X350001D01*
X348710Y662419D01*
X345468D01*
G01X345440Y683936D02*
X348820D01*
X349063Y683693D01*
X351709D01*
X354274Y681128D01*
X355955D01*
G01X345440Y678817D02*
X351095D01*
X355955Y673957D01*
Y673128D01*
G01Y685128D02*
X353513D01*
X352146Y686495D01*
X345440D01*
G01X355955Y689128D02*
X355363D01*
X353695Y690796D01*
X351672D01*
X349930Y689054D01*
X345440D01*
G01Y681376D02*
X350830D01*
X355078Y677128D01*
X355955D01*
G01X345440Y694172D02*
X350290D01*
X353246Y697128D01*
X355955D01*
G01Y701128D02*
X354027D01*
X349630Y696731D01*
X345440D01*
G01X355955Y693128D02*
X351015D01*
X349500Y691613D01*
X345440D01*
G01X357096Y723537D02*
X353805D01*
X352400Y722132D01*
G01X342230Y709384D02*
X347426D01*
X352010Y713968D01*
G01X338270Y733387D02*
X340381Y731276D01*
X357995D01*
X360246Y733527D01*
Y735537D01*
G01X357096D02*
X356372D01*
X342579Y749330D01*
Y778930D01*
X343369Y779720D01*
G01X345100Y771906D02*
Y751342D01*
X350720Y745722D01*
G01X350630Y777187D02*
X352420Y775397D01*
Y741323D01*
X356414Y737329D01*
X367466D01*
X369336Y735459D01*
G01X343369Y779720D02*
X343370D01*
G01X342579Y807872D02*
Y780510D01*
X343369Y779720D01*
G01X346516Y807872D02*
Y792699D01*
X348216Y790999D01*
Y781737D01*
X345100Y778621D01*
Y771906D01*
G01X350630Y777187D02*
X352550Y779107D01*
Y788363D01*
X350453Y790460D01*
Y807872D01*
G01X338642D02*
Y785716D01*
G01X363025Y12926D02*
X365267Y10684D01*
X399700D01*
X432940Y43924D01*
Y62790D01*
X439670Y69520D01*
Y70044D01*
G01X442380Y75513D02*
X429810Y62943D01*
Y44442D01*
X398294Y12926D01*
X363025D01*
G01X364980Y655266D02*
X365530Y654716D01*
Y649197D01*
X368450Y646277D01*
Y639600D01*
X365945Y637095D01*
X362102D01*
X362069Y637128D01*
X359105D01*
G01X364950Y639095D02*
X357464D01*
X355955Y640604D01*
Y641128D01*
G01X357830Y718682D02*
X357920Y718772D01*
Y720670D01*
X360246Y722996D01*
Y723537D01*
G01X406940Y709231D02*
X404140D01*
X403858Y708949D01*
X401153D01*
X388094Y722008D01*
X370366D01*
X370180Y721822D01*
X365443D01*
X364920Y721299D01*
Y720059D01*
G01X376946Y689985D02*
X369930Y697001D01*
Y702948D01*
X369360Y703518D01*
Y706219D01*
X367583Y707996D01*
Y709853D01*
X361980Y715456D01*
Y717119D01*
X364920Y720059D01*
G01X357096Y727537D02*
X355684D01*
X354520Y728701D01*
G01X360246Y735537D02*
X363311D01*
X363460Y735388D01*
G01X360246Y727537D02*
X364466D01*
X364750Y727821D01*
G01X356600Y782086D02*
Y772487D01*
X356870Y772217D01*
Y751648D01*
X354420Y749198D01*
G01D02*
X355396Y748222D01*
Y740105D01*
X355964Y739537D01*
X357096D01*
G01X362264Y786424D02*
X362120Y786280D01*
Y782952D01*
X361300Y782132D01*
Y779029D01*
X361760Y778569D01*
Y776752D01*
X362160Y776352D01*
Y774694D01*
X361760Y774294D01*
Y747148D01*
X360246Y745634D01*
Y743537D01*
G01X357610Y748302D02*
Y747966D01*
X357096Y747452D01*
Y743537D01*
G01X366860Y739956D02*
X366430Y740386D01*
Y766405D01*
X370130Y770105D01*
G01X366860Y739956D02*
Y739949D01*
X367350Y739459D01*
X369336D01*
G01X358327Y807872D02*
X358320D01*
X358160Y807712D01*
Y783646D01*
X356600Y782086D01*
G01X362264Y807872D02*
Y786424D01*
G01X378508Y117817D02*
X378510D01*
X379650Y118957D01*
Y123437D01*
X378183Y124904D01*
G01X391683Y658078D02*
X383871D01*
X383860Y658089D01*
G01D02*
Y656100D01*
X381820Y654060D01*
Y648061D01*
X383627Y646254D01*
G01X373433Y677656D02*
X380088D01*
X382311Y675433D01*
X384868D01*
G01X383940Y681081D02*
Y676361D01*
X384868Y675433D01*
G01X373433Y685656D02*
X374709D01*
X375408Y686355D01*
X377673D01*
G01X383940Y686199D02*
X380529D01*
X380373Y686355D01*
X377673D01*
G01X383940Y683640D02*
X379967D01*
X377682Y681355D01*
G01X373433Y681656D02*
X377381D01*
X377682Y681355D01*
G01X376635Y715026D02*
X376640D01*
X379090Y712576D01*
Y708481D01*
X380899Y706672D01*
X383940D01*
G01X391740Y705957D02*
Y705962D01*
X391030Y706672D01*
X383940D01*
G01X377100Y697218D02*
X377079D01*
X370360Y703937D01*
Y706948D01*
X369170Y708138D01*
Y712652D01*
X370920Y714402D01*
Y715351D01*
X372595Y717026D01*
X380356D01*
X382134Y715248D01*
X384333D01*
G01X390950Y701922D02*
X388759Y704113D01*
X383940D01*
G01D02*
X375497D01*
X374844Y704766D01*
X372360D01*
G01X387483Y715248D02*
Y717149D01*
X386024Y718608D01*
X370363D01*
X368920Y720051D01*
Y720059D01*
G01X372486Y735459D02*
X372807D01*
X375548Y732718D01*
Y731459D01*
G01X372486D02*
Y730807D01*
X375834Y727459D01*
G01X377840Y724388D02*
X378900Y725448D01*
Y736693D01*
X378350Y737243D01*
Y747682D01*
X373370Y752662D01*
Y783928D01*
G01X377840Y724388D02*
X375681D01*
X372578Y727491D01*
Y727622D01*
G01X373500Y748457D02*
X373496D01*
X372486Y747447D01*
Y743459D01*
G01X370130Y770105D02*
Y788248D01*
X370138Y788256D01*
Y807872D01*
G01X373370Y783928D02*
X374075Y784633D01*
Y807872D01*
G01X409481Y252489D02*
X407546D01*
X406208Y251151D01*
X402078D01*
X400848Y252381D01*
Y253276D01*
X397198Y256926D01*
Y269051D01*
X404868Y276721D01*
X425288D01*
X435683Y287116D01*
X437859D01*
X450872Y300129D01*
X451790D01*
G01X409481Y260489D02*
Y260998D01*
X407598Y262881D01*
X403118D01*
X399518Y266481D01*
Y269956D01*
X405283Y275721D01*
X425711D01*
X436106Y286116D01*
X438280D01*
X442717Y290553D01*
X452582D01*
X453810Y289325D01*
G01X396366Y653229D02*
X395257Y654338D01*
X391683D01*
G01D02*
X387157D01*
X385145Y652326D01*
G01X391683Y650598D02*
X393555D01*
X399223Y644930D01*
G01X396411Y664578D02*
Y665491D01*
X400517Y669597D01*
Y673712D01*
X398016Y676213D01*
G01X399873Y666411D02*
X400599Y667137D01*
X403989D01*
G01X398016Y676213D02*
Y679843D01*
X397593Y680266D01*
X396550D01*
G01X406940Y686199D02*
X404110D01*
X400118Y690191D01*
X399829D01*
G01X406940Y704113D02*
X396381D01*
X391910Y699642D01*
Y696742D01*
G01X406940Y698995D02*
X401036D01*
X398620Y701411D01*
G01X406940Y706672D02*
X402012D01*
X393436Y715248D01*
X391790D01*
G01X387483D02*
X391790D01*
G01X400730Y721954D02*
Y721113D01*
X399443Y719826D01*
Y716254D01*
G01X404310Y65213D02*
Y66709D01*
X407303Y69702D01*
Y95117D01*
G01X401220Y65155D02*
X406258Y70193D01*
Y91911D01*
X404813Y93356D01*
Y93887D01*
G01X412631Y264679D02*
Y268679D01*
G01Y260489D02*
X413536D01*
X414578Y261531D01*
Y263631D01*
X417248Y266301D01*
G01X420858Y261331D02*
Y258601D01*
X418746Y256489D01*
X412631D01*
G01D02*
Y252489D01*
G01Y268679D02*
X417910D01*
X422858Y263731D01*
Y259311D01*
X422528Y258981D01*
Y253531D01*
G01X412631Y272731D02*
X413818D01*
X414711Y271838D01*
X428759D01*
X445540Y288619D01*
Y288853D01*
G01X412631Y268679D02*
Y272731D01*
G01X449183Y650754D02*
X447429Y649000D01*
X442800D01*
X440768Y651032D01*
X421235D01*
X411982Y660285D01*
G01X413966Y675624D02*
X414090D01*
X419014Y670700D01*
Y664852D01*
X425334Y658532D01*
Y656419D01*
G01X453235Y650730D02*
Y652676D01*
X451956Y653955D01*
X438631D01*
X438571Y653895D01*
X423249D01*
X422712Y654432D01*
X422072D01*
X415210Y661294D01*
Y664203D01*
X415218D01*
G01X403989Y667137D02*
X405964D01*
X407758Y665343D01*
X413028D01*
X416938Y669253D01*
Y669947D01*
G01X405343Y676183D02*
X410998D01*
X416938Y670243D01*
Y669947D01*
G01X411862Y688027D02*
X410034Y686199D01*
X406940D01*
G01Y683640D02*
X404150D01*
X401091Y686699D01*
X400968D01*
G01X406940Y688758D02*
X409275D01*
X410546Y690029D01*
X417532D01*
X418381Y690878D01*
G01X429820Y656709D02*
X428440Y658089D01*
Y661415D01*
X420020Y669835D01*
Y671975D01*
X413991Y678004D01*
X411532D01*
X411149Y678387D01*
G01X420289Y700660D02*
X417838Y703111D01*
X411990D01*
X410433Y701554D01*
X406940D01*
G01Y698995D02*
X409717D01*
X413600Y695112D01*
X417739D01*
X420548Y692303D01*
X422060D01*
X422108Y692351D01*
X423815D01*
X426873Y689293D01*
Y687881D01*
X425200Y686208D01*
Y675053D01*
X441121Y659132D01*
X445975D01*
X458267Y671424D01*
X471602D01*
X480610Y662416D01*
Y658316D01*
X484180Y654746D01*
Y643265D01*
X479563Y638648D01*
X474877D01*
X462652Y626423D01*
X459690D01*
G01X412080Y719034D02*
X419950Y711164D01*
Y706306D01*
X422612Y703644D01*
X427246D01*
X429818Y701072D01*
X434499D01*
X436415Y699156D01*
G01X414080Y721334D02*
X411975D01*
X410380Y719739D01*
Y718329D01*
X416112Y712597D01*
X416435D01*
X417430Y711602D01*
Y707411D01*
X422197Y702644D01*
X422515D01*
X425686Y699473D01*
X427755D01*
X429872Y697356D01*
X434217D01*
X436415Y695158D01*
Y695156D01*
G01X413940Y742231D02*
X411780Y740071D01*
Y734507D01*
X413940Y732347D01*
Y730731D01*
G01Y727581D02*
Y725365D01*
X416670Y722635D01*
Y718080D01*
X417330Y717420D01*
G01X413940Y742231D02*
X413600Y742571D01*
Y779159D01*
X414130Y779689D01*
G01X413447Y807872D02*
Y785995D01*
X416464Y782978D01*
Y773962D01*
X417552Y772874D01*
G01X409510Y807872D02*
Y797038D01*
X412130Y794418D01*
Y781689D01*
X414130Y779689D01*
G01X417248Y266301D02*
X418575Y264974D01*
Y263691D01*
G01X448460Y625960D02*
X451381Y623039D01*
X466266D01*
X485180Y641953D01*
Y655252D01*
X481610Y658822D01*
Y662830D01*
X481195Y663246D01*
X472017Y672424D01*
X457320D01*
X448039Y663143D01*
X438525D01*
X426200Y675468D01*
Y685764D01*
X428910Y688474D01*
Y694980D01*
X425417Y698473D01*
X425080D01*
X422893Y700660D01*
X420289D01*
G01X418852Y685654D02*
Y690407D01*
X418381Y690878D01*
G01X427230Y707377D02*
X429477Y705130D01*
X434389D01*
X436415Y707156D01*
G01X421730Y717398D02*
X420202D01*
X418440Y719160D01*
Y727581D01*
G01X429240Y721014D02*
X429250D01*
Y721015D01*
X429230D01*
Y720995D01*
X429820Y720405D01*
Y714249D01*
X428938Y713367D01*
Y710410D01*
X429992Y709356D01*
X434378D01*
X436178Y711156D01*
X436415D01*
G01X422940Y739081D02*
X421630Y737771D01*
Y735081D01*
X420290Y733741D01*
G01X422940Y730731D02*
Y731091D01*
X420290Y733741D01*
G01X426940Y742231D02*
X425407D01*
X424740Y741564D01*
Y736895D01*
X423900Y736055D01*
G01X418440Y730731D02*
Y732926D01*
X416570Y734796D01*
Y740361D01*
X418440Y742231D01*
G01X431440Y723955D02*
X429640Y725755D01*
Y729609D01*
X428518Y730731D01*
X427440D01*
G01X431440Y739081D02*
X430650D01*
X429160Y737591D01*
Y734076D01*
X427440Y732356D01*
Y730731D01*
G01X422940Y742231D02*
Y765760D01*
X422010Y766690D01*
G01X425540Y786506D02*
X424900Y785866D01*
Y747413D01*
X426940Y745373D01*
Y742231D01*
G01X431440D02*
Y743751D01*
X431290Y743901D01*
Y785484D01*
G01X417552Y772874D02*
Y763635D01*
X418440Y762747D01*
Y742231D01*
G01X422010Y766690D02*
X419690Y769010D01*
Y780377D01*
X419880Y780567D01*
Y789397D01*
X419330Y789947D01*
Y793844D01*
X417384Y795790D01*
Y807872D01*
G01X429195D02*
Y788707D01*
X431290Y786612D01*
Y785484D01*
G01X425540Y786506D02*
X425370Y786676D01*
Y807762D01*
X425260Y807872D01*
X425258D01*
G01X451226Y642685D02*
X448890D01*
X446500Y645075D01*
G01X449183Y647604D02*
X449029D01*
X446500Y645075D01*
G01X442650Y719485D02*
X445530Y716605D01*
X454096D01*
X455770Y714931D01*
Y713521D01*
X453860Y711611D01*
Y675786D01*
X447210Y669136D01*
Y665143D01*
G01X446940Y686140D02*
X451506D01*
X451980Y686614D01*
Y688267D01*
X451548Y688699D01*
X446940D01*
G01Y686140D02*
X444435D01*
X442733Y684438D01*
X440688D01*
G01X436415Y683156D02*
X439406D01*
X440688Y684438D01*
G01X446940Y683581D02*
Y679387D01*
X445648Y678095D01*
X442920D01*
G01D02*
X440920D01*
X439859Y679156D01*
X436415D01*
G01X446940Y691258D02*
X442508D01*
X440688Y689438D01*
G01X436415Y687156D02*
X438406D01*
X440688Y689438D01*
G01X436415Y691156D02*
X437406D01*
X440688Y694438D01*
G01X446940Y701495D02*
X441581D01*
X440690Y702386D01*
G01D02*
X439920Y703156D01*
X436415D01*
G01Y699156D02*
X437959D01*
X438241Y699438D01*
X443072D01*
X443574Y698936D01*
X446940D01*
G01Y706613D02*
X440995D01*
X436712Y710896D01*
X436675D01*
X436415Y711156D01*
G01X446940Y704054D02*
X443360D01*
X442702Y704712D01*
X440464D01*
X438020Y707156D01*
X436415D01*
G01Y695156D02*
X437914Y696655D01*
X442627D01*
X442906Y696376D01*
X446940D01*
G01Y693817D02*
X443460D01*
X442839Y694438D01*
X440688D01*
G01X435940Y742231D02*
X434431D01*
X433470Y741270D01*
X433240Y741044D01*
Y724715D01*
X434280Y723675D01*
Y719128D01*
G01X446940Y709172D02*
X442838D01*
X441198Y710812D01*
Y711527D01*
X440660Y712065D01*
G01D02*
X439585Y713140D01*
X438870D01*
X436854Y715156D01*
X436415D01*
G01X449060Y721761D02*
X447613Y720314D01*
X444231D01*
X443360Y721185D01*
X441940D01*
X439883Y719128D01*
X437430D01*
G01X439200Y722093D02*
X438880Y722413D01*
Y729662D01*
X437811Y730731D01*
X436440D01*
G01X444940Y742231D02*
X443492D01*
X442140Y740879D01*
Y737891D01*
X441640Y737391D01*
Y733990D01*
X440940Y733290D01*
Y730731D01*
G01X442120Y724781D02*
Y725897D01*
X440940Y727077D01*
Y727581D01*
G01X436440Y730731D02*
Y733816D01*
X438140Y735516D01*
Y738291D01*
X438930Y739081D01*
X440440D01*
G01X445440Y730731D02*
Y731324D01*
X447680Y733564D01*
G01X440440Y742231D02*
Y764673D01*
X442100Y766333D01*
Y777623D01*
G01X446510Y784890D02*
Y767571D01*
X444940Y766001D01*
Y742231D01*
G01X435940D02*
Y765444D01*
X436560Y766064D01*
Y770904D01*
G01X442100Y777623D02*
X438770Y780953D01*
Y794066D01*
X437069Y795767D01*
Y807872D01*
G01X444943D02*
Y786457D01*
X446510Y784890D01*
G01X436560Y770904D02*
Y783043D01*
X433132Y786471D01*
Y807872D01*
G01X468400Y135800D02*
X466500Y137700D01*
Y154900D01*
X469500Y157900D01*
Y161600D01*
X466500Y164600D01*
Y198575D01*
X459000Y206075D01*
G01D02*
X464975D01*
X466200Y207300D01*
G01X454371Y638786D02*
Y642680D01*
X454376Y642685D01*
G01D02*
X456704D01*
X458903Y644884D01*
G01X460587Y669424D02*
Y661990D01*
X458938Y660341D01*
Y655198D01*
G01X461997Y654507D02*
X461254D01*
X460563Y655198D01*
X458938D01*
G01X453233Y657403D02*
Y659346D01*
X457138Y663251D01*
G01X453235Y647580D02*
X463081D01*
X463178Y647483D01*
G01X457060Y722427D02*
X457170Y722317D01*
Y712941D01*
X455260Y711031D01*
Y682075D01*
X460308Y677027D01*
X466754D01*
X468985Y674796D01*
X473490D01*
X477493Y670793D01*
X489461D01*
X490350Y669904D01*
X492632D01*
X497320Y665216D01*
G01X469940Y704054D02*
X465199D01*
X459122Y710131D01*
Y715410D01*
X461650Y717938D01*
Y724371D01*
X458440Y727581D01*
G01X469940Y706613D02*
X466480D01*
X462980Y710113D01*
Y727041D01*
X462440Y727581D01*
G01X453940Y742231D02*
X451330Y739621D01*
Y735167D01*
X452110Y734387D01*
Y732977D01*
X449972Y730839D01*
X449940D01*
Y730731D01*
G01X462440Y742231D02*
X460200Y739991D01*
Y734250D01*
X458440Y732490D01*
Y730731D01*
G01X466440Y742231D02*
Y741964D01*
X466100Y741624D01*
X466093D01*
X464740Y740271D01*
Y735006D01*
X462440Y732706D01*
Y730731D01*
G01X454440D02*
Y733143D01*
X455410Y734113D01*
G01D02*
X458440Y737143D01*
Y739081D01*
G01X449940Y727581D02*
Y726424D01*
X451320Y725044D01*
G01X447680Y733564D02*
X447745Y733629D01*
Y736374D01*
X449440Y738069D01*
Y739081D01*
G01X454399Y771873D02*
X453940Y771414D01*
Y742231D01*
G01X458440D02*
Y775219D01*
X457530Y776129D01*
Y779016D01*
G01X449610Y777933D02*
Y767291D01*
X449440Y767121D01*
Y742231D01*
G01X466070Y774997D02*
Y768144D01*
X462440Y764514D01*
Y742231D01*
G01X454399Y771873D02*
X454510Y771984D01*
Y774853D01*
X452120Y777243D01*
Y794584D01*
X452817Y795281D01*
Y807872D01*
G01X457530Y779016D02*
X458454Y779940D01*
Y792181D01*
X456754Y793881D01*
Y807872D01*
G01X449610Y777933D02*
Y779421D01*
X448880Y780151D01*
Y807872D01*
G01X476400Y203100D02*
Y195600D01*
X470900Y190100D01*
Y165200D01*
X472100Y164000D01*
Y162000D01*
X476100Y158000D01*
Y156500D01*
X471500Y151900D01*
Y146000D01*
X475100Y142400D01*
Y138200D01*
X470324Y133424D01*
G01X471300Y201900D02*
Y193600D01*
X468900Y191200D01*
Y165000D01*
X470800Y163100D01*
Y156300D01*
X469000Y154500D01*
Y143075D01*
G01D02*
X470425D01*
X473200Y140300D01*
G01X479125Y168113D02*
X476394D01*
X475760Y168747D01*
G01X472670Y166398D02*
X474899D01*
X477184Y164113D01*
X479125D01*
G01X475385Y180383D02*
Y179664D01*
X473580Y177859D01*
G01X473950Y172124D02*
X476943D01*
X476954Y172113D01*
X479125D01*
G01Y176113D02*
X478486D01*
X477216Y174843D01*
X474630D01*
G01X482980Y181071D02*
X482292Y180383D01*
X478535D01*
G01X478000Y206925D02*
Y204700D01*
X476400Y203100D01*
G01X473898Y652798D02*
X471934D01*
X470689Y651553D01*
X469437D01*
X468810Y652180D01*
G01X473216Y656713D02*
X472481D01*
X468810Y653042D01*
Y652180D01*
G01X466980Y667059D02*
X469608D01*
X473044Y663623D01*
X473363D01*
G01X469467Y679915D02*
X467268D01*
X465090Y682093D01*
Y686751D01*
X467038Y688699D01*
X469940D01*
G01X469977Y676496D02*
X471167Y677686D01*
Y680620D01*
X470172Y681615D01*
X467266D01*
X466290Y682591D01*
Y685554D01*
X466876Y686140D01*
X469940D01*
G01Y691258D02*
X478467D01*
X481227Y688498D01*
Y685366D01*
G01X485465Y698656D02*
X482626Y701495D01*
X469940D01*
G01X490900Y706145D02*
X483000D01*
X480909Y704054D01*
X469940D01*
G01X488090Y710545D02*
X484484D01*
X480552Y706613D01*
X469940D01*
G01Y693817D02*
X478776D01*
X481227Y691366D01*
G01X469940Y696376D02*
X481217D01*
X481227Y696366D01*
G01X485465Y694656D02*
X483850Y696271D01*
Y697660D01*
X482574Y698936D01*
X469940D01*
G01Y711731D02*
Y717916D01*
X468740Y719116D01*
Y725881D01*
X470440Y727581D01*
G01X488180Y719244D02*
X486906D01*
X479393Y711731D01*
X469940D01*
G01Y709172D02*
X467122D01*
X463980Y712314D01*
Y725121D01*
X466440Y727581D01*
G01X490890Y714898D02*
Y714895D01*
X485211D01*
X479488Y709172D01*
X469940D01*
G01X466440Y730731D02*
X468590Y732881D01*
Y741862D01*
X468959Y742231D01*
X470440D01*
G01X473560Y724951D02*
X472260Y726251D01*
Y728911D01*
X470440Y730731D01*
G01X478290Y786393D02*
Y743657D01*
X473284Y738651D01*
Y732335D01*
X471680Y730731D01*
X470440D01*
G01X476980Y736594D02*
X479186Y738800D01*
X483291D01*
X485300Y736791D01*
Y732900D01*
X496637Y721562D01*
X503969D01*
X506690Y718841D01*
Y699814D01*
X508100Y698404D01*
Y696746D01*
X507070Y695716D01*
Y693768D01*
X508471Y692367D01*
Y690606D01*
X507183Y689318D01*
X501342D01*
X496577Y684553D01*
G01X476160Y734205D02*
X477117D01*
X479319Y736407D01*
X480862D01*
X484100Y733169D01*
Y732401D01*
X496139Y720362D01*
X497775D01*
X505490Y712647D01*
Y698177D01*
X506092Y697575D01*
G01X469360Y780411D02*
X468260Y779311D01*
Y744051D01*
X466440Y742231D01*
G01X470440D02*
Y770637D01*
X475620Y775817D01*
Y779095D01*
G01X464628Y807872D02*
Y790708D01*
X466070Y789266D01*
Y774997D01*
G01X468565Y807872D02*
Y781694D01*
X468570D01*
X469360Y780904D01*
Y780411D01*
G01X475620Y779095D02*
Y786282D01*
X472502Y789400D01*
Y807872D01*
G01X478290Y786393D02*
Y793843D01*
X476439Y795694D01*
Y807872D01*
G01X480790Y139364D02*
X497300D01*
X500215Y136449D01*
G01X494644Y157761D02*
Y155976D01*
X490815Y152147D01*
X487857D01*
G01X488570Y147486D02*
X490379Y145677D01*
X499149D01*
X500526Y144300D01*
X512400D01*
X513900Y145800D01*
X518900D01*
X525134Y139566D01*
Y135466D01*
X531600Y129000D01*
X563300D01*
X576035Y116265D01*
Y89635D01*
X568100Y81700D01*
Y28000D01*
X576900Y19200D01*
X621100D01*
X632200Y30300D01*
Y49600D01*
X638500Y55900D01*
X667759D01*
X669987Y53672D01*
G01X480790Y147364D02*
X488448D01*
X488570Y147486D01*
G01X505124Y142186D02*
X492472D01*
X492424Y142234D01*
G01X480790Y143364D02*
X490130D01*
X491260Y142234D01*
X492424D01*
G01X505124Y150686D02*
X499959D01*
X498140Y148867D01*
X494467D01*
G01D02*
X493187Y150147D01*
X485960D01*
X484743Y151364D01*
X480790D01*
G01X494644Y162261D02*
X492884D01*
X492059Y163086D01*
X490130D01*
G01X482275Y168113D02*
X487670D01*
X489040Y169483D01*
G01X482275Y164113D02*
X486598D01*
X488954Y166469D01*
X495610D01*
X496360Y167219D01*
Y167221D01*
G01X482500Y184169D02*
X489199D01*
X507295Y166073D01*
Y157004D01*
X513699Y150600D01*
X520200D01*
X530696Y140104D01*
Y139146D01*
G01X487080Y180918D02*
Y180914D01*
X490794D01*
X505416Y166292D01*
Y157468D01*
X513284Y149600D01*
X519100D01*
X529041Y139659D01*
Y136801D01*
X530696Y135146D01*
G01Y143146D02*
X529454D01*
X521000Y151600D01*
X518849D01*
X518829Y151620D01*
X514231D01*
X508611Y157240D01*
Y166717D01*
X489230Y186098D01*
X480550D01*
X480220Y185768D01*
Y185766D01*
G01X482275Y172113D02*
X493428D01*
X493670Y171871D01*
G01X482275Y176113D02*
X488156D01*
X488850Y175419D01*
G01X504941Y227859D02*
X488600Y211518D01*
Y206500D01*
X490600Y204500D01*
X496000D01*
X498700Y201800D01*
X504550D01*
G01X490040Y622140D02*
Y626986D01*
X487530Y629496D01*
Y640096D01*
X489347Y641913D01*
X491190D01*
X492781Y643504D01*
X497169D01*
X498760Y641913D01*
X502321D01*
X506390Y637844D01*
Y637629D01*
G01X492770Y665090D02*
Y660625D01*
X496745Y656650D01*
X500086D01*
X509898Y646838D01*
X511396D01*
X517460Y640774D01*
Y639892D01*
X523940Y633412D01*
Y625981D01*
X526300Y623621D01*
G01X484700Y660355D02*
X488260Y656795D01*
Y652161D01*
X491605Y648816D01*
X493838D01*
X498580Y644073D01*
X501940D01*
G01X485465Y682656D02*
X483937D01*
X481227Y685366D01*
G01X485465Y686656D02*
Y687033D01*
X481227Y691271D01*
Y691366D01*
G01X485465Y690656D02*
X485154D01*
X481227Y694583D01*
Y696366D01*
G01X497350Y699767D02*
X494165Y696582D01*
X486615D01*
X485465Y697732D01*
Y698656D01*
G01X495560Y694781D02*
X494165D01*
X492201Y692817D01*
X487304D01*
X485465Y694656D01*
G01X506409Y691373D02*
Y692577D01*
X504300Y694686D01*
Y696535D01*
X504090Y696745D01*
Y698404D01*
X504290Y698604D01*
Y712149D01*
X497277Y719162D01*
X493813D01*
X481960Y731015D01*
Y732814D01*
X480620Y734154D01*
Y734244D01*
G01X501890Y746663D02*
Y744447D01*
X493590Y736147D01*
Y735035D01*
X493150Y734595D01*
Y728574D01*
X498773Y722951D01*
X504278D01*
X508908Y718321D01*
Y705411D01*
X509671Y704648D01*
Y688326D01*
X507081Y685736D01*
X505274D01*
X503940Y684402D01*
Y680938D01*
X499910Y676903D01*
Y674799D01*
X501400Y673309D01*
Y665821D01*
X503412Y663809D01*
X514674D01*
X514710Y663845D01*
X516370D01*
X523126Y657089D01*
X527317D01*
X530908Y653498D01*
X536998D01*
X540219Y650277D01*
X541882D01*
G01X498080Y733252D02*
Y737842D01*
X505940Y745702D01*
Y757173D01*
X488250Y774863D01*
Y786657D01*
G01X484313Y807872D02*
Y780233D01*
X483870Y779790D01*
Y773070D01*
X501890Y755050D01*
Y746663D01*
G01X492187Y807872D02*
Y783261D01*
X494514Y780934D01*
Y775675D01*
X510099Y760090D01*
Y749626D01*
X512610Y747115D01*
G01X488250Y786657D02*
Y807872D01*
G01X512465Y120512D02*
Y124514D01*
X509710Y127269D01*
G01X508274Y137686D02*
X512282D01*
X512288Y137692D01*
G01X505124Y137686D02*
X501452D01*
X500215Y136449D01*
G01X508274Y146686D02*
X511786D01*
X512600Y147500D01*
G01X508274Y150686D02*
Y146686D01*
G01Y142186D02*
X512305D01*
X512308Y142189D01*
G01X510000Y232425D02*
Y231500D01*
X507500Y229000D01*
Y213711D01*
G01X504941Y221289D02*
Y227859D01*
G01X502000Y232425D02*
X506000D01*
G01D02*
Y228918D01*
X504941Y227859D01*
G01X510000Y232425D02*
X510925D01*
X512500Y234000D01*
Y236500D01*
X514000Y238000D01*
X526500D01*
X528100Y236400D01*
Y230599D01*
X528105Y230594D01*
G01X506000Y235575D02*
X507575Y234000D01*
X508425D01*
X510000Y232425D01*
G01X498563Y460516D02*
Y469567D01*
X498119Y470011D01*
G01X502390Y628829D02*
X508032D01*
X510070Y626791D01*
X512533D01*
G01X498390Y637629D02*
Y630030D01*
X496650Y628290D01*
Y626875D01*
X497896Y625629D01*
X504680D01*
X504716Y625665D01*
X508480D01*
X512524Y621621D01*
X527129D01*
X532479Y626971D01*
Y633588D01*
G01X506390Y637629D02*
Y634496D01*
X510945Y629941D01*
X512533D01*
G01X509917Y655007D02*
Y655275D01*
X511683Y657041D01*
X515864D01*
X517328Y655577D01*
Y655529D01*
G01X509884Y670488D02*
X504456D01*
X504114Y670830D01*
G01X508143Y674660D02*
X502878D01*
X501914Y675624D01*
G01X508578Y666397D02*
X504829D01*
X504241Y665809D01*
G01X505580Y679105D02*
X509544D01*
X509632Y679193D01*
X509823Y679002D01*
G01X514940Y741231D02*
Y757634D01*
X496950Y775624D01*
Y780685D01*
X497880Y781615D01*
Y785893D01*
G01X509000Y775415D02*
X505710Y778705D01*
Y787363D01*
X507935Y789588D01*
Y807872D01*
G01X523940Y741231D02*
Y760475D01*
X509000Y775415D01*
G01X519440Y741231D02*
Y760965D01*
X502480Y777925D01*
Y782382D01*
G01X503998Y807872D02*
Y792947D01*
X503068Y792017D01*
Y782970D01*
X502480Y782382D01*
G01X496124Y807872D02*
Y794856D01*
X497840Y793140D01*
Y785933D01*
X497880Y785893D01*
G01X514510Y133093D02*
X522507D01*
X529500Y126100D01*
X561900D01*
X573200Y114800D01*
Y94129D01*
X565500Y86429D01*
Y26800D01*
X576400Y15900D01*
X622700D01*
X635300Y28500D01*
Y41800D01*
X644800Y51300D01*
X657525D01*
X659947Y53722D01*
G01X512288Y137692D02*
Y135315D01*
X514510Y133093D01*
G01X522448Y137674D02*
Y136052D01*
X531000Y127500D01*
X562800D01*
X574600Y115700D01*
Y90900D01*
X566800Y83100D01*
Y27400D01*
X576700Y17500D01*
X621900D01*
X633700Y29300D01*
Y47592D01*
X639957Y53849D01*
G01X512308Y142189D02*
X512389D01*
X514600Y144400D01*
X518400D01*
X521684Y141116D01*
Y138438D01*
X522448Y137674D01*
G01X577371Y38803D02*
Y41271D01*
X588600Y52500D01*
X588610D01*
X602610Y66500D01*
Y85953D01*
X607543Y90886D01*
Y153100D01*
X587111Y173532D01*
X574938D01*
X573578Y172172D01*
X554805D01*
X553395Y173582D01*
Y175001D01*
X552224Y176172D01*
X545233D01*
X543799Y174738D01*
X530338D01*
X520300Y164700D01*
X516200D01*
X513775Y162275D01*
Y155423D01*
X515401Y153797D01*
G01X518551D02*
X522403D01*
X523100Y153100D01*
G01D02*
X527007Y149193D01*
X531799D01*
X533846Y147146D01*
G01X512600Y147500D02*
X519100D01*
X527200Y139400D01*
Y135400D01*
X532004Y130596D01*
X564304D01*
X581000Y113900D01*
Y90300D01*
X569400Y78700D01*
Y28600D01*
X577300Y20700D01*
X619600D01*
X630500Y31600D01*
Y50000D01*
X638400Y57900D01*
X671806D01*
X675927Y53779D01*
G01X597371Y38803D02*
X593368Y34800D01*
X575600D01*
X573300Y37100D01*
Y47100D01*
X580900Y54700D01*
X588300D01*
X601310Y67710D01*
Y86957D01*
X606243Y91890D01*
Y117668D01*
X602520Y121391D01*
Y156284D01*
X586572Y172232D01*
X575942D01*
X574582Y170872D01*
X552471D01*
X551337Y172006D01*
X544806D01*
X543374Y173438D01*
X530938D01*
X520800Y163300D01*
X517100D01*
X515375Y161575D01*
Y159940D01*
G01X607371Y38803D02*
X601568Y33000D01*
X575400D01*
X572000Y36400D01*
Y47800D01*
X580200Y56000D01*
X587700D01*
X599674Y67974D01*
Y95712D01*
X603418Y99456D01*
Y117823D01*
X601160Y120081D01*
Y155805D01*
X586033Y170932D01*
X576481D01*
X575121Y169572D01*
X551933D01*
X551847Y169658D01*
X551432Y170072D01*
X544901D01*
X542835Y172138D01*
X531893D01*
X524875Y165120D01*
Y161009D01*
X526046Y159838D01*
X535433D01*
X539010Y163415D01*
X541614D01*
G01X518525Y159940D02*
X522560D01*
X523100Y159400D01*
G01X533846Y155146D02*
X531732Y157260D01*
X526040D01*
X523900Y159400D01*
X523100D01*
G01X523611Y218900D02*
X525800D01*
X526700Y218000D01*
Y212400D01*
X523500Y209200D01*
Y202500D01*
X521100Y200100D01*
Y197500D01*
X522300Y196300D01*
Y191600D01*
X519300Y188600D01*
Y185425D01*
X521400Y183325D01*
G01D02*
Y178264D01*
X521320Y178184D01*
G01Y173675D02*
Y178184D01*
G01X523593Y198171D02*
X523500Y198078D01*
Y190400D01*
X521400Y188300D01*
Y186475D01*
G01X516875Y182600D02*
Y178800D01*
X516175Y178100D01*
X516100D01*
G01X526621Y177079D02*
X523500Y180200D01*
Y184575D01*
X525400Y186475D01*
G01X523593Y198171D02*
X524800Y199378D01*
Y208300D01*
X528100Y211600D01*
Y220300D01*
X529259Y221459D01*
X531189D01*
G01X517670Y247527D02*
X520383Y250240D01*
Y253249D01*
X515474Y258158D01*
Y259152D01*
X516178Y259856D01*
X517172D01*
X522081Y254947D01*
X523075D01*
X523779Y255651D01*
Y256645D01*
X518870Y261554D01*
Y262548D01*
X519574Y263252D01*
X520568D01*
X525477Y258343D01*
X526471D01*
X527175Y259047D01*
Y260041D01*
X522266Y264950D01*
Y265944D01*
X522970Y266648D01*
X523964D01*
X528873Y261739D01*
X529867D01*
X532794Y264666D01*
Y282068D01*
G01X566876Y289890D02*
X565188Y288202D01*
X557910D01*
X557041Y287333D01*
X541088D01*
X536713Y282958D01*
Y262294D01*
X533772Y259353D01*
Y253162D01*
X533069Y252459D01*
X525721D01*
X525018Y251756D01*
Y250762D01*
X525721Y250059D01*
X533069D01*
X533772Y249356D01*
Y248362D01*
X533069Y247659D01*
X525721D01*
X525018Y246956D01*
Y245962D01*
X525721Y245259D01*
X533069D01*
X533772Y244556D01*
Y228268D01*
X534208Y227832D01*
G01X531527Y483627D02*
Y483623D01*
X528658D01*
X528258Y484023D01*
X525638D01*
G01X512533Y626791D02*
X514397D01*
X515768Y625420D01*
X520108D01*
X520370Y625158D01*
G01X524782Y638398D02*
X527278D01*
X528699Y639819D01*
X531543D01*
X532479Y638883D01*
Y633588D01*
G01X524399Y645214D02*
Y643631D01*
X524780Y643250D01*
Y638398D01*
X524782D01*
G01X513067Y655007D02*
Y652367D01*
X515438Y649996D01*
G01X513034Y670488D02*
X517420D01*
X517806Y670102D01*
G01X511293Y674660D02*
X515127D01*
X515870Y673917D01*
X517222D01*
G01X555508Y645268D02*
Y653591D01*
X553287Y655812D01*
X549706D01*
X546498Y659020D01*
X529070D01*
X526560Y661530D01*
X524395D01*
X522080Y663845D01*
Y695643D01*
X512700Y705023D01*
Y721941D01*
X512548Y722093D01*
G01X559333Y643123D02*
Y645229D01*
X557320Y647242D01*
Y653477D01*
X553785Y657012D01*
X550962D01*
X544954Y663020D01*
X528340D01*
X528050Y662730D01*
X525601D01*
X523280Y665051D01*
Y697011D01*
X514620Y705671D01*
Y713193D01*
G01X548493Y643163D02*
X551738Y646408D01*
Y648336D01*
X542576Y657498D01*
X528872D01*
X526040Y660330D01*
X523894D01*
X520880Y663344D01*
Y695145D01*
X510608Y705417D01*
Y717448D01*
G01X511728Y666397D02*
X518179D01*
X518800Y665776D01*
G01X519440Y726581D02*
Y725894D01*
X520294Y725040D01*
Y702567D01*
X524480Y698381D01*
Y666680D01*
X526430Y664730D01*
G01X512973Y679002D02*
X517627D01*
X518382Y678247D01*
G01X519440Y729731D02*
Y732953D01*
X521970Y735483D01*
Y738701D01*
X519440Y741231D01*
G01X528440Y729731D02*
Y732621D01*
X526134Y734927D01*
Y738925D01*
X528440Y741231D01*
G01X521800Y732667D02*
Y732806D01*
X522870Y733876D01*
Y733926D01*
X523890Y734946D01*
X523940D01*
Y738081D01*
G01Y729731D02*
Y730527D01*
X521800Y732667D01*
G01X514940Y738081D02*
Y733651D01*
X514420Y733131D01*
G01D02*
X514940Y732611D01*
Y729731D01*
G01X528440Y741231D02*
Y760343D01*
X514430Y774353D01*
Y785721D01*
G01X519560Y779689D02*
X521073Y778176D01*
Y775021D01*
X530060Y766034D01*
Y754107D01*
X532940Y751227D01*
Y741231D01*
G01X519560Y779689D02*
X517540Y781709D01*
Y793481D01*
X515809Y795212D01*
Y807872D01*
G01X514430Y785721D02*
X511872Y788279D01*
Y807872D01*
G01X537440Y741231D02*
Y750588D01*
X531940Y756088D01*
Y771957D01*
X523683Y780214D01*
Y786110D01*
G01D02*
Y807872D01*
G01X533846Y139146D02*
X541434Y139235D01*
X541614Y139415D01*
G01D02*
Y139921D01*
X543224Y141531D01*
X549170D01*
X552173Y138528D01*
G01X550599Y132596D02*
X542919D01*
X541614Y133901D01*
Y135415D01*
G01D02*
X538019D01*
X537750Y135146D01*
X533846D01*
G01Y151146D02*
X537920D01*
X538189Y151415D01*
X538655D01*
G01D02*
X541614D01*
G01X533846Y147146D02*
X537462D01*
X537731Y147415D01*
X541614D01*
G01X533846Y155146D02*
X537204D01*
X537473Y155415D01*
X541614D01*
G01X551464Y143862D02*
X550165Y145161D01*
X542693D01*
X541614Y144082D01*
Y143415D01*
G01X533846Y143146D02*
X541345D01*
X541614Y143415D01*
G01X617371Y38803D02*
X612600Y34032D01*
Y26700D01*
X608703Y22803D01*
X577197D01*
X570700Y29300D01*
Y48400D01*
X579600Y57300D01*
X587100D01*
X598300Y68500D01*
Y79400D01*
X598374Y79474D01*
Y96857D01*
X602118Y100601D01*
Y116592D01*
X599740Y118970D01*
Y145721D01*
X586748Y158713D01*
Y166505D01*
X583621Y169632D01*
X577020D01*
X575263Y167875D01*
X553236D01*
X551433Y166072D01*
X549280D01*
X546580Y168772D01*
X544360D01*
X542294Y170838D01*
X532432D01*
X530559Y168965D01*
Y167329D01*
G01X551604Y162541D02*
X549289D01*
X544470Y167360D01*
X543857D01*
X542379Y168838D01*
X538968D01*
G01X533846Y163146D02*
Y164545D01*
X533709Y164682D01*
Y167329D01*
G01X538968Y168838D02*
Y168829D01*
X537468Y167329D01*
X533709D01*
G01X542002Y186426D02*
X541995Y186433D01*
X537928D01*
G01X542002Y186426D02*
Y193998D01*
X539500Y196500D01*
G01X536232Y192086D02*
X533768Y189622D01*
Y186419D01*
G01X529272Y186459D02*
X533728D01*
X533768Y186419D01*
G01X574071Y606204D02*
X573621Y605754D01*
X565715D01*
X564830Y606639D01*
X543683D01*
X540540Y603496D01*
Y601008D01*
G01X538828Y602945D02*
Y603199D01*
X543268Y607639D01*
X568815D01*
X568930Y607754D01*
G01X528782Y629598D02*
Y635357D01*
X530779Y637354D01*
G01X530012Y708618D02*
X537603Y701027D01*
Y674322D01*
X553713Y658212D01*
X556153D01*
X575830Y638535D01*
X614618D01*
X615510Y639427D01*
X620510D01*
G01X535062Y708679D02*
X539751Y703990D01*
Y680551D01*
X543684Y676618D01*
Y670321D01*
X554554Y659451D01*
X556613D01*
X560079Y655985D01*
X563971D01*
X568092Y651864D01*
X572550D01*
X584679Y639735D01*
X608952D01*
X610439Y641222D01*
X623290D01*
G01X600980Y641533D02*
X584718D01*
X570038Y656213D01*
X566085D01*
X564760Y657538D01*
X560766D01*
X557639Y660665D01*
X555038D01*
X545481Y670222D01*
Y677862D01*
X541281Y682062D01*
Y704348D01*
X537503Y708126D01*
Y710088D01*
G01X528440Y726581D02*
Y726565D01*
X526600Y724725D01*
Y689392D01*
X529111Y686881D01*
Y685223D01*
X526994Y683106D01*
Y679511D01*
X526600Y679117D01*
G01X537440Y726581D02*
Y724028D01*
X539577Y721891D01*
G01X528388Y722903D02*
X529591D01*
X535513Y716981D01*
X539589D01*
X549166Y707404D01*
Y672917D01*
X551283Y670800D01*
G01X537440Y729731D02*
Y733074D01*
X535438Y735076D01*
Y739229D01*
X537440Y741231D01*
G01X541940Y729731D02*
Y733125D01*
X539938Y735127D01*
Y739229D01*
X541940Y741231D01*
G01Y726581D02*
Y723814D01*
X544934Y720820D01*
G01X532940Y729731D02*
Y731231D01*
X531029Y733142D01*
G01X532940Y738081D02*
X532851D01*
X531029Y736259D01*
Y733142D01*
G01X541940Y741231D02*
Y750729D01*
X534950Y757719D01*
Y772203D01*
X527620Y779533D01*
Y781318D01*
G01X546440Y741231D02*
Y751797D01*
X537463Y760774D01*
Y771565D01*
X531557Y777471D01*
Y786392D01*
G01X537320Y786298D02*
Y777249D01*
X541400Y773169D01*
Y762405D01*
X550940Y752865D01*
Y741231D01*
G01X527620Y807872D02*
Y781318D01*
G01X531557Y807872D02*
Y786392D01*
G01X537320Y786298D02*
Y794841D01*
X535500Y796661D01*
X535494D01*
Y807872D01*
G01X568933Y140404D02*
X567950Y139421D01*
X553066D01*
X552173Y138528D01*
G01X568933Y136404D02*
X560159D01*
X556351Y132596D01*
X550599D01*
G01X564076Y145372D02*
X556528D01*
X553100Y148800D01*
X550393D01*
X547778Y151415D01*
X544764D01*
G01X556699Y149274D02*
Y150951D01*
X550370Y157280D01*
G01X544764Y159415D02*
Y155415D01*
G01D02*
X546817D01*
X550550Y151682D01*
G01X554754Y162541D02*
Y157559D01*
X558059Y154254D01*
G01X544764Y147415D02*
X549656D01*
X550371Y146700D01*
X552965D01*
X557154Y142511D01*
X558348D01*
G01X568933Y144404D02*
X564980Y140451D01*
X555767D01*
X552356Y143862D01*
X551464D01*
G01X550370Y157280D02*
Y157461D01*
G01X544764Y163415D02*
Y162886D01*
X550370Y157280D01*
G01X546000Y192000D02*
Y186426D01*
G01X594067Y265168D02*
X591848Y267387D01*
Y272695D01*
X594179Y275026D01*
Y282588D01*
X598409Y286818D01*
Y308527D01*
X590209Y316727D01*
X583953D01*
X553580Y347100D01*
Y386757D01*
X552090Y388247D01*
Y388953D01*
G01X555508Y642118D02*
Y640613D01*
X558281Y637840D01*
G01X551643Y643163D02*
Y637813D01*
X551030Y637200D01*
G01X545032Y650277D02*
Y652213D01*
X542424Y654821D01*
G01X545062Y708679D02*
Y706474D01*
X543284Y704696D01*
Y697293D01*
X547006Y693571D01*
Y670677D01*
X554674Y663009D01*
X562144D01*
X562932Y662221D01*
X566976D01*
X567626Y661571D01*
X575271D01*
X575880Y662180D01*
X578178D01*
X586482Y653876D01*
X592389D01*
X593860Y655347D01*
X596354D01*
X596470Y655231D01*
G01X550940Y726581D02*
Y724695D01*
X553360Y722275D01*
Y721704D01*
X556973Y718091D01*
X560544D01*
G01X555440Y726581D02*
Y722429D01*
X555527Y722342D01*
X555551D01*
G01X546440Y729731D02*
Y732625D01*
X544438Y734627D01*
Y739229D01*
X546440Y741231D01*
G01X550940D02*
X549140Y739431D01*
Y734425D01*
X550940Y732625D01*
Y729731D01*
G01X555440Y741531D02*
X553198Y739289D01*
Y733643D01*
X555440Y731401D01*
Y729731D01*
G01X546440Y726581D02*
X547063D01*
X549049Y724595D01*
Y724412D01*
G01X543075Y775577D02*
X545629Y773023D01*
Y762771D01*
X555280Y753120D01*
Y743293D01*
X555440Y743133D01*
Y741531D01*
G01X559940Y741731D02*
Y754733D01*
X548880Y765793D01*
Y776946D01*
X549350Y777416D01*
G01X564440Y741731D02*
Y758672D01*
X553503Y769609D01*
Y774301D01*
X552830Y774974D01*
Y785015D01*
G01X543075Y775577D02*
X542210Y776442D01*
Y786142D01*
X543368Y787300D01*
Y807872D01*
G01X547305D02*
Y779461D01*
X549350Y777416D01*
G01X551242Y807872D02*
Y786603D01*
X552830Y785015D01*
G01X558360Y775757D02*
Y780215D01*
X556879Y781696D01*
Y792181D01*
X555179Y793881D01*
Y807872D01*
G01X568933Y152404D02*
Y151907D01*
X564076Y147050D01*
Y145372D01*
G01X568933Y156404D02*
X564721D01*
X562571Y154254D01*
X558059D01*
G01X568933Y148404D02*
Y147368D01*
X564076Y142511D01*
X558348D01*
G01X563410Y165289D02*
X578792D01*
X581897Y162184D01*
Y159900D01*
X595438Y146359D01*
Y138130D01*
G01X563274Y162169D02*
X570255D01*
X570710Y162624D01*
X575727D01*
X579247Y159104D01*
X580259D01*
X592938Y146425D01*
Y140689D01*
G01X568933Y160404D02*
X565990D01*
X564601Y159015D01*
X562195D01*
G01X562483Y643123D02*
Y640869D01*
X565647Y637705D01*
G01X571440Y674199D02*
X578256D01*
X580815Y676758D01*
X594440D01*
G01X560915Y669156D02*
X561880D01*
X564364Y671640D01*
X571440D01*
G01D02*
X579445D01*
X581177Y669908D01*
Y667403D01*
X578959Y665185D01*
X573108D01*
X571494Y663571D01*
G01X560915Y665156D02*
X564626D01*
X565168Y664614D01*
G01X571440Y669081D02*
X569635D01*
X565168Y664614D01*
G01X560915Y673156D02*
Y673662D01*
X563441Y676188D01*
Y676872D01*
G01X560915Y681156D02*
X562605D01*
X563586Y682137D01*
G01X571440Y681876D02*
X567094D01*
X566833Y682137D01*
X563586D01*
G01X571440Y689554D02*
X568069D01*
X565339Y692284D01*
X563577D01*
G01X571440Y676758D02*
X567049D01*
X566935Y676872D01*
X563441D01*
G01X560915Y677156D02*
X563373Y679614D01*
X565168D01*
G01X571440Y679317D02*
X567916D01*
X567619Y679614D01*
X565168D01*
G01X560915Y685156D02*
X562667Y686908D01*
X563393D01*
G01X571440Y684436D02*
X568635D01*
X566163Y686908D01*
X563393D01*
G01X560915Y689156D02*
X561926D01*
X562384Y689614D01*
X565168D01*
G01X571440Y686995D02*
X567787D01*
X565168Y689614D01*
G01X571440Y692113D02*
X567669D01*
X565168Y694614D01*
G01X560915Y697156D02*
X562626D01*
X565168Y694614D01*
G01X560915Y693156D02*
X562705D01*
X563577Y692284D01*
G01X560915Y701156D02*
X563576D01*
X565118Y699614D01*
X565168D01*
G01X571440Y694672D02*
X568956D01*
X567164Y696464D01*
Y697638D01*
X565188Y699614D01*
X565168D01*
G01X564440Y726581D02*
Y725946D01*
X569138Y721248D01*
X569604D01*
G01X564440Y729731D02*
Y732573D01*
X564240Y732773D01*
X564236D01*
X562128Y734881D01*
Y739419D01*
X564440Y741731D01*
G01X573440Y729731D02*
Y732560D01*
X575640Y734760D01*
Y739531D01*
X573440Y741731D01*
G01X579220Y720776D02*
X578346Y721650D01*
X577502D01*
X575415Y723737D01*
Y724606D01*
X573440Y726581D01*
G01X568940Y729731D02*
Y730253D01*
X571232Y732545D01*
G01X568940Y738581D02*
X569547D01*
X571232Y736896D01*
Y732545D01*
G01X559940Y729731D02*
Y732091D01*
X557978Y734053D01*
G01X559940Y738581D02*
X558460Y737101D01*
Y734533D01*
X557980Y734053D01*
X557978D01*
G01X568940Y741731D02*
Y759740D01*
X558360Y770320D01*
Y775757D01*
G01X563053Y785792D02*
X563350Y785495D01*
Y777340D01*
X565885Y774805D01*
Y769496D01*
X573440Y761941D01*
Y741731D01*
G01X570928Y807872D02*
Y785433D01*
X571230Y785131D01*
G01X587940Y741231D02*
Y758579D01*
X576200Y770319D01*
Y780161D01*
X571230Y785131D01*
G01X566990Y807872D02*
Y778750D01*
X567210Y778530D01*
G01X577940Y741731D02*
Y766519D01*
X568668Y775791D01*
Y777072D01*
X567210Y778530D01*
G01X563053Y807872D02*
Y785792D01*
G01X594440Y692113D02*
X592070D01*
X591803Y692380D01*
X586122D01*
X579151Y699351D01*
Y702301D01*
G01D02*
X577589D01*
X576442Y703448D01*
Y705492D01*
G01X594440Y694672D02*
X590766D01*
X583651Y701787D01*
Y702301D01*
G01D02*
X586060Y704710D01*
Y708968D01*
X584312Y710716D01*
G01X588151Y702301D02*
Y699875D01*
X590787Y697239D01*
X594440D01*
G01X587940Y729731D02*
Y732621D01*
X585438Y735123D01*
Y738729D01*
X587940Y741231D01*
G01X577940Y738581D02*
Y737830D01*
X579572Y736198D01*
Y731923D01*
X577940Y730291D01*
Y729731D01*
G01D02*
X579530D01*
X580510Y728751D01*
Y724421D01*
G01X595950Y708997D02*
Y714681D01*
X590080Y720551D01*
Y724989D01*
X588488Y726581D01*
X587940D01*
G01X596940Y741231D02*
Y758924D01*
X583870Y771994D01*
Y779242D01*
X583879Y779251D01*
G01X592440Y741231D02*
Y759646D01*
X581840Y770246D01*
Y777250D01*
X578330Y780760D01*
Y785014D01*
G01X586676Y786016D02*
Y781027D01*
X601440Y766263D01*
Y741231D01*
G01X583880Y779251D02*
X583879D01*
G01D02*
X582739Y780391D01*
Y807872D01*
G01X574864D02*
Y793875D01*
X574870D01*
X576570Y792175D01*
Y786774D01*
X578330Y785014D01*
G01X586676Y807872D02*
Y786016D01*
G01X591279Y656223D02*
X596156Y661100D01*
X601310D01*
X603787Y663577D01*
X616837D01*
X619644Y660770D01*
X623202D01*
G01X594440Y674199D02*
X597119D01*
X600162Y671156D01*
X602332D01*
G01X594440Y671640D02*
X596820D01*
X600035Y668425D01*
X600736D01*
G01X600719Y675156D02*
X604965D01*
G01X594440Y676758D02*
X599117D01*
X600719Y675156D01*
G01X594440Y686995D02*
X597386D01*
X599691Y689300D01*
Y690897D01*
X600690Y691896D01*
G01X604965Y691156D02*
X603838D01*
X603098Y691896D01*
X600690D01*
G01X594440Y681876D02*
X600727D01*
G01X604965Y683156D02*
X602071D01*
X600791Y681876D01*
X600727D01*
G01X594440Y679317D02*
X601859D01*
X602020Y679156D01*
G01D02*
X604965D01*
G01X594440Y689554D02*
X596687D01*
X598590Y691457D01*
Y693613D01*
X600133Y695156D01*
X604965D01*
G01X594440Y684436D02*
X598287D01*
X600727Y686876D01*
G01X604965Y687156D02*
X601007D01*
X600727Y686876D01*
G01X604965Y695156D02*
Y698393D01*
X604220Y699138D01*
Y703774D01*
G01X606940Y716692D02*
Y714760D01*
X607846Y713854D01*
Y711090D01*
X601680Y704924D01*
Y700847D01*
X598412Y697579D01*
X594780D01*
X594440Y697239D01*
G01D02*
Y697231D01*
G01X601440Y726581D02*
Y724237D01*
X603747Y721930D01*
Y713370D01*
X601856Y711479D01*
G01X605940Y726581D02*
Y725062D01*
X604750Y723872D01*
Y714541D01*
X606146Y713145D01*
G01X596940Y726581D02*
X601813Y721708D01*
Y715579D01*
G01X600650Y707835D02*
X598010Y710475D01*
Y717495D01*
X597115Y718390D01*
Y720270D01*
X594640Y722745D01*
Y727501D01*
X594620Y727521D01*
Y728629D01*
X593518Y729731D01*
X592440D01*
G01X601440D02*
Y732621D01*
X599438Y734623D01*
Y739229D01*
X601440Y741231D01*
G01X605940Y729731D02*
Y732621D01*
X603938Y734623D01*
Y739229D01*
X605940Y741231D01*
G01X596940Y729731D02*
Y733260D01*
X595086Y735114D01*
Y739377D01*
X596940Y741231D01*
G01X592440Y738081D02*
X591187D01*
Y732513D01*
X592440Y731260D01*
Y729731D01*
G01X591460Y780096D02*
Y779305D01*
X606574Y764191D01*
Y741871D01*
X605940Y741237D01*
Y741231D01*
G01X602424Y807872D02*
Y778468D01*
G01X614940Y741231D02*
Y762878D01*
X602424Y775394D01*
Y778468D01*
G01X590613Y807872D02*
Y780943D01*
X591460Y780096D01*
G01X610440Y741231D02*
Y764456D01*
X600100Y774796D01*
Y782694D01*
X596590Y786204D01*
G01D02*
Y793540D01*
X594550Y795580D01*
Y807872D01*
G01X627202Y651970D02*
X623398Y655774D01*
X617683D01*
X615700Y657757D01*
G01X650339Y663568D02*
X652280Y661627D01*
Y657646D01*
X642507Y647873D01*
X620220D01*
X619202Y648891D01*
Y651970D01*
G01X627463Y678159D02*
X623639D01*
X621227Y675747D01*
X616629D01*
X616031Y675149D01*
G01X609345Y669937D02*
X610510D01*
X610990Y670417D01*
Y670424D01*
X614204Y673638D01*
X614520D01*
X616031Y675149D01*
G01X609345Y666787D02*
X611824D01*
X613899Y668862D01*
X618537D01*
X619183Y668216D01*
X625703D01*
X626340Y668853D01*
G01X615510Y692781D02*
X616834D01*
X620026Y689589D01*
X623220D01*
G01X627463Y680718D02*
X622600D01*
X620203Y678321D01*
X620180D01*
G01X617235Y682716D02*
Y679122D01*
X618036Y678321D01*
X620180D01*
G01X609840Y713617D02*
X610776Y712681D01*
X612540D01*
X613830Y711391D01*
Y709573D01*
X617094Y706309D01*
X627463D01*
G01X613086Y697395D02*
Y693845D01*
X614150Y692781D01*
X615510D01*
G01X622290Y708516D02*
X620149D01*
X617798Y710867D01*
X617697D01*
X611730Y716834D01*
Y721782D01*
X614940Y724992D01*
Y726581D01*
G01X619440D02*
Y724592D01*
X618290Y723442D01*
Y719534D01*
X616419Y717663D01*
X613730D01*
G01X610440Y726581D02*
X606940Y723081D01*
Y716692D01*
G01X623957Y714942D02*
X623100D01*
X622340Y715702D01*
X619530D01*
X618270Y714442D01*
Y713344D01*
G01X627463Y708868D02*
X624513D01*
X621958Y711423D01*
X620191D01*
X618270Y713344D01*
G01X614940Y729731D02*
Y732353D01*
X617140Y734553D01*
Y739031D01*
X614940Y741231D01*
G01X619440Y729731D02*
Y730800D01*
X621590Y732950D01*
Y739411D01*
X620220Y740781D01*
X619890D01*
X619440Y741231D01*
G01X610440Y729731D02*
Y734873D01*
X612438Y736871D01*
Y739233D01*
X610440Y741231D01*
G01X619440D02*
X618000Y742671D01*
Y766588D01*
X606361Y778227D01*
Y785390D01*
G01X624010Y746351D02*
Y764233D01*
X615560Y772683D01*
Y785603D01*
X612535Y788628D01*
Y793449D01*
X614235Y795149D01*
Y807872D01*
G01X606361Y785390D02*
Y807872D01*
G01X639200Y170100D02*
X642300Y173200D01*
Y237800D01*
X637000Y243100D01*
Y243000D01*
X635000Y245000D01*
Y265400D01*
G01X634212Y281670D02*
X635078Y282536D01*
X646010D01*
X648530Y285056D01*
X661643D01*
X677720Y301133D01*
Y348303D01*
X679430Y350013D01*
G01X646171Y364676D02*
X645161Y363666D01*
X644167D01*
X639810Y368023D01*
X638816D01*
X638112Y367319D01*
Y366325D01*
X642469Y361968D01*
Y360974D01*
X641765Y360270D01*
X640771D01*
X636414Y364627D01*
X635420D01*
X634716Y363923D01*
Y362929D01*
X644988Y352657D01*
Y351663D01*
X644284Y350959D01*
X643290D01*
X633018Y361231D01*
X632024D01*
X631320Y360527D01*
Y359533D01*
X637974Y352879D01*
Y351885D01*
X637270Y351181D01*
X636276D01*
X629622Y357835D01*
X628628D01*
X627924Y357131D01*
Y356137D01*
X637337Y346724D01*
Y345730D01*
X636633Y345026D01*
X635639D01*
X626226Y354439D01*
X625232D01*
X624528Y353735D01*
Y352741D01*
X628885Y348384D01*
Y345562D01*
X628141Y344818D01*
G01X623202Y660770D02*
Y664092D01*
X625342Y666232D01*
X634633D01*
X635638Y665227D01*
Y659206D01*
X634238Y657806D01*
Y650847D01*
X635535Y649550D01*
X640504D01*
X642410Y651456D01*
Y653865D01*
X648963Y660418D01*
X650339D01*
G01X627202Y651970D02*
X627330Y652098D01*
Y659363D01*
X630404Y662437D01*
X632938D01*
G01X627463Y675600D02*
Y669976D01*
X626340Y668853D01*
G01X627463Y683277D02*
X631577D01*
X639340Y691040D01*
Y717828D01*
X640570Y719058D01*
Y724114D01*
X643400Y726944D01*
Y729179D01*
X647900Y733679D01*
Y734100D01*
X650500Y736700D01*
Y753277D01*
X652540Y755317D01*
Y768382D01*
X650400Y770522D01*
G01X645400Y734600D02*
X644561Y733761D01*
Y732038D01*
X642200Y729677D01*
Y727442D01*
X639370Y724612D01*
Y719556D01*
X638140Y718326D01*
Y691735D01*
X632241Y685836D01*
X627463D01*
G01Y688395D02*
X623706D01*
X623220Y688881D01*
Y689589D01*
G01X627463Y693514D02*
X630839D01*
X631720Y692633D01*
Y691634D01*
X631040Y690954D01*
X627463D01*
G01D02*
X623708D01*
X623220Y690466D01*
Y689589D01*
G01X627463Y703750D02*
X631224D01*
X633170Y705696D01*
Y716148D01*
X632530Y716788D01*
G01X627463Y701191D02*
X632920D01*
X634530Y702801D01*
Y719643D01*
X631970Y722203D01*
Y723862D01*
X633141Y725033D01*
X634697D01*
X638170Y728506D01*
Y731753D01*
X640600Y734183D01*
Y736772D01*
X641628Y737800D01*
Y749042D01*
X640956Y749714D01*
Y750643D01*
G01X627463Y696073D02*
X633164D01*
X636940Y699849D01*
Y718824D01*
X638170Y720054D01*
Y725110D01*
X641000Y727940D01*
Y731000D01*
X643000Y733000D01*
Y735670D01*
X644230Y736900D01*
Y766757D01*
X650234Y772761D01*
X656970D01*
G01X627463Y698632D02*
X633719D01*
X635740Y700653D01*
Y720559D01*
X636970Y721789D01*
Y725608D01*
X639370Y728008D01*
Y731170D01*
X641800Y733600D01*
Y736270D01*
X643030Y737500D01*
Y768946D01*
X644110Y770026D01*
Y773108D01*
G01X628440Y726572D02*
Y723778D01*
X628160Y723498D01*
Y722343D01*
G01X623957Y718092D02*
X622440D01*
X621864Y717516D01*
X620830D01*
G01X627957Y718092D02*
X630350Y720485D01*
Y724672D01*
X632085Y726407D01*
X633242D01*
X636170Y729335D01*
G01X627957Y714942D02*
X628846D01*
X630692Y716788D01*
X632530D01*
G01X630040Y745114D02*
X630140Y745014D01*
Y738554D01*
X629667Y738081D01*
X628440D01*
G01X636440D02*
X637190Y737331D01*
Y734455D01*
X636165Y733430D01*
X632324D01*
X632010Y733744D01*
X631690D01*
G01X632440Y738081D02*
X632560D01*
X635460Y735181D01*
Y735130D01*
G01X623940Y729731D02*
X623949Y729722D01*
X628440D01*
G01D02*
Y729725D01*
X630333Y731618D01*
X635402D01*
X636214Y732430D01*
X636580D01*
X638190Y734040D01*
Y734406D01*
X638663Y734879D01*
X638890D01*
G01X632300Y749755D02*
Y763500D01*
X627010Y768790D01*
Y784018D01*
X626046Y784982D01*
Y807872D01*
G01X632440Y741231D02*
Y748127D01*
X632300Y748267D01*
Y749755D01*
G01X636440Y741231D02*
Y745345D01*
X636910Y745815D01*
G01X623940Y741231D02*
Y743226D01*
X626010Y745296D01*
Y766893D01*
X622030Y770873D01*
Y786047D01*
G01X628440Y741231D02*
X623940D01*
G01X636910Y745815D02*
Y760761D01*
X632060Y765611D01*
Y770811D01*
X628283Y774588D01*
Y795349D01*
X629983Y797049D01*
Y807872D01*
G01X635662Y772045D02*
Y774667D01*
X636390Y775395D01*
G01D02*
Y788272D01*
X641794Y793676D01*
Y807872D01*
G01X631522Y782841D02*
Y779645D01*
X632030Y779137D01*
G01X632000Y775400D02*
X634500Y777900D01*
Y788400D01*
X637857Y791757D01*
Y807872D01*
G01X622030Y786047D02*
X622031D01*
X622109Y785969D01*
Y807872D01*
G01X642932Y284768D02*
X645163Y286999D01*
X660838D01*
X675060Y301221D01*
Y348299D01*
X679590Y352829D01*
G01X643417Y568945D02*
X646372D01*
X646870Y569443D01*
G01X654141Y571687D02*
X651426D01*
X646870Y576243D01*
G01X636938Y653637D02*
Y684839D01*
X639940Y687841D01*
G01X645752Y660431D02*
Y659368D01*
X640021Y653637D01*
X636938D01*
G01X640330Y684439D02*
X640211Y684320D01*
Y670194D01*
X641622Y668783D01*
X641630D01*
G01X645752Y663581D02*
Y664661D01*
X641630Y668783D01*
G01X640938Y662437D02*
Y668091D01*
X641630Y668783D01*
G01X642999Y685781D02*
X643000D01*
X644550Y684231D01*
Y671463D01*
X647370Y668643D01*
G01X650339Y663568D02*
X650330D01*
X648720Y665178D01*
Y667293D01*
X647370Y668643D01*
G01X650463Y685836D02*
X662691D01*
X669800Y678727D01*
Y673637D01*
X669203Y673040D01*
G01X650463Y675600D02*
X654014D01*
X654776Y674838D01*
Y673534D01*
X653390Y672148D01*
Y669459D01*
X653870Y668979D01*
G01X650463Y688395D02*
X646715D01*
X640740Y694370D01*
Y717248D01*
X641970Y718478D01*
Y723534D01*
X645251Y726815D01*
Y728736D01*
X649910Y733395D01*
X650160D01*
G01X658220Y671797D02*
Y674629D01*
X654690Y678159D01*
X650463D01*
G01Y690954D02*
X646128D01*
X641740Y695342D01*
Y716833D01*
X642970Y718063D01*
Y721649D01*
X643970Y722649D01*
G01X650463Y698632D02*
X647067D01*
X643680Y702019D01*
Y715944D01*
X643740Y716004D01*
G01X650463Y701191D02*
X656505D01*
G01X651227Y720581D02*
Y716674D01*
G01Y720581D02*
X653722Y718086D01*
X654050D01*
G01X651227Y720674D02*
Y720581D01*
G01X648077Y720674D02*
Y719829D01*
X644252Y716004D01*
X643740D01*
G01X648077Y724674D02*
X645995D01*
X643970Y722649D01*
G01X648000Y738925D02*
Y737200D01*
X645400Y734600D01*
G01X649027Y728674D02*
Y729024D01*
X650969Y730966D01*
Y733000D01*
X650574Y733395D01*
X650160D01*
G01X645731Y807872D02*
Y794829D01*
X642910Y792008D01*
Y778286D01*
X641670Y777046D01*
Y751357D01*
X640956Y750643D01*
G01X640010Y778215D02*
X640470Y777755D01*
Y754076D01*
X639920Y753526D01*
G01X646500Y746300D02*
X648000Y744800D01*
Y742075D01*
G01X646370Y759252D02*
Y760176D01*
X646150Y760396D01*
Y765793D01*
X647410Y767053D01*
G01X651690Y778099D02*
X649062Y780727D01*
Y790286D01*
X653605Y794829D01*
Y807872D01*
G01X644110Y773108D02*
Y789271D01*
X649668Y794829D01*
Y807872D01*
G01X652212Y786700D02*
Y784555D01*
X651262Y783605D01*
G01X659933Y513927D02*
Y509976D01*
X672345Y497564D01*
X684697D01*
X684876Y497385D01*
G01X664024Y513414D02*
Y510965D01*
X673517Y501472D01*
X684827D01*
X689017Y497282D01*
G01X664307Y609468D02*
X659555D01*
X658980Y610043D01*
G01X664503Y672129D02*
X668292D01*
X669203Y673040D01*
G01X664503Y668979D02*
X653870D01*
G01X660889Y676595D02*
Y672758D01*
X659928Y671797D01*
X658220D01*
G01X652660Y742510D02*
Y749000D01*
G01X657500Y761500D02*
Y745500D01*
X656660Y744660D01*
Y742510D01*
G01X669320Y783845D02*
X667660Y785505D01*
Y787557D01*
X667653D01*
Y794802D01*
X669353Y796502D01*
Y807872D01*
G01X656970Y772761D02*
X659762Y775553D01*
Y792164D01*
X661479Y793881D01*
Y807872D01*
G01X657482Y782805D02*
Y785567D01*
X657010Y786039D01*
G01D02*
Y791302D01*
X657542Y791834D01*
Y807872D01*
G01X668573Y514155D02*
X676507Y506221D01*
X687749D01*
X691858Y502112D01*
X692955D01*
G01X677227Y807872D02*
Y798020D01*
X675330Y796123D01*
Y779499D01*
X676390Y778439D01*
G01X681164Y807872D02*
Y799150D01*
X679390Y797376D01*
Y785378D01*
X677490Y783478D01*
Y782114D01*
G01X681480Y777388D02*
Y778793D01*
X683330Y780643D01*
Y785253D01*
X681470Y787113D01*
Y795439D01*
X685101Y799070D01*
Y807872D01*
G01X673290D02*
Y785942D01*
X671550Y784202D01*
Y780529D01*
X672500Y779579D01*
G01X696070Y458901D02*
X691070Y463901D01*
Y464058D01*
G01X702797Y464038D02*
X701031Y462272D01*
X700590D01*
G54D46*
X227718Y279888D03*
X230718D03*
X266418Y582683D03*
G54D73*
X711575Y143555D03*
Y195355D03*
Y222361D03*
Y274161D03*
X733975Y143555D03*
Y195355D03*
Y222361D03*
Y274161D03*
G54D19*
X25439Y303260D03*
Y356804D03*
G54D37*
X144058Y370080D03*
Y373230D03*
X148058D03*
Y370080D03*
X147999Y380582D03*
Y383732D03*
X146675Y413599D03*
Y410449D03*
X145531Y526980D03*
Y523830D03*
X152058Y370080D03*
Y373230D03*
X160058Y370080D03*
Y373230D03*
X156058D03*
Y370080D03*
X164058Y373230D03*
Y370080D03*
X156104Y380583D03*
Y383733D03*
X163735Y380294D03*
Y383444D03*
X150709Y506778D03*
Y509928D03*
X149482Y526928D03*
Y523778D03*
X163330Y593010D03*
Y589860D03*
X164163Y625058D03*
Y628208D03*
X179627Y236399D03*
Y239549D03*
X175627Y236399D03*
Y239549D03*
X176058Y370080D03*
Y373230D03*
X168058Y370080D03*
Y373230D03*
X180058D03*
Y370080D03*
X172058Y373230D03*
Y370080D03*
X179801Y380622D03*
Y383772D03*
X171934Y380727D03*
Y383877D03*
X169330Y593010D03*
Y589860D03*
X176263Y593108D03*
Y589958D03*
X176830Y625060D03*
Y628210D03*
X172530Y625060D03*
Y628210D03*
X168430Y624960D03*
Y628110D03*
X179693Y726467D03*
Y729617D03*
X190058Y349894D03*
Y346744D03*
X194185Y349984D03*
Y346834D03*
X184058Y370080D03*
Y373230D03*
X188058D03*
Y370080D03*
X187970Y380726D03*
Y383876D03*
X188886Y553920D03*
Y550770D03*
X183330Y593210D03*
Y590060D03*
X182430Y625260D03*
Y628410D03*
X189940Y714931D03*
Y718081D03*
X185440Y714931D03*
Y718081D03*
X194440Y714898D03*
Y718048D03*
Y739081D03*
Y727581D03*
Y730731D03*
X185440Y727581D03*
Y730731D03*
X189940Y727581D03*
Y730731D03*
Y739081D03*
X185440D03*
X194440Y742231D03*
X189940D03*
X185440D03*
X198653Y281646D03*
X209447Y296692D03*
Y293542D03*
X197847Y297731D03*
X198653Y284796D03*
X209018Y304542D03*
Y307692D03*
X203447Y304742D03*
Y307892D03*
X199447Y304742D03*
Y307892D03*
X197847Y300881D03*
X203520Y327969D03*
Y324819D03*
X196887Y326622D03*
Y323472D03*
X208687Y382271D03*
Y379121D03*
X200687D03*
Y382271D03*
X204687D03*
Y379121D03*
X208209Y486428D03*
Y483278D03*
X207940Y714931D03*
Y718081D03*
X203440Y714898D03*
Y718048D03*
X198940Y714931D03*
Y718081D03*
X207940Y739081D03*
X203440D03*
X198940D03*
X207940Y727581D03*
Y730731D03*
X203440Y727581D03*
Y730731D03*
X198940Y727581D03*
Y730731D03*
X207940Y742231D03*
X203440D03*
X198940D03*
X221421Y233971D03*
Y237121D03*
X217564Y246804D03*
Y249954D03*
X213265Y268130D03*
Y271280D03*
X226995Y269007D03*
Y272157D03*
X222018Y280912D03*
X227718Y277838D03*
X222018Y284062D03*
X215518Y302042D03*
Y305192D03*
X227947Y309542D03*
Y312692D03*
X227712Y302770D03*
Y299620D03*
X212447Y327042D03*
X220447Y323542D03*
Y326692D03*
X212447Y330192D03*
X227767Y336322D03*
Y333172D03*
X220687Y382271D03*
Y379121D03*
X216687Y382271D03*
Y379121D03*
X212687D03*
Y382271D03*
X224687D03*
Y379121D03*
X212709Y486428D03*
Y483278D03*
X216709Y486428D03*
Y483278D03*
X218867Y521088D03*
Y524238D03*
X225940Y727581D03*
Y730731D03*
X212440Y739081D03*
X221440D03*
X216940Y730731D03*
Y727581D03*
X225940Y739081D03*
X216940D03*
X212440Y730731D03*
Y727581D03*
X221440Y730731D03*
Y727581D03*
X212440Y742231D03*
X221440D03*
X225940D03*
X216940D03*
X228745Y265718D03*
Y262568D03*
X237910Y277692D03*
Y274542D03*
X241525Y278042D03*
Y281192D03*
X234060Y274542D03*
Y277692D03*
X230718Y277838D03*
X234789Y286926D03*
Y283776D03*
X235107Y297434D03*
X234789Y290675D03*
Y293825D03*
X228408Y291228D03*
Y294378D03*
X228439Y287413D03*
Y284263D03*
X235018Y313042D03*
X240307Y312400D03*
X231600Y303157D03*
Y306307D03*
X235107Y300584D03*
X235018Y316192D03*
X240307Y315550D03*
X235518Y329412D03*
X243612Y336435D03*
Y333285D03*
X235518Y332562D03*
X238643Y360796D03*
Y363946D03*
X236687Y379121D03*
Y382271D03*
X232687Y377621D03*
Y380771D03*
X235319Y470268D03*
Y467118D03*
X241979Y466578D03*
Y469728D03*
X241909Y478128D03*
Y474978D03*
X228689Y494181D03*
Y491031D03*
X240509Y578028D03*
Y574878D03*
X236209Y578028D03*
Y574878D03*
X231809Y578028D03*
Y574878D03*
X239440Y739081D03*
X230440D03*
X234940Y727581D03*
Y730731D03*
X239440D03*
Y727581D03*
X230440Y730731D03*
Y727581D03*
X234940Y739081D03*
X239440Y742231D03*
X230440D03*
X234940D03*
X258263Y245896D03*
Y249046D03*
X252399Y262158D03*
Y265308D03*
X244634Y266202D03*
Y263052D03*
X246947Y278042D03*
Y281192D03*
X248625Y274017D03*
Y270867D03*
X244480Y273876D03*
Y270726D03*
X252261Y272285D03*
Y269135D03*
X256097Y292632D03*
Y289482D03*
X247018Y284912D03*
Y288062D03*
X248250Y310104D03*
Y313254D03*
X252250Y310104D03*
Y313254D03*
X244359Y312651D03*
X256218Y318562D03*
Y315412D03*
X251231Y321857D03*
Y325007D03*
X244359Y315801D03*
X248690Y388933D03*
Y392083D03*
X248687Y379121D03*
Y382271D03*
X252687Y379121D03*
Y382271D03*
X258687Y388902D03*
Y392052D03*
X256687Y379121D03*
Y382271D03*
X251309Y466078D03*
Y469228D03*
X255509Y465978D03*
Y469128D03*
X251309Y478128D03*
Y474978D03*
X255509Y478128D03*
Y474978D03*
X246089Y478179D03*
Y475029D03*
X255048Y516344D03*
X250209Y516778D03*
X259000Y516356D03*
X258748Y509415D03*
Y512565D03*
X255048Y519494D03*
X250209Y519928D03*
X259000Y519506D03*
X249368Y543928D03*
Y547078D03*
X251809Y555928D03*
Y552778D03*
X246209Y553728D03*
Y550578D03*
X248440Y739081D03*
X243940Y727581D03*
Y730731D03*
X257440Y739081D03*
X252940D03*
X257440Y730731D03*
Y727581D03*
X243940Y739081D03*
X252940Y730731D03*
Y727581D03*
X248440Y730731D03*
Y727581D03*
Y742231D03*
X257440D03*
X252940D03*
X243940D03*
X271339Y84895D03*
Y81745D03*
X269625Y100289D03*
Y103439D03*
X264953Y114152D03*
Y117302D03*
X272953Y114152D03*
Y117302D03*
X268953Y114152D03*
Y117302D03*
X262132Y245889D03*
Y249039D03*
X260143Y275621D03*
Y272471D03*
X272218Y318562D03*
Y315412D03*
X264218Y318562D03*
Y315412D03*
X260218Y318562D03*
Y315412D03*
X268218Y318562D03*
Y315412D03*
X260350Y366987D03*
Y363837D03*
X272687Y379121D03*
Y382271D03*
X268687D03*
Y379121D03*
X260687Y382271D03*
Y379121D03*
X260609Y465978D03*
Y469128D03*
X264909Y465978D03*
Y469128D03*
X269209Y465978D03*
Y469128D03*
X273509Y465978D03*
Y469128D03*
X260609Y478128D03*
Y474978D03*
X269109Y478128D03*
Y474978D03*
X264909Y478128D03*
Y474978D03*
X273209Y478128D03*
Y474978D03*
X270209Y490278D03*
Y493428D03*
X274209Y490278D03*
Y493428D03*
X270209Y518428D03*
Y515278D03*
X274209Y518428D03*
Y515278D03*
X267242Y543505D03*
Y546655D03*
X266418Y580633D03*
X270940Y730731D03*
Y727581D03*
X261940Y739081D03*
X266440D03*
X261940Y730731D03*
Y727581D03*
X270940Y739081D03*
X266440Y730731D03*
Y727581D03*
X261940Y742231D03*
X266440D03*
X270940D03*
X279552Y84908D03*
Y81758D03*
X287905Y84695D03*
Y81545D03*
X283786Y84695D03*
Y81545D03*
X275542Y84928D03*
Y81778D03*
X284199Y106109D03*
Y109259D03*
X276953Y117302D03*
Y114152D03*
X276218Y318562D03*
Y315412D03*
X284218Y318562D03*
Y315412D03*
X280218Y318562D03*
Y315412D03*
X288218Y318562D03*
Y315412D03*
X283498Y367402D03*
Y364252D03*
X276825Y367017D03*
Y363867D03*
X282368Y478188D03*
Y475038D03*
X278311Y478202D03*
Y475052D03*
X278209Y517928D03*
Y514778D03*
X277590Y582884D03*
X288630Y727362D03*
Y730512D03*
X283440Y739081D03*
X275440D03*
X279940Y727281D03*
Y730431D03*
X287440Y739081D03*
X279440D03*
X275440Y730731D03*
Y727581D03*
X283440Y742231D03*
X275440D03*
X287440D03*
X279440D03*
X295862Y84735D03*
Y81585D03*
X291824Y84815D03*
Y81665D03*
X299135Y322650D03*
Y325800D03*
X292218Y318562D03*
Y315412D03*
X296218Y318562D03*
Y315412D03*
X297131Y369021D03*
Y372171D03*
X301131Y369021D03*
Y372171D03*
X305708Y507818D03*
Y510968D03*
X296913Y510981D03*
Y507831D03*
X301457Y507829D03*
Y510979D03*
X294909Y586128D03*
Y582978D03*
X292420Y652392D03*
Y649242D03*
X296453Y649199D03*
Y652349D03*
X299638Y707048D03*
X303538D03*
X299638Y710198D03*
X303538D03*
X299440Y739081D03*
X291440D03*
X292840Y729522D03*
Y732672D03*
X303440Y739081D03*
X301450Y729345D03*
Y726195D03*
X295440Y739081D03*
X305640Y730942D03*
Y727792D03*
X299440Y742231D03*
X291440D03*
X303440D03*
X295440D03*
X310939Y84815D03*
Y81665D03*
X319005Y84635D03*
Y81485D03*
X314926Y84714D03*
Y81564D03*
X313789Y115659D03*
Y118809D03*
X313190Y342353D03*
Y339203D03*
X321987Y536052D03*
Y539202D03*
X311940Y739081D03*
X307940D03*
X313410Y732276D03*
Y729126D03*
X309530Y730942D03*
Y727792D03*
X311940Y742231D03*
X307940D03*
X327005Y84635D03*
Y81485D03*
X323005Y84635D03*
Y81485D03*
X368920Y716909D03*
Y720059D03*
X364920Y716909D03*
Y720059D03*
X383860Y658089D03*
Y661239D03*
X389999Y665278D03*
Y668428D03*
X407506Y653413D03*
Y650263D03*
X413940Y739081D03*
Y730731D03*
Y727581D03*
Y742231D03*
X427079Y522404D03*
Y519254D03*
X420289Y697510D03*
Y700660D03*
X422940Y727581D03*
Y730731D03*
X426940Y739081D03*
X427440Y727581D03*
Y730731D03*
X418440Y739081D03*
X422940D03*
X431440D03*
X418440Y730731D03*
Y727581D03*
X426940Y742231D03*
X418440D03*
X422940D03*
X431440D03*
X435773Y265453D03*
Y262303D03*
X445440Y727581D03*
Y730731D03*
X435940Y739081D03*
X436440Y727581D03*
Y730731D03*
X444940Y739081D03*
X440440D03*
X440940Y730731D03*
Y727581D03*
X435940Y742231D03*
X444940D03*
X440440D03*
X459000Y202925D03*
Y206075D03*
X450957Y486305D03*
Y489455D03*
X458938Y655198D03*
Y652048D03*
X453235Y647580D03*
Y650730D03*
X449183Y647604D03*
Y650754D03*
X462440Y739081D03*
X453940D03*
X454440Y727581D03*
Y730731D03*
X458440D03*
Y727581D03*
X462440Y730731D03*
Y727581D03*
X458440Y739081D03*
X449940Y730731D03*
Y727581D03*
X449440Y739081D03*
X462440Y742231D03*
X453940D03*
X458440D03*
X449440D03*
X469000Y139925D03*
Y143075D03*
X478000Y210075D03*
Y206925D03*
X473898Y649648D03*
Y652798D03*
X466440Y739081D03*
X470440D03*
Y730731D03*
Y727581D03*
X466440Y730731D03*
Y727581D03*
Y742231D03*
X470440D03*
X495738Y543850D03*
Y547000D03*
X502000Y232425D03*
X506000D03*
X510000D03*
X502000Y235575D03*
X506000D03*
X510000D03*
X498563Y460516D03*
Y457366D03*
X501938Y534030D03*
X506938Y539940D03*
Y536790D03*
X510938Y539940D03*
Y536790D03*
X501938Y537180D03*
X496338Y555750D03*
Y558900D03*
X503628Y571790D03*
Y568640D03*
X507528Y571790D03*
Y568640D03*
X505138Y597300D03*
Y594150D03*
X521320Y170525D03*
X525400Y186475D03*
Y183325D03*
X521400Y186475D03*
Y183325D03*
X521320Y173675D03*
X514059Y230075D03*
Y226925D03*
X517577Y450051D03*
Y446901D03*
X522638Y450298D03*
Y447148D03*
X526638Y533350D03*
X518838D03*
X514938D03*
X522738D03*
X526638Y536500D03*
X518838D03*
X514938D03*
X522738D03*
X519638Y597200D03*
Y594050D03*
X523538Y597300D03*
Y594150D03*
X512533Y626791D03*
Y629941D03*
X514940Y726581D03*
Y729731D03*
X519440Y738081D03*
X523940Y726581D03*
Y729731D03*
X519440D03*
Y726581D03*
X514940Y738081D03*
X523940D03*
X519440Y741231D03*
X514940D03*
X523940D03*
X533768Y186419D03*
Y183269D03*
X537928Y186433D03*
Y183283D03*
X529272Y186459D03*
Y183309D03*
X542002Y186426D03*
Y183276D03*
X531238Y450298D03*
Y447148D03*
X528338Y474348D03*
Y477498D03*
X530538Y533350D03*
X541538Y533250D03*
X534438Y533350D03*
X530538Y536500D03*
X541538Y536400D03*
X534438Y536500D03*
X536438Y597200D03*
Y594050D03*
X531438Y597300D03*
Y594150D03*
X527438Y597300D03*
Y594150D03*
X540338Y597200D03*
Y594050D03*
X537440Y738081D03*
X541940D03*
X532940Y726581D03*
Y729731D03*
X528440Y738081D03*
X541940Y729731D03*
Y726581D03*
X532940Y738081D03*
X537440Y729731D03*
Y726581D03*
X528440Y729731D03*
Y726581D03*
X537440Y741231D03*
X541940D03*
X528440D03*
X532940D03*
X546000Y186426D03*
Y183276D03*
X557174Y269020D03*
Y272170D03*
X545438Y533250D03*
Y536400D03*
X548238Y547950D03*
X555138Y561450D03*
Y564600D03*
X548238Y551100D03*
X555138Y568350D03*
Y571500D03*
X544238Y597200D03*
Y594050D03*
X555138Y587400D03*
Y584250D03*
X548138Y597200D03*
Y594050D03*
X555508Y642118D03*
Y645268D03*
X550940Y738081D03*
X546440D03*
X555440Y738381D03*
X546440Y729731D03*
Y726581D03*
X555440Y729731D03*
Y726581D03*
X550940Y729731D03*
Y726581D03*
Y741231D03*
X546440D03*
X555440Y741531D03*
X563474Y234520D03*
X569874D03*
X563474Y237670D03*
X569874D03*
X566774Y269020D03*
Y272170D03*
X570874Y269020D03*
Y272170D03*
X568940Y726581D03*
Y729731D03*
X564440Y738581D03*
X573440D03*
X559940Y726581D03*
Y729731D03*
X568940Y738581D03*
X573440Y729731D03*
Y726581D03*
X564440Y729731D03*
Y726581D03*
X559940Y738581D03*
X564440Y741731D03*
X573440D03*
X568940D03*
X559940D03*
X576074Y234520D03*
Y237670D03*
X583651Y705451D03*
Y702301D03*
X588151Y705451D03*
Y702301D03*
X579151Y705451D03*
Y702301D03*
X577940Y726581D03*
Y729731D03*
X587940Y738081D03*
Y729731D03*
Y726581D03*
X577940Y738581D03*
X587940Y741231D03*
X577940Y741731D03*
X596741Y242818D03*
Y245968D03*
X604741Y242818D03*
Y245968D03*
X600741D03*
Y242818D03*
X596741Y254218D03*
Y257368D03*
X596641Y266268D03*
Y263118D03*
X604741Y254218D03*
Y257368D03*
X600741D03*
Y254218D03*
X604641Y266268D03*
Y263118D03*
X600641D03*
Y266268D03*
X601440Y738081D03*
X605940D03*
X596940D03*
X592440Y726581D03*
Y729731D03*
Y738081D03*
X596940Y729731D03*
Y726581D03*
X601440Y729731D03*
Y726581D03*
X605940Y729731D03*
Y726581D03*
X601440Y741231D03*
X605940D03*
X596940D03*
X592440D03*
X608741Y242818D03*
Y245968D03*
X612841D03*
Y242818D03*
X608741Y254218D03*
Y257368D03*
X608641Y266268D03*
Y263118D03*
X612774Y263120D03*
Y266270D03*
X612841Y257368D03*
Y254218D03*
X609345Y669937D03*
Y666787D03*
X617235Y682716D03*
Y685866D03*
X619440Y738081D03*
X614940D03*
X610440D03*
X619440Y729731D03*
Y726581D03*
X614940Y729731D03*
Y726581D03*
X610440Y729731D03*
Y726581D03*
X619440Y741231D03*
X614940D03*
X610440D03*
X626970Y587418D03*
Y584268D03*
X632570Y587618D03*
Y584468D03*
X636870Y587618D03*
Y584468D03*
X626070Y619468D03*
Y622618D03*
X633137Y619570D03*
Y622720D03*
X623957Y718092D03*
Y714942D03*
X627957Y718092D03*
Y714942D03*
X623940Y726581D03*
Y729731D03*
Y738081D03*
X628440D03*
X636440D03*
X632440D03*
X628440Y729722D03*
Y726572D03*
X623940Y741231D03*
X628440D03*
X636440D03*
X632440D03*
X648838Y414360D03*
Y411210D03*
X645237Y587620D03*
Y584470D03*
X640970Y587718D03*
Y584568D03*
X646070Y619668D03*
Y622818D03*
X640070Y619668D03*
Y622818D03*
X650339Y660418D03*
X645752Y660431D03*
X650339Y663568D03*
X645752Y663581D03*
X648000Y738925D03*
X652660Y739360D03*
Y742510D03*
X648000Y742075D03*
X668422Y373085D03*
Y369935D03*
X659938Y383660D03*
Y380510D03*
X663938D03*
Y383660D03*
X658338Y414360D03*
Y411210D03*
X653538Y411310D03*
Y414460D03*
X663238D03*
Y411310D03*
X667538Y414360D03*
Y411210D03*
X664503Y672129D03*
Y668979D03*
X661034Y683798D03*
Y680648D03*
X656660Y739360D03*
Y742510D03*
X672522Y369935D03*
Y373085D03*
X683468Y625772D03*
Y628922D03*
X687468Y625772D03*
Y628922D03*
X711261Y625723D03*
Y628873D03*
X715761Y625723D03*
Y628873D03*
X709500Y740425D03*
Y743575D03*
X720261Y625723D03*
Y628873D03*
X729500Y734575D03*
Y731425D03*
Y740425D03*
Y743575D03*
G54D64*
X546181Y81889D03*
G54D55*
X414961Y98622D03*
G54D28*
X51240Y807872D03*
X55177D03*
X59114D03*
X63051D03*
X66988D03*
X70925D03*
X74862D03*
X78799D03*
X82736D03*
X86673D03*
X90610D03*
X94547D03*
X98484D03*
X102421D03*
X106358D03*
X110295D03*
X114232D03*
X118169D03*
X122106D03*
X126043D03*
X129980D03*
X133917D03*
X137854D03*
X141791D03*
X145728D03*
X149665D03*
X153602D03*
X157539D03*
X161476D03*
X165413D03*
X169350D03*
X173287D03*
X177224D03*
X181161D03*
X185098D03*
X189035D03*
X192972D03*
X196909D03*
X200846D03*
X204783D03*
X208720D03*
X212658D03*
X216594D03*
X220532D03*
X224469D03*
X228406D03*
X232343D03*
X236280D03*
X240217D03*
X244154D03*
X248091D03*
X252028D03*
X255965D03*
X259902D03*
X263839D03*
X267776D03*
X271713D03*
X275650D03*
X279587D03*
X283524D03*
X287461D03*
X291398D03*
X295335D03*
X299272D03*
X303209D03*
X307146D03*
X311083D03*
X315020D03*
X318957D03*
X322894D03*
X326831D03*
X338642D03*
X342579D03*
X346516D03*
X350453D03*
X354390D03*
X358327D03*
X362264D03*
X366201D03*
X370138D03*
X374075D03*
X409510D03*
X413447D03*
X417384D03*
X421321D03*
X425258D03*
X429195D03*
X433132D03*
X437069D03*
X441006D03*
X444943D03*
X448880D03*
X452817D03*
X456754D03*
X460691D03*
X464628D03*
X468565D03*
X472502D03*
X476439D03*
X480376D03*
X484313D03*
X488250D03*
X492187D03*
X496124D03*
X500061D03*
X503998D03*
X507935D03*
X511872D03*
X515809D03*
X519746D03*
X523683D03*
X527620D03*
X531557D03*
X535494D03*
X539431D03*
X543368D03*
X547305D03*
X551242D03*
X555179D03*
X559116D03*
X563053D03*
X566990D03*
X570928D03*
X574864D03*
X578802D03*
X582739D03*
X586676D03*
X590613D03*
X594550D03*
X598487D03*
X602424D03*
X606361D03*
X610298D03*
X614235D03*
X618172D03*
X622109D03*
X626046D03*
X629983D03*
X633920D03*
X637857D03*
X641794D03*
X645731D03*
X649668D03*
X653605D03*
X657542D03*
X661479D03*
X665416D03*
X669353D03*
X673290D03*
X677227D03*
X681164D03*
X685101D03*
X696912D03*
X700849D03*
X704786D03*
X708723D03*
X712660D03*
X716597D03*
X720534D03*
X724471D03*
X728408D03*
X732345D03*
G54D83*
G01X78799D02*
Y798987D01*
X77685Y797873D01*
Y786625D01*
X77637Y778501D01*
X76324Y765640D01*
X74736Y756629D01*
X66230Y721206D01*
Y697974D01*
X66229Y697371D01*
X68901Y634156D01*
X68872Y633766D01*
X67986Y629071D01*
X64430Y625515D01*
X62850D01*
X61205Y623870D01*
G01X74862Y807872D02*
Y798986D01*
X75975Y797873D01*
Y786631D01*
X75927Y778593D01*
X74629Y765876D01*
X73060Y756978D01*
X64520Y721409D01*
Y697976D01*
X64518Y697336D01*
X66048Y661034D01*
X66153Y658531D01*
X66206Y657300D01*
X65593Y656637D01*
X65646Y655406D01*
X66311Y654797D01*
X66364Y653566D01*
X65751Y652903D01*
X65804Y651672D01*
X66469Y651063D01*
X66683Y646024D01*
X66134Y645431D01*
X66187Y644200D01*
X66783Y643652D01*
X66836Y642422D01*
X66288Y641829D01*
X66341Y640598D01*
X66937Y640050D01*
X66990Y638820D01*
X66442Y638227D01*
X66495Y636996D01*
X67091Y636448D01*
X67192Y634084D01*
X66403Y629907D01*
X63721Y627225D01*
X62850D01*
X61205Y628870D01*
G01X86673Y807872D02*
Y798986D01*
X87786Y797873D01*
Y786041D01*
X69660Y722039D01*
Y699414D01*
X72134Y686659D01*
X73857Y668218D01*
X74111Y665512D01*
X74227Y664286D01*
X73554Y663477D01*
X73670Y662251D01*
X74481Y661580D01*
X74597Y660354D01*
X73924Y659545D01*
X74040Y658319D01*
X74851Y657648D01*
X74967Y656422D01*
X74294Y655613D01*
X74410Y654387D01*
X75221Y653716D01*
X75337Y652490D01*
X74664Y651681D01*
X74780Y650455D01*
X75591Y649784D01*
X75707Y648558D01*
X75034Y647749D01*
X75150Y646523D01*
X75960Y645852D01*
X79193Y611392D01*
X78512Y607899D01*
X78152Y607269D01*
X77025D01*
X75380Y608914D01*
G01Y603914D02*
X77025Y605559D01*
X79145D01*
X80137Y607295D01*
X80919Y611306D01*
X73829Y686902D01*
X71370Y699579D01*
Y721801D01*
X89496Y785803D01*
Y797873D01*
X90610Y798987D01*
Y807872D01*
G01X611702Y185690D02*
X614194Y183198D01*
X623045D01*
X624800Y184953D01*
G01X611702Y178997D02*
X614193Y181488D01*
X623265D01*
X624800Y179953D01*
G01X611702Y200690D02*
X614193Y198199D01*
X621356D01*
X623301Y200144D01*
G01X611702Y193997D02*
X614194Y196489D01*
X621356D01*
X623301Y194544D01*
G01Y200144D02*
Y198609D01*
X623711Y198199D01*
X626458D01*
X627566Y199307D01*
G01X623301Y194544D02*
Y196079D01*
X623711Y196489D01*
X626384D01*
X627566Y195307D01*
G01X634962Y200121D02*
X633317Y198476D01*
X631547D01*
X630716Y199307D01*
G01X634962Y195121D02*
X633317Y196766D01*
X632175D01*
X630716Y195307D01*
G01X712660Y807872D02*
Y798986D01*
X713773Y797873D01*
Y785144D01*
X712191Y776811D01*
X711865Y769203D01*
X712066Y767038D01*
X714820Y746842D01*
Y694687D01*
X709017Y679549D01*
X709184Y675145D01*
X711313Y673016D01*
X715070D01*
X716750Y674696D01*
Y675946D01*
X718445Y677641D01*
G01X713445D02*
X715040Y676046D01*
Y675405D01*
X714361Y674726D01*
X712022D01*
X710868Y675880D01*
X710740Y679264D01*
X712623Y684177D01*
X713399Y684523D01*
X713841Y685673D01*
X713493Y686448D01*
X713935Y687599D01*
X714711Y687945D01*
X715153Y689095D01*
X714805Y689870D01*
X715247Y691021D01*
X716023Y691367D01*
X716465Y692517D01*
X716117Y693293D01*
X716530Y694370D01*
Y695822D01*
X717220Y696512D01*
Y697742D01*
X716530Y698432D01*
Y699662D01*
X717220Y700352D01*
Y701582D01*
X716530Y702272D01*
Y703502D01*
X717220Y704192D01*
Y705422D01*
X716530Y706112D01*
Y707342D01*
X717220Y708032D01*
Y709262D01*
X716530Y709952D01*
Y711182D01*
X717220Y711872D01*
Y713102D01*
X716530Y713792D01*
Y746959D01*
X713766Y767233D01*
X713579Y769246D01*
X713659Y771089D01*
X714151Y771539D01*
X714204Y772770D01*
X713752Y773261D01*
X713895Y776614D01*
X714068Y777522D01*
X714609Y777889D01*
X714839Y779100D01*
X714470Y779639D01*
X714700Y780848D01*
X715241Y781215D01*
X715471Y782426D01*
X715101Y782965D01*
X715483Y784983D01*
Y797873D01*
X716597Y798987D01*
Y807872D01*
G01X724471D02*
Y798986D01*
X725584Y797873D01*
Y789037D01*
X722730Y778778D01*
Y774355D01*
X723350Y768323D01*
Y709430D01*
X722500Y708580D01*
Y707350D01*
X723350Y706500D01*
Y705270D01*
X722500Y704420D01*
Y703190D01*
X723350Y702340D01*
Y701110D01*
X722500Y700260D01*
Y699030D01*
X723350Y698180D01*
Y696950D01*
X722500Y696100D01*
Y694870D01*
X723350Y694020D01*
Y692790D01*
X722500Y691940D01*
Y690710D01*
X723350Y689860D01*
Y688630D01*
X722500Y687780D01*
Y686550D01*
X723350Y685700D01*
Y683232D01*
X722958Y682051D01*
X722185Y681663D01*
X721797Y680494D01*
X722186Y679722D01*
X719978Y673055D01*
X716005Y669082D01*
X714882Y668626D01*
X714179Y668925D01*
X713038Y668461D01*
X712741Y667758D01*
X709908Y666609D01*
X707433D01*
X706741Y667301D01*
Y668129D01*
X708386Y669774D01*
G01X728408Y807872D02*
Y798987D01*
X727294Y797873D01*
Y788803D01*
X724440Y778544D01*
Y774443D01*
X725060Y768411D01*
Y682956D01*
X721474Y672132D01*
X716970Y667627D01*
X710242Y664899D01*
X706724D01*
X705031Y666592D01*
Y668129D01*
X703386Y669774D01*
G54D56*
X413386Y377165D03*
G54D74*
X712975Y155655D03*
Y165455D03*
Y173455D03*
Y183255D03*
Y234461D03*
Y244261D03*
Y252261D03*
Y262061D03*
X723275Y165455D03*
Y173455D03*
Y183255D03*
Y244261D03*
Y252261D03*
Y262061D03*
G54D29*
X71970Y357848D03*
X147590Y647878D03*
X487770Y513674D03*
X577880Y395242D03*
X693400Y758198D03*
X745580Y62870D03*
G54D65*
X556181Y81889D03*
G54D38*
X160874Y263034D03*
X159894Y269042D03*
X175200Y265676D03*
X167849Y270242D03*
G54D47*
X228130Y225834D03*
X236593Y258887D03*
X244122Y250972D03*
G54D84*
G01X38493Y-241864D02*
Y-246864D01*
G01X37036Y-241864D02*
X39950D01*
G01X44860Y-246864D02*
X42326D01*
Y-241864D01*
X44860D01*
G01X43846Y-244281D02*
X42326D01*
G01X47426Y-241864D02*
Y-246864D01*
X49960D01*
G01X53793Y-247031D02*
X53666Y-246947D01*
Y-246781D01*
X53793Y-246697D01*
X53920Y-246781D01*
Y-246947D01*
X53793Y-247031D01*
G01Y-244781D02*
X53666Y-244697D01*
Y-244531D01*
X53793Y-244447D01*
X53920Y-244531D01*
Y-244697D01*
X53793Y-244781D01*
G01X58576Y-248531D02*
X57943Y-247697D01*
X57626Y-246864D01*
Y-243531D01*
X57943Y-242697D01*
X58576Y-241864D01*
G01X63993D02*
X63486Y-242031D01*
X63106Y-242447D01*
X62853Y-242947D01*
X62663Y-243614D01*
X62600Y-244364D01*
X62663Y-245114D01*
X62853Y-245781D01*
X63106Y-246281D01*
X63486Y-246697D01*
X63993Y-246864D01*
X64500Y-246697D01*
X64880Y-246281D01*
X65133Y-245781D01*
X65323Y-245114D01*
X65386Y-244364D01*
X65323Y-243614D01*
X65133Y-242947D01*
X64880Y-242447D01*
X64500Y-242031D01*
X63993Y-241864D01*
G01X67700Y-245864D02*
X68080Y-246447D01*
X68586Y-246781D01*
X69156Y-246864D01*
X69663Y-246781D01*
X70170Y-246364D01*
X70486Y-245864D01*
X70550Y-245364D01*
X70423Y-244781D01*
X69980Y-244364D01*
X69536Y-244197D01*
X68966D01*
G01X69536D02*
X69916Y-243947D01*
X70233Y-243531D01*
X70360Y-243031D01*
X70233Y-242531D01*
X69916Y-242114D01*
X69346Y-241864D01*
X68776Y-241947D01*
X68206Y-242281D01*
G01X74510Y-248531D02*
X75143Y-247697D01*
X75460Y-246864D01*
Y-243531D01*
X75143Y-242697D01*
X74510Y-241864D01*
G01X77900Y-245864D02*
X78280Y-246447D01*
X78786Y-246781D01*
X79356Y-246864D01*
X79863Y-246781D01*
X80370Y-246364D01*
X80686Y-245864D01*
X80750Y-245364D01*
X80623Y-244781D01*
X80180Y-244364D01*
X79736Y-244197D01*
X79166D01*
G01X79736D02*
X80116Y-243947D01*
X80433Y-243531D01*
X80560Y-243031D01*
X80433Y-242531D01*
X80116Y-242114D01*
X79546Y-241864D01*
X78976Y-241947D01*
X78406Y-242281D01*
G01X83190Y-242697D02*
X83570Y-242197D01*
X84013Y-241947D01*
X84520Y-241864D01*
X85153Y-242031D01*
X85596Y-242447D01*
X85723Y-242947D01*
X85660Y-243447D01*
X85406Y-243864D01*
X84140Y-244697D01*
X83570Y-245281D01*
X83190Y-246114D01*
X83063Y-246864D01*
X85723D01*
G01X89366D02*
X89493Y-245781D01*
X89683Y-244864D01*
X89936Y-244031D01*
X90253Y-243114D01*
X90760Y-241864D01*
X88226D01*
G01X93770Y-245197D02*
X95416D01*
G01X98490Y-242697D02*
X98870Y-242197D01*
X99313Y-241947D01*
X99820Y-241864D01*
X100453Y-242031D01*
X100896Y-242447D01*
X101023Y-242947D01*
X100960Y-243447D01*
X100706Y-243864D01*
X99440Y-244697D01*
X98870Y-245281D01*
X98490Y-246114D01*
X98363Y-246864D01*
X101023D01*
G01X103400Y-245864D02*
X103780Y-246447D01*
X104286Y-246781D01*
X104856Y-246864D01*
X105363Y-246781D01*
X105870Y-246364D01*
X106186Y-245864D01*
X106250Y-245364D01*
X106123Y-244781D01*
X105680Y-244364D01*
X105236Y-244197D01*
X104666D01*
G01X105236D02*
X105616Y-243947D01*
X105933Y-243531D01*
X106060Y-243031D01*
X105933Y-242531D01*
X105616Y-242114D01*
X105046Y-241864D01*
X104476Y-241947D01*
X103906Y-242281D01*
G01X110653Y-246864D02*
Y-241864D01*
X108310Y-245447D01*
X111476D01*
G01X113600Y-246114D02*
X113980Y-246531D01*
X114423Y-246781D01*
X114993Y-246864D01*
X115563Y-246697D01*
X116006Y-246364D01*
X116323Y-245781D01*
X116386Y-245114D01*
X116260Y-244447D01*
X115943Y-244031D01*
X115500Y-243697D01*
X115056Y-243614D01*
X114613Y-243697D01*
X114043Y-244031D01*
X114233Y-241864D01*
X115943D01*
G01X123990Y-246864D02*
Y-241864D01*
X126396D01*
G01X125510Y-244281D02*
X123990D01*
G01X128710Y-246864D02*
X130293Y-241864D01*
X131876Y-246864D01*
G01X131306Y-245114D02*
X129280D01*
G01X134063Y-246864D02*
X136723Y-241864D01*
G01X134063D02*
X136723Y-246864D01*
G01X140493Y-247031D02*
X140366Y-246947D01*
Y-246781D01*
X140493Y-246697D01*
X140620Y-246781D01*
Y-246947D01*
X140493Y-247031D01*
G01Y-244781D02*
X140366Y-244697D01*
Y-244531D01*
X140493Y-244447D01*
X140620Y-244531D01*
Y-244697D01*
X140493Y-244781D01*
G01X145276Y-248531D02*
X144643Y-247697D01*
X144326Y-246864D01*
Y-243531D01*
X144643Y-242697D01*
X145276Y-241864D01*
G01X150693D02*
X150186Y-242031D01*
X149806Y-242447D01*
X149553Y-242947D01*
X149363Y-243614D01*
X149300Y-244364D01*
X149363Y-245114D01*
X149553Y-245781D01*
X149806Y-246281D01*
X150186Y-246697D01*
X150693Y-246864D01*
X151200Y-246697D01*
X151580Y-246281D01*
X151833Y-245781D01*
X152023Y-245114D01*
X152086Y-244364D01*
X152023Y-243614D01*
X151833Y-242947D01*
X151580Y-242447D01*
X151200Y-242031D01*
X150693Y-241864D01*
G01X154400Y-245864D02*
X154780Y-246447D01*
X155286Y-246781D01*
X155856Y-246864D01*
X156363Y-246781D01*
X156870Y-246364D01*
X157186Y-245864D01*
X157250Y-245364D01*
X157123Y-244781D01*
X156680Y-244364D01*
X156236Y-244197D01*
X155666D01*
G01X156236D02*
X156616Y-243947D01*
X156933Y-243531D01*
X157060Y-243031D01*
X156933Y-242531D01*
X156616Y-242114D01*
X156046Y-241864D01*
X155476Y-241947D01*
X154906Y-242281D01*
G01X161210Y-248531D02*
X161843Y-247697D01*
X162160Y-246864D01*
Y-243531D01*
X161843Y-242697D01*
X161210Y-241864D01*
G01X164600Y-245864D02*
X164980Y-246447D01*
X165486Y-246781D01*
X166056Y-246864D01*
X166563Y-246781D01*
X167070Y-246364D01*
X167386Y-245864D01*
X167450Y-245364D01*
X167323Y-244781D01*
X166880Y-244364D01*
X166436Y-244197D01*
X165866D01*
G01X166436D02*
X166816Y-243947D01*
X167133Y-243531D01*
X167260Y-243031D01*
X167133Y-242531D01*
X166816Y-242114D01*
X166246Y-241864D01*
X165676Y-241947D01*
X165106Y-242281D01*
G01X170016Y-246281D02*
X170460Y-246697D01*
X170966Y-246864D01*
X171473Y-246697D01*
X171916Y-246197D01*
X172233Y-245447D01*
X172360Y-244697D01*
Y-243781D01*
X172233Y-243031D01*
X171916Y-242364D01*
X171536Y-242031D01*
X171093Y-241864D01*
X170586Y-242031D01*
X170206Y-242364D01*
X169953Y-242864D01*
X169826Y-243531D01*
X169953Y-244114D01*
X170270Y-244697D01*
X170650Y-245031D01*
X171093Y-245114D01*
X171600Y-244947D01*
X171980Y-244531D01*
X172360Y-243781D01*
G01X176066Y-246864D02*
X176193Y-245781D01*
X176383Y-244864D01*
X176636Y-244031D01*
X176953Y-243114D01*
X177460Y-241864D01*
X174926D01*
G01X180470Y-245197D02*
X182116D01*
G01X185000Y-245864D02*
X185380Y-246447D01*
X185886Y-246781D01*
X186456Y-246864D01*
X186963Y-246781D01*
X187470Y-246364D01*
X187786Y-245864D01*
X187850Y-245364D01*
X187723Y-244781D01*
X187280Y-244364D01*
X186836Y-244197D01*
X186266D01*
G01X186836D02*
X187216Y-243947D01*
X187533Y-243531D01*
X187660Y-243031D01*
X187533Y-242531D01*
X187216Y-242114D01*
X186646Y-241864D01*
X186076Y-241947D01*
X185506Y-242281D01*
G01X190290Y-244781D02*
X190733Y-244197D01*
X191113Y-243864D01*
X191620Y-243697D01*
X192063Y-243864D01*
X192380Y-244197D01*
X192633Y-244697D01*
X192696Y-245281D01*
X192633Y-245781D01*
X192380Y-246281D01*
X192000Y-246697D01*
X191556Y-246864D01*
X191050Y-246697D01*
X190606Y-246197D01*
X190353Y-245447D01*
X190290Y-244614D01*
X190416Y-243531D01*
X190606Y-242947D01*
X190923Y-242364D01*
X191366Y-241947D01*
X191810Y-241864D01*
X192253Y-242031D01*
X192570Y-242447D01*
G01X196593Y-246864D02*
Y-241864D01*
X195833Y-242864D01*
G01Y-246864D02*
X197353D01*
G01X202453D02*
Y-241864D01*
X200110Y-245447D01*
X203276D01*
G01X26493Y-176864D02*
Y-251864D01*
X526493D01*
Y-176864D01*
X26493D01*
G01X221493D02*
Y-251864D01*
G01Y-226864D02*
X324493D01*
Y-201864D01*
G01X221493D02*
X324493D01*
G01X332000Y-236864D02*
Y-231864D01*
X333266D01*
X333773Y-232114D01*
X334153Y-232447D01*
X334470Y-232947D01*
X334723Y-233531D01*
X334786Y-234364D01*
X334723Y-235197D01*
X334470Y-235781D01*
X334153Y-236281D01*
X333773Y-236614D01*
X333266Y-236864D01*
X332000D01*
G01X336910D02*
X338493Y-231864D01*
X340076Y-236864D01*
G01X339506Y-235114D02*
X337480D01*
G01X343593Y-231864D02*
Y-236864D01*
G01X342136Y-231864D02*
X345050D01*
G01X349960Y-236864D02*
X347426D01*
Y-231864D01*
X349960D01*
G01X348946Y-234281D02*
X347426D01*
G01X353793Y-237031D02*
X353666Y-236947D01*
Y-236781D01*
X353793Y-236697D01*
X353920Y-236781D01*
Y-236947D01*
X353793Y-237031D01*
G01Y-234781D02*
X353666Y-234697D01*
Y-234531D01*
X353793Y-234447D01*
X353920Y-234531D01*
Y-234697D01*
X353793Y-234781D01*
G01X326493Y-176864D02*
Y-251864D01*
G01X324493Y-176864D02*
Y-251864D01*
G01X326493Y-226864D02*
X526493D01*
G01X332126Y-211864D02*
Y-206864D01*
X333646D01*
X334153Y-207114D01*
X334533Y-207697D01*
X334660Y-208364D01*
X334533Y-209031D01*
X334216Y-209531D01*
X333646Y-209781D01*
X332126D01*
G01X337353Y-212031D02*
X339633Y-206864D01*
G01X342136Y-211864D02*
Y-206864D01*
X345050Y-211864D01*
Y-206864D01*
G01X348693Y-212031D02*
X348566Y-211947D01*
Y-211781D01*
X348693Y-211697D01*
X348820Y-211781D01*
Y-211947D01*
X348693Y-212031D01*
G01Y-209781D02*
X348566Y-209697D01*
Y-209531D01*
X348693Y-209447D01*
X348820Y-209531D01*
Y-209697D01*
X348693Y-209781D01*
G01X326493Y-201864D02*
X526493D01*
G01X332126Y-186864D02*
Y-181864D01*
X333646D01*
X334153Y-182114D01*
X334533Y-182697D01*
X334660Y-183364D01*
X334533Y-184031D01*
X334216Y-184531D01*
X333646Y-184781D01*
X332126D01*
G01X337226Y-186864D02*
Y-181864D01*
X338810D01*
X339316Y-182114D01*
X339633Y-182447D01*
X339760Y-183114D01*
X339633Y-183781D01*
X339253Y-184197D01*
X338810Y-184447D01*
X337226D01*
G01X338810D02*
X339760Y-186864D01*
G01X343593D02*
X343086Y-186781D01*
X342643Y-186447D01*
X342263Y-185947D01*
X342010Y-185364D01*
X341883Y-184697D01*
Y-184031D01*
X342010Y-183364D01*
X342263Y-182781D01*
X342643Y-182281D01*
X343086Y-181947D01*
X343593Y-181864D01*
X344100Y-181947D01*
X344543Y-182281D01*
X344923Y-182781D01*
X345176Y-183364D01*
X345303Y-184031D01*
Y-184697D01*
X345176Y-185364D01*
X344923Y-185947D01*
X344543Y-186447D01*
X344100Y-186781D01*
X343593Y-186864D01*
G01X347426Y-185864D02*
X347743Y-186364D01*
X348123Y-186697D01*
X348566Y-186864D01*
X349073Y-186697D01*
X349453Y-186364D01*
X349833Y-185864D01*
X349960Y-185197D01*
Y-181864D01*
G01X355060Y-186864D02*
X352526D01*
Y-181864D01*
X355060D01*
G01X354046Y-184281D02*
X352526D01*
G01X360286Y-182281D02*
X359906Y-182031D01*
X359463Y-181864D01*
X358956D01*
X358386Y-182114D01*
X357943Y-182531D01*
X357626Y-183031D01*
X357373Y-183864D01*
X357310Y-184614D01*
X357436Y-185364D01*
X357626Y-185864D01*
X358006Y-186364D01*
X358450Y-186697D01*
X358893Y-186864D01*
X359336D01*
X359780Y-186697D01*
X360160Y-186447D01*
X360476Y-186114D01*
G01X363993Y-181864D02*
Y-186864D01*
G01X362536Y-181864D02*
X365450D01*
G01X369093Y-187031D02*
X368966Y-186947D01*
Y-186781D01*
X369093Y-186697D01*
X369220Y-186781D01*
Y-186947D01*
X369093Y-187031D01*
G01Y-184781D02*
X368966Y-184697D01*
Y-184531D01*
X369093Y-184447D01*
X369220Y-184531D01*
Y-184697D01*
X369093Y-184781D01*
G01X447126Y-236864D02*
Y-231864D01*
X448710D01*
X449216Y-232114D01*
X449533Y-232447D01*
X449660Y-233114D01*
X449533Y-233781D01*
X449153Y-234197D01*
X448710Y-234447D01*
X447126D01*
G01X448710D02*
X449660Y-236864D01*
G01X454760D02*
X452226D01*
Y-231864D01*
X454760D01*
G01X453746Y-234281D02*
X452226D01*
G01X457010Y-231864D02*
X458593Y-236864D01*
X460176Y-231864D01*
G01X463693Y-237031D02*
X463566Y-236947D01*
Y-236781D01*
X463693Y-236697D01*
X463820Y-236781D01*
Y-236947D01*
X463693Y-237031D01*
G01Y-234781D02*
X463566Y-234697D01*
Y-234531D01*
X463693Y-234447D01*
X463820Y-234531D01*
Y-234697D01*
X463693Y-234781D01*
G01X441493Y-226864D02*
Y-251864D01*
G01X490493Y-226864D02*
Y-251864D01*
G01X-1043962Y-705877D02*
Y2342823D01*
X2300638D01*
Y-705877D01*
X-1043962D01*
G01X37198Y-238524D02*
X37825Y-239049D01*
X38530Y-239364D01*
X39156D01*
X39783Y-239049D01*
X40253Y-238524D01*
X40488Y-237789D01*
X40331Y-237054D01*
X39940Y-236424D01*
X39235Y-236004D01*
X38295Y-235794D01*
X37746Y-235374D01*
X37511Y-234639D01*
X37668Y-233904D01*
X38060Y-233379D01*
X38608Y-233064D01*
X39156D01*
X39705Y-233274D01*
X40175Y-233799D01*
G01X43498Y-239364D02*
Y-233064D01*
G01X46788D02*
Y-239364D01*
G01Y-236214D02*
X43498D01*
G01X50503Y-233064D02*
X52383D01*
G01X51443D02*
Y-239364D01*
G01X50503D02*
X52383D01*
G01X59310D02*
X56176D01*
Y-233064D01*
X59310D01*
G01X58056Y-236109D02*
X56176D01*
G01X62241Y-239364D02*
Y-233064D01*
X65845Y-239364D01*
Y-233064D01*
G01X70186Y-240519D02*
X70500Y-239154D01*
G01X76643Y-233064D02*
Y-239364D01*
G01X74841Y-233064D02*
X78445D01*
G01X80985Y-239364D02*
X82943Y-233064D01*
X84901Y-239364D01*
G01X84196Y-237159D02*
X81690D01*
G01X88303Y-233064D02*
X90183D01*
G01X89243D02*
Y-239364D01*
G01X88303D02*
X90183D01*
G01X93193Y-233064D02*
X94290Y-239364D01*
X95543Y-233064D01*
X96796Y-239364D01*
X97893Y-233064D01*
G01X99885Y-239364D02*
X101843Y-233064D01*
X103801Y-239364D01*
G01X103096Y-237159D02*
X100590D01*
G01X106341Y-239364D02*
Y-233064D01*
X109945Y-239364D01*
Y-233064D01*
G01X119176Y-239364D02*
Y-233064D01*
X121135D01*
X121761Y-233379D01*
X122153Y-233799D01*
X122310Y-234639D01*
X122153Y-235479D01*
X121683Y-236004D01*
X121135Y-236319D01*
X119176D01*
G01X121135D02*
X122310Y-239364D01*
G01X127043Y-239574D02*
X126886Y-239469D01*
Y-239259D01*
X127043Y-239154D01*
X127200Y-239259D01*
Y-239469D01*
X127043Y-239574D01*
G01X133343Y-239364D02*
X132716Y-239259D01*
X132168Y-238839D01*
X131698Y-238209D01*
X131385Y-237474D01*
X131228Y-236634D01*
Y-235794D01*
X131385Y-234954D01*
X131698Y-234219D01*
X132168Y-233589D01*
X132716Y-233169D01*
X133343Y-233064D01*
X133970Y-233169D01*
X134518Y-233589D01*
X134988Y-234219D01*
X135301Y-234954D01*
X135458Y-235794D01*
Y-236634D01*
X135301Y-237474D01*
X134988Y-238209D01*
X134518Y-238839D01*
X133970Y-239259D01*
X133343Y-239364D01*
G01X139643Y-239574D02*
X139486Y-239469D01*
Y-239259D01*
X139643Y-239154D01*
X139800Y-239259D01*
Y-239469D01*
X139643Y-239574D01*
G01X147666Y-233589D02*
X147196Y-233274D01*
X146648Y-233064D01*
X146021D01*
X145316Y-233379D01*
X144768Y-233904D01*
X144376Y-234534D01*
X144063Y-235584D01*
X143985Y-236529D01*
X144141Y-237474D01*
X144376Y-238104D01*
X144846Y-238734D01*
X145395Y-239154D01*
X145943Y-239364D01*
X146491D01*
X147040Y-239154D01*
X147510Y-238839D01*
X147901Y-238419D01*
G01X152243Y-239574D02*
X152086Y-239469D01*
Y-239259D01*
X152243Y-239154D01*
X152400Y-239259D01*
Y-239469D01*
X152243Y-239574D01*
G01X37120Y-229364D02*
Y-223064D01*
G01X40096D02*
X37120Y-226949D01*
G01X40566Y-229364D02*
X38451Y-225164D01*
G01X43420Y-223064D02*
Y-227579D01*
X43733Y-228524D01*
X44360Y-229154D01*
X45143Y-229364D01*
X45926Y-229154D01*
X46553Y-228524D01*
X46866Y-227579D01*
Y-223064D01*
G01X53010Y-229364D02*
X49876D01*
Y-223064D01*
X53010D01*
G01X51756Y-226109D02*
X49876D01*
G01X56803Y-223064D02*
X58683D01*
G01X57743D02*
Y-229364D01*
G01X56803D02*
X58683D01*
G01X68698Y-228524D02*
X69325Y-229049D01*
X70030Y-229364D01*
X70656D01*
X71283Y-229049D01*
X71753Y-228524D01*
X71988Y-227789D01*
X71831Y-227054D01*
X71440Y-226424D01*
X70735Y-226004D01*
X69795Y-225794D01*
X69246Y-225374D01*
X69011Y-224639D01*
X69168Y-223904D01*
X69560Y-223379D01*
X70108Y-223064D01*
X70656D01*
X71205Y-223274D01*
X71675Y-223799D01*
G01X74998Y-229364D02*
Y-223064D01*
G01X78288D02*
Y-229364D01*
G01Y-226214D02*
X74998D01*
G01X80985Y-229364D02*
X82943Y-223064D01*
X84901Y-229364D01*
G01X84196Y-227159D02*
X81690D01*
G01X87441Y-229364D02*
Y-223064D01*
X91045Y-229364D01*
Y-223064D01*
G01X100198Y-229364D02*
Y-223064D01*
G01X103488D02*
Y-229364D01*
G01Y-226214D02*
X100198D01*
G01X106498Y-228524D02*
X107125Y-229049D01*
X107830Y-229364D01*
X108456D01*
X109083Y-229049D01*
X109553Y-228524D01*
X109788Y-227789D01*
X109631Y-227054D01*
X109240Y-226424D01*
X108535Y-226004D01*
X107595Y-225794D01*
X107046Y-225374D01*
X106811Y-224639D01*
X106968Y-223904D01*
X107360Y-223379D01*
X107908Y-223064D01*
X108456D01*
X109005Y-223274D01*
X109475Y-223799D01*
G01X113503Y-223064D02*
X115383D01*
G01X114443D02*
Y-229364D01*
G01X113503D02*
X115383D01*
G01X118785D02*
X120743Y-223064D01*
X122701Y-229364D01*
G01X121996Y-227159D02*
X119490D01*
G01X125241Y-229364D02*
Y-223064D01*
X128845Y-229364D01*
Y-223064D01*
G01X133813Y-226214D02*
X135380D01*
Y-228104D01*
X134910Y-228734D01*
X134361Y-229154D01*
X133578Y-229364D01*
X132795Y-229154D01*
X132246Y-228734D01*
X131776Y-228104D01*
X131463Y-227369D01*
X131306Y-226529D01*
Y-225794D01*
X131463Y-225164D01*
X131776Y-224429D01*
X132246Y-223799D01*
X132716Y-223379D01*
X133343Y-223064D01*
X133891D01*
X134518Y-223274D01*
X134988Y-223694D01*
G01X139486Y-230519D02*
X139800Y-229154D01*
G01X145943Y-223064D02*
Y-229364D01*
G01X144141Y-223064D02*
X147745D01*
G01X150285Y-229364D02*
X152243Y-223064D01*
X154201Y-229364D01*
G01X153496Y-227159D02*
X150990D01*
G01X158543Y-229364D02*
X157916Y-229259D01*
X157368Y-228839D01*
X156898Y-228209D01*
X156585Y-227474D01*
X156428Y-226634D01*
Y-225794D01*
X156585Y-224954D01*
X156898Y-224219D01*
X157368Y-223589D01*
X157916Y-223169D01*
X158543Y-223064D01*
X159170Y-223169D01*
X159718Y-223589D01*
X160188Y-224219D01*
X160501Y-224954D01*
X160658Y-225794D01*
Y-226634D01*
X160501Y-227474D01*
X160188Y-228209D01*
X159718Y-228839D01*
X159170Y-229259D01*
X158543Y-229364D01*
G01X171143D02*
Y-226529D01*
X169576Y-223064D01*
G01X172710D02*
X171143Y-226529D01*
G01X175720Y-223064D02*
Y-227579D01*
X176033Y-228524D01*
X176660Y-229154D01*
X177443Y-229364D01*
X178226Y-229154D01*
X178853Y-228524D01*
X179166Y-227579D01*
Y-223064D01*
G01X181785Y-229364D02*
X183743Y-223064D01*
X185701Y-229364D01*
G01X184996Y-227159D02*
X182490D01*
G01X188241Y-229364D02*
Y-223064D01*
X191845Y-229364D01*
Y-223064D01*
G01X37041Y-219364D02*
Y-213064D01*
X40645Y-219364D01*
Y-213064D01*
G01X45143Y-219364D02*
X44516Y-219259D01*
X43968Y-218839D01*
X43498Y-218209D01*
X43185Y-217474D01*
X43028Y-216634D01*
Y-215794D01*
X43185Y-214954D01*
X43498Y-214219D01*
X43968Y-213589D01*
X44516Y-213169D01*
X45143Y-213064D01*
X45770Y-213169D01*
X46318Y-213589D01*
X46788Y-214219D01*
X47101Y-214954D01*
X47258Y-215794D01*
Y-216634D01*
X47101Y-217474D01*
X46788Y-218209D01*
X46318Y-218839D01*
X45770Y-219259D01*
X45143Y-219364D01*
G01X51443Y-219574D02*
X51286Y-219469D01*
Y-219259D01*
X51443Y-219154D01*
X51600Y-219259D01*
Y-219469D01*
X51443Y-219574D01*
G01X57743Y-219364D02*
Y-213064D01*
X56803Y-214324D01*
G01Y-219364D02*
X58683D01*
G01X64043D02*
X64591Y-219259D01*
X65218Y-218944D01*
X65610Y-218419D01*
X65766Y-217684D01*
X65610Y-216949D01*
X65140Y-216319D01*
X64435Y-216004D01*
X63651D01*
X63181Y-215794D01*
X62790Y-215269D01*
X62633Y-214534D01*
X62868Y-213799D01*
X63416Y-213274D01*
X64043Y-213064D01*
X64670Y-213274D01*
X65218Y-213799D01*
X65453Y-214534D01*
X65296Y-215269D01*
X64905Y-215794D01*
X64435Y-216004D01*
X63651D01*
X62946Y-216319D01*
X62476Y-216949D01*
X62320Y-217684D01*
X62476Y-218419D01*
X62868Y-218944D01*
X63495Y-219259D01*
X64043Y-219364D01*
G01X70343D02*
X70891Y-219259D01*
X71518Y-218944D01*
X71910Y-218419D01*
X72066Y-217684D01*
X71910Y-216949D01*
X71440Y-216319D01*
X70735Y-216004D01*
X69951D01*
X69481Y-215794D01*
X69090Y-215269D01*
X68933Y-214534D01*
X69168Y-213799D01*
X69716Y-213274D01*
X70343Y-213064D01*
X70970Y-213274D01*
X71518Y-213799D01*
X71753Y-214534D01*
X71596Y-215269D01*
X71205Y-215794D01*
X70735Y-216004D01*
X69951D01*
X69246Y-216319D01*
X68776Y-216949D01*
X68620Y-217684D01*
X68776Y-218419D01*
X69168Y-218944D01*
X69795Y-219259D01*
X70343Y-219364D01*
G01X76486Y-220519D02*
X76800Y-219154D01*
G01X80593Y-213064D02*
X81690Y-219364D01*
X82943Y-213064D01*
X84196Y-219364D01*
X85293Y-213064D01*
G01X90810Y-219364D02*
X87676D01*
Y-213064D01*
X90810D01*
G01X89556Y-216109D02*
X87676D01*
G01X93741Y-219364D02*
Y-213064D01*
X97345Y-219364D01*
Y-213064D01*
G01X106498Y-219364D02*
Y-213064D01*
G01X109788D02*
Y-219364D01*
G01Y-216214D02*
X106498D01*
G01X112093Y-213064D02*
X113190Y-219364D01*
X114443Y-213064D01*
X115696Y-219364D01*
X116793Y-213064D01*
G01X118785Y-219364D02*
X120743Y-213064D01*
X122701Y-219364D01*
G01X121996Y-217159D02*
X119490D01*
G01X131855Y-214114D02*
X132325Y-213484D01*
X132873Y-213169D01*
X133500Y-213064D01*
X134283Y-213274D01*
X134831Y-213799D01*
X134988Y-214429D01*
X134910Y-215059D01*
X134596Y-215584D01*
X133030Y-216634D01*
X132325Y-217369D01*
X131855Y-218419D01*
X131698Y-219364D01*
X134988D01*
G01X137841D02*
Y-213064D01*
X141445Y-219364D01*
Y-213064D01*
G01X144220Y-219364D02*
Y-213064D01*
X145786D01*
X146413Y-213379D01*
X146883Y-213799D01*
X147275Y-214429D01*
X147588Y-215164D01*
X147666Y-216214D01*
X147588Y-217264D01*
X147275Y-217999D01*
X146883Y-218629D01*
X146413Y-219049D01*
X145786Y-219364D01*
X144220D01*
G01X156976D02*
Y-213064D01*
X158935D01*
X159561Y-213379D01*
X159953Y-213799D01*
X160110Y-214639D01*
X159953Y-215479D01*
X159483Y-216004D01*
X158935Y-216319D01*
X156976D01*
G01X158935D02*
X160110Y-219364D01*
G01X163120D02*
Y-213064D01*
X164686D01*
X165313Y-213379D01*
X165783Y-213799D01*
X166175Y-214429D01*
X166488Y-215164D01*
X166566Y-216214D01*
X166488Y-217264D01*
X166175Y-217999D01*
X165783Y-218629D01*
X165313Y-219049D01*
X164686Y-219364D01*
X163120D01*
G01X171143Y-219574D02*
X170986Y-219469D01*
Y-219259D01*
X171143Y-219154D01*
X171300Y-219259D01*
Y-219469D01*
X171143Y-219574D01*
G01X61143Y-206664D02*
X58623Y-206247D01*
X56418Y-204581D01*
X54528Y-202081D01*
X53268Y-199164D01*
X52638Y-195831D01*
Y-192497D01*
X53268Y-189164D01*
X54528Y-186247D01*
X56418Y-183748D01*
X58623Y-182081D01*
X61143Y-181664D01*
X63663Y-182081D01*
X65868Y-183748D01*
X67758Y-186247D01*
X69018Y-189164D01*
X69648Y-192497D01*
Y-195831D01*
X69018Y-199164D01*
X67758Y-202081D01*
X65868Y-204581D01*
X63663Y-206247D01*
X61143Y-206664D01*
G01X63663Y-199997D02*
X67443Y-206664D01*
G01X80988Y-189998D02*
Y-201664D01*
X82248Y-204581D01*
X84138Y-206247D01*
X86343Y-206664D01*
X88548Y-206247D01*
X90438Y-204581D01*
X91698Y-201664D01*
G01Y-206664D02*
Y-189998D01*
G01X117213Y-206664D02*
Y-189998D01*
G01Y-192914D02*
X115953Y-191248D01*
X114063Y-190414D01*
X111858Y-189998D01*
X109653Y-190831D01*
X107763Y-192497D01*
X106503Y-194998D01*
X105873Y-198331D01*
X106503Y-201664D01*
X107763Y-204165D01*
X109653Y-205831D01*
X111858Y-206664D01*
X114063Y-206247D01*
X115953Y-204998D01*
X117213Y-203331D01*
G01X131388Y-206664D02*
Y-189998D01*
G01Y-194164D02*
X132648Y-192081D01*
X134538Y-190414D01*
X137058Y-189998D01*
X139263Y-190414D01*
X141153Y-192081D01*
X142098Y-194998D01*
Y-206664D01*
G01X161943Y-181664D02*
Y-206664D01*
G01X157533Y-189998D02*
X166353D01*
G01X192813Y-206664D02*
Y-189998D01*
G01Y-192914D02*
X191553Y-191248D01*
X189663Y-190414D01*
X187458Y-189998D01*
X185253Y-190831D01*
X183363Y-192497D01*
X182103Y-194998D01*
X181473Y-198331D01*
X182103Y-201664D01*
X183363Y-204165D01*
X185253Y-205831D01*
X187458Y-206664D01*
X189663Y-206247D01*
X191553Y-204998D01*
X192813Y-203331D01*
G01X232493Y-186364D02*
Y-194364D01*
X236493D01*
G01X244293D02*
Y-189031D01*
G01Y-189964D02*
X243893Y-189431D01*
X243293Y-189164D01*
X242593Y-189031D01*
X241893Y-189297D01*
X241293Y-189831D01*
X240893Y-190631D01*
X240693Y-191697D01*
X240893Y-192764D01*
X241293Y-193564D01*
X241893Y-194097D01*
X242593Y-194364D01*
X243293Y-194231D01*
X243893Y-193831D01*
X244293Y-193298D01*
G01X248393Y-196764D02*
X248993Y-197031D01*
X249793Y-196764D01*
X250293Y-196231D01*
X250693Y-195564D01*
X251293Y-193431D01*
X252593Y-189031D01*
G01X249393D02*
X251293Y-193431D01*
G01X256993Y-190764D02*
X260193D01*
X259893Y-189831D01*
X259393Y-189297D01*
X258693Y-189031D01*
X257993Y-189164D01*
X257393Y-189564D01*
X256993Y-190497D01*
X256793Y-191298D01*
Y-192097D01*
X256993Y-192897D01*
X257493Y-193697D01*
X258093Y-194231D01*
X258793Y-194364D01*
X259493Y-194097D01*
X260193Y-193298D01*
G01X265093Y-194364D02*
Y-189031D01*
G01Y-190097D02*
X265593Y-189564D01*
X266093Y-189164D01*
X266793Y-189031D01*
X267293Y-189164D01*
X267893Y-189564D01*
G01X254793Y-236364D02*
X257193D01*
G01X255993D02*
Y-244364D01*
G01X254793D02*
X257193D01*
G01X262593D02*
Y-239031D01*
G01Y-240097D02*
X263093Y-239564D01*
X263593Y-239164D01*
X264293Y-239031D01*
X264793Y-239164D01*
X265393Y-239564D01*
G01X270493Y-240764D02*
X273693D01*
X273393Y-239831D01*
X272893Y-239297D01*
X272193Y-239031D01*
X271493Y-239164D01*
X270893Y-239564D01*
X270493Y-240497D01*
X270293Y-241298D01*
Y-242097D01*
X270493Y-242897D01*
X270993Y-243697D01*
X271593Y-244231D01*
X272293Y-244364D01*
X272993Y-244097D01*
X273693Y-243298D01*
G01X278293Y-244364D02*
Y-239031D01*
G01Y-240364D02*
X278693Y-239697D01*
X279293Y-239164D01*
X280093Y-239031D01*
X280793Y-239164D01*
X281393Y-239697D01*
X281693Y-240631D01*
Y-244364D01*
G01X286493Y-240764D02*
X289693D01*
X289393Y-239831D01*
X288893Y-239297D01*
X288193Y-239031D01*
X287493Y-239164D01*
X286893Y-239564D01*
X286493Y-240497D01*
X286293Y-241298D01*
Y-242097D01*
X286493Y-242897D01*
X286993Y-243697D01*
X287593Y-244231D01*
X288293Y-244364D01*
X288993Y-244097D01*
X289693Y-243298D01*
G01X256793Y-215097D02*
X257193Y-214697D01*
X257493Y-214031D01*
X257693Y-213097D01*
X257493Y-212297D01*
X257093Y-211764D01*
X256393Y-211364D01*
X253693D01*
Y-219364D01*
X256993D01*
X257693Y-218831D01*
X258093Y-218031D01*
X258293Y-217097D01*
X258093Y-216164D01*
X257493Y-215364D01*
X256793Y-215097D01*
X253693D01*
G01X263993Y-219364D02*
X263193Y-219231D01*
X262493Y-218697D01*
X261893Y-217897D01*
X261493Y-216964D01*
X261293Y-215897D01*
Y-214831D01*
X261493Y-213764D01*
X261893Y-212831D01*
X262493Y-212031D01*
X263193Y-211497D01*
X263993Y-211364D01*
X264793Y-211497D01*
X265493Y-212031D01*
X266093Y-212831D01*
X266493Y-213764D01*
X266693Y-214831D01*
Y-215897D01*
X266493Y-216964D01*
X266093Y-217897D01*
X265493Y-218697D01*
X264793Y-219231D01*
X263993Y-219364D01*
G01X271993Y-211364D02*
Y-219364D01*
G01X269693Y-211364D02*
X274293D01*
G01X279993D02*
Y-219364D01*
G01X277693Y-211364D02*
X282293D01*
G01X287993Y-219364D02*
X287193Y-219231D01*
X286493Y-218697D01*
X285893Y-217897D01*
X285493Y-216964D01*
X285293Y-215897D01*
Y-214831D01*
X285493Y-213764D01*
X285893Y-212831D01*
X286493Y-212031D01*
X287193Y-211497D01*
X287993Y-211364D01*
X288793Y-211497D01*
X289493Y-212031D01*
X290093Y-212831D01*
X290493Y-213764D01*
X290693Y-214831D01*
Y-215897D01*
X290493Y-216964D01*
X290093Y-217897D01*
X289493Y-218697D01*
X288793Y-219231D01*
X287993Y-219364D01*
G01X293393D02*
Y-211364D01*
X295993Y-218031D01*
X298593Y-211364D01*
Y-219364D01*
G01X285993Y-194364D02*
Y-186364D01*
X284793Y-187964D01*
G01Y-194364D02*
X287193D01*
G01X293993Y-186364D02*
X293193Y-186631D01*
X292593Y-187297D01*
X292193Y-188097D01*
X291893Y-189164D01*
X291793Y-190364D01*
X291893Y-191564D01*
X292193Y-192631D01*
X292593Y-193431D01*
X293193Y-194097D01*
X293993Y-194364D01*
X294793Y-194097D01*
X295393Y-193431D01*
X295793Y-192631D01*
X296093Y-191564D01*
X296193Y-190364D01*
X296093Y-189164D01*
X295793Y-188097D01*
X295393Y-187297D01*
X294793Y-186631D01*
X293993Y-186364D01*
G01X359093Y-237697D02*
X359693Y-236897D01*
X360393Y-236497D01*
X361193Y-236364D01*
X362193Y-236631D01*
X362893Y-237297D01*
X363093Y-238097D01*
X362993Y-238898D01*
X362593Y-239564D01*
X360593Y-240897D01*
X359693Y-241831D01*
X359093Y-243164D01*
X358893Y-244364D01*
X363093D01*
G01X368993Y-236364D02*
X368193Y-236631D01*
X367593Y-237297D01*
X367193Y-238097D01*
X366893Y-239164D01*
X366793Y-240364D01*
X366893Y-241564D01*
X367193Y-242631D01*
X367593Y-243431D01*
X368193Y-244097D01*
X368993Y-244364D01*
X369793Y-244097D01*
X370393Y-243431D01*
X370793Y-242631D01*
X371093Y-241564D01*
X371193Y-240364D01*
X371093Y-239164D01*
X370793Y-238097D01*
X370393Y-237297D01*
X369793Y-236631D01*
X368993Y-236364D01*
G01X376993Y-244364D02*
Y-236364D01*
X375793Y-237964D01*
G01Y-244364D02*
X378193D01*
G01X383093Y-237697D02*
X383693Y-236897D01*
X384393Y-236497D01*
X385193Y-236364D01*
X386193Y-236631D01*
X386893Y-237297D01*
X387093Y-238097D01*
X386993Y-238898D01*
X386593Y-239564D01*
X384593Y-240897D01*
X383693Y-241831D01*
X383093Y-243164D01*
X382893Y-244364D01*
X387093D01*
G01X391193Y-244631D02*
X394793Y-236364D01*
G01X400993Y-244364D02*
Y-236364D01*
X399793Y-237964D01*
G01Y-244364D02*
X402193D01*
G01X408993Y-236364D02*
X408193Y-236631D01*
X407593Y-237297D01*
X407193Y-238097D01*
X406893Y-239164D01*
X406793Y-240364D01*
X406893Y-241564D01*
X407193Y-242631D01*
X407593Y-243431D01*
X408193Y-244097D01*
X408993Y-244364D01*
X409793Y-244097D01*
X410393Y-243431D01*
X410793Y-242631D01*
X411093Y-241564D01*
X411193Y-240364D01*
X411093Y-239164D01*
X410793Y-238097D01*
X410393Y-237297D01*
X409793Y-236631D01*
X408993Y-236364D01*
G01X415193Y-244631D02*
X418793Y-236364D01*
G01X422793Y-242764D02*
X423393Y-243697D01*
X424193Y-244231D01*
X425093Y-244364D01*
X425893Y-244231D01*
X426693Y-243564D01*
X427193Y-242764D01*
X427293Y-241964D01*
X427093Y-241031D01*
X426393Y-240364D01*
X425693Y-240097D01*
X424793D01*
G01X425693D02*
X426293Y-239697D01*
X426793Y-239031D01*
X426993Y-238231D01*
X426793Y-237431D01*
X426293Y-236764D01*
X425393Y-236364D01*
X424493Y-236497D01*
X423593Y-237031D01*
G01X432993Y-244364D02*
Y-236364D01*
X431793Y-237964D01*
G01Y-244364D02*
X434193D01*
G01X358793Y-219364D02*
Y-211364D01*
X360793D01*
X361593Y-211764D01*
X362193Y-212297D01*
X362693Y-213097D01*
X363093Y-214031D01*
X363193Y-215364D01*
X363093Y-216697D01*
X362693Y-217631D01*
X362193Y-218431D01*
X361593Y-218964D01*
X360793Y-219364D01*
X358793D01*
G01X366493D02*
X368993Y-211364D01*
X371493Y-219364D01*
G01X370593Y-216564D02*
X367393D01*
G01X376993Y-211364D02*
Y-219364D01*
G01X374693Y-211364D02*
X379293D01*
G01X383093Y-216031D02*
X383793Y-215097D01*
X384393Y-214564D01*
X385193Y-214297D01*
X385893Y-214564D01*
X386393Y-215097D01*
X386793Y-215897D01*
X386893Y-216831D01*
X386793Y-217631D01*
X386393Y-218431D01*
X385793Y-219097D01*
X385093Y-219364D01*
X384293Y-219097D01*
X383593Y-218298D01*
X383193Y-217097D01*
X383093Y-215764D01*
X383293Y-214031D01*
X383593Y-213097D01*
X384093Y-212164D01*
X384793Y-211497D01*
X385493Y-211364D01*
X386193Y-211631D01*
X386693Y-212297D01*
G01X390393Y-219364D02*
Y-211364D01*
X392993Y-218031D01*
X395593Y-211364D01*
Y-219364D01*
G01X400993Y-211364D02*
Y-219364D01*
G01X398693Y-211364D02*
X403293D01*
G01X406893Y-219364D02*
Y-211364D01*
G01X411093D02*
Y-219364D01*
G01Y-215364D02*
X406893D01*
G01X414793Y-217764D02*
X415393Y-218697D01*
X416193Y-219231D01*
X417093Y-219364D01*
X417893Y-219231D01*
X418693Y-218564D01*
X419193Y-217764D01*
X419293Y-216964D01*
X419093Y-216031D01*
X418393Y-215364D01*
X417693Y-215097D01*
X416793D01*
G01X417693D02*
X418293Y-214697D01*
X418793Y-214031D01*
X418993Y-213231D01*
X418793Y-212431D01*
X418293Y-211764D01*
X417393Y-211364D01*
X416493Y-211497D01*
X415593Y-212031D01*
G01X422493Y-219364D02*
X424993Y-211364D01*
X427493Y-219364D01*
G01X426593Y-216564D02*
X423393D01*
G01X430793Y-219364D02*
Y-211364D01*
X432793D01*
X433593Y-211764D01*
X434193Y-212297D01*
X434693Y-213097D01*
X435093Y-214031D01*
X435193Y-215364D01*
X435093Y-216697D01*
X434693Y-217631D01*
X434193Y-218431D01*
X433593Y-218964D01*
X432793Y-219364D01*
X430793D01*
G01X440993Y-211364D02*
X440193Y-211631D01*
X439593Y-212297D01*
X439193Y-213097D01*
X438893Y-214164D01*
X438793Y-215364D01*
X438893Y-216564D01*
X439193Y-217631D01*
X439593Y-218431D01*
X440193Y-219097D01*
X440993Y-219364D01*
X441793Y-219097D01*
X442393Y-218431D01*
X442793Y-217631D01*
X443093Y-216564D01*
X443193Y-215364D01*
X443093Y-214164D01*
X442793Y-213097D01*
X442393Y-212297D01*
X441793Y-211631D01*
X440993Y-211364D01*
G01X380993Y-186364D02*
Y-194364D01*
G01X378693Y-186364D02*
X383293D01*
G01X387093Y-191031D02*
X387793Y-190097D01*
X388393Y-189564D01*
X389193Y-189297D01*
X389893Y-189564D01*
X390393Y-190097D01*
X390793Y-190897D01*
X390893Y-191831D01*
X390793Y-192631D01*
X390393Y-193431D01*
X389793Y-194097D01*
X389093Y-194364D01*
X388293Y-194097D01*
X387593Y-193298D01*
X387193Y-192097D01*
X387093Y-190764D01*
X387293Y-189031D01*
X387593Y-188097D01*
X388093Y-187164D01*
X388793Y-186497D01*
X389493Y-186364D01*
X390193Y-186631D01*
X390693Y-187297D01*
G01X394393Y-194364D02*
Y-186364D01*
X396993Y-193031D01*
X399593Y-186364D01*
Y-194364D01*
G01X401993Y-197031D02*
X407993D01*
G01X415193Y-187031D02*
X414593Y-186631D01*
X413893Y-186364D01*
X413093D01*
X412193Y-186764D01*
X411493Y-187431D01*
X410993Y-188231D01*
X410593Y-189564D01*
X410493Y-190764D01*
X410693Y-191964D01*
X410993Y-192764D01*
X411593Y-193564D01*
X412293Y-194097D01*
X412993Y-194364D01*
X413693D01*
X414393Y-194097D01*
X414993Y-193697D01*
X415493Y-193164D01*
G01X418393Y-194364D02*
Y-186364D01*
X420993Y-193031D01*
X423593Y-186364D01*
Y-194364D01*
G01X425993Y-197031D02*
X431993D01*
G01X434793Y-194364D02*
Y-186364D01*
X436793D01*
X437593Y-186764D01*
X438193Y-187297D01*
X438693Y-188097D01*
X439093Y-189031D01*
X439193Y-190364D01*
X439093Y-191697D01*
X438693Y-192631D01*
X438193Y-193431D01*
X437593Y-193964D01*
X436793Y-194364D01*
X434793D01*
G01X473793Y-244364D02*
Y-236364D01*
X475793D01*
X476593Y-236764D01*
X477193Y-237297D01*
X477693Y-238097D01*
X478093Y-239031D01*
X478193Y-240364D01*
X478093Y-241697D01*
X477693Y-242631D01*
X477193Y-243431D01*
X476593Y-243964D01*
X475793Y-244364D01*
X473793D01*
G01X503493D02*
Y-236364D01*
X502293Y-237964D01*
G01Y-244364D02*
X504693D01*
G01X509593Y-241031D02*
X510293Y-240097D01*
X510893Y-239564D01*
X511693Y-239297D01*
X512393Y-239564D01*
X512893Y-240097D01*
X513293Y-240897D01*
X513393Y-241831D01*
X513293Y-242631D01*
X512893Y-243431D01*
X512293Y-244097D01*
X511593Y-244364D01*
X510793Y-244097D01*
X510093Y-243298D01*
X509693Y-242097D01*
X509593Y-240764D01*
X509793Y-239031D01*
X510093Y-238097D01*
X510593Y-237164D01*
X511293Y-236497D01*
X511993Y-236364D01*
X512693Y-236631D01*
X513193Y-237297D01*
G54D57*
X456963Y479623D03*
X465293D03*
X456963Y491223D03*
X465293D03*
G54D39*
X156251Y297210D03*
Y303010D03*
X166297Y297499D03*
Y303299D03*
X208947Y343717D03*
Y349517D03*
X203509Y481453D03*
Y487253D03*
X220218Y266687D03*
Y272487D03*
X214447Y343717D03*
Y349517D03*
X218709Y498253D03*
Y492453D03*
X225034Y541049D03*
Y546849D03*
X244201Y326196D03*
Y320396D03*
X251717Y335325D03*
Y341125D03*
X250109Y572109D03*
Y577909D03*
X279004Y494955D03*
Y489155D03*
X291199Y494792D03*
Y488992D03*
X284724Y495518D03*
Y489718D03*
X306221Y79539D03*
Y85339D03*
X300821Y79539D03*
Y85339D03*
X296735Y487826D03*
Y493626D03*
X435451Y251925D03*
Y257725D03*
X494065Y486325D03*
Y492125D03*
X508438Y484300D03*
Y490100D03*
X683230Y454899D03*
Y460699D03*
X689126Y454965D03*
X694833Y464340D03*
Y470140D03*
X689126Y460765D03*
X695082Y480906D03*
Y486706D03*
G54D75*
X723275Y155655D03*
Y234461D03*
G54D66*
X583913Y69167D03*
X608571D03*
G54D48*
X264930Y408493D03*
X467880Y569288D03*
G54D85*
G01X-34986Y240533D02*
Y241487D01*
X-35262Y241763D01*
Y251603D01*
X-27952Y293183D01*
X-51519Y426980D01*
X-52146Y430539D01*
X-49021Y448310D01*
X-43434Y480087D01*
X-56462Y553913D01*
X-41265Y639943D01*
Y641923D01*
G01X-42472D02*
Y640012D01*
X-57681Y553913D01*
X-46718Y491789D01*
X-44654Y480094D01*
X-50242Y448310D01*
X-53366Y430544D01*
X-52738Y426980D01*
X-29171Y293183D01*
X-36444Y251811D01*
X-36462Y251708D01*
Y241783D01*
X-36758Y241487D01*
Y240533D01*
G01X129650Y250414D02*
X131550Y252314D01*
X138245D01*
X139645Y250914D01*
G01X129650Y255414D02*
X131550Y253514D01*
X138245D01*
X139645Y254914D01*
G01X139556Y261548D02*
X137906Y263198D01*
X131114D01*
X125260Y269052D01*
Y283004D01*
X124568Y283696D01*
X123960D01*
G01X139556Y266048D02*
X137906Y264398D01*
X131612D01*
X126460Y269550D01*
Y272103D01*
X126960Y272603D01*
Y274103D01*
X126460Y274603D01*
Y276103D01*
X126960Y276603D01*
Y278103D01*
X126460Y278603D01*
Y283004D01*
X127152Y283696D01*
X128960D01*
G01X485738Y587125D02*
X487638Y585225D01*
Y583763D01*
X483952Y581097D01*
X470251Y577082D01*
X434384Y576553D01*
X411695Y579705D01*
X381495Y578251D01*
X363780Y571164D01*
X353658Y549885D01*
X353536Y534615D01*
X357266Y502207D01*
X357894Y497382D01*
X357292Y490728D01*
X357716Y484507D01*
X357648Y483385D01*
X357517Y481257D01*
X350679Y453273D01*
X347024Y440418D01*
X341982Y437710D01*
X332864Y437285D01*
X324202Y438614D01*
X318315Y436929D01*
X317703Y436519D01*
X315072Y433190D01*
X311386Y424158D01*
X305552Y417680D01*
X300790Y414897D01*
X279341D01*
X253330Y414766D01*
X246059Y412568D01*
X243238Y412504D01*
X242701Y412491D01*
X238430D01*
X207911Y413029D01*
Y413104D01*
X170786Y411872D01*
X170726Y411866D01*
X170714Y411864D01*
X170611Y411852D01*
X163301Y410548D01*
X162250Y410361D01*
X158433Y408671D01*
X148253Y398580D01*
X132268Y382595D01*
X129907Y374794D01*
X129906Y374791D01*
X127001Y365191D01*
X126020Y304435D01*
X130484Y295954D01*
X130526Y295746D01*
X130525Y295744D01*
X134290Y277061D01*
X136890Y274181D01*
X142008Y273361D01*
X145809Y269560D01*
X147566Y268558D01*
X150865Y268662D01*
X152443Y267487D01*
G01X490738Y587125D02*
X488838Y585225D01*
Y583149D01*
X484488Y580003D01*
X470432Y575884D01*
X434310Y575351D01*
X411641Y578500D01*
X381754Y577062D01*
X364662Y570224D01*
X354857Y549609D01*
X354737Y534679D01*
X358458Y502353D01*
X359102Y497406D01*
X358496Y490715D01*
X358919Y484511D01*
X358846Y483312D01*
X358709Y481076D01*
X351840Y452966D01*
X348040Y439601D01*
X342310Y436523D01*
X332800Y436080D01*
X324280Y437387D01*
X318645Y435775D01*
X316119Y432579D01*
X312419Y423510D01*
X306319Y416738D01*
X301115Y413697D01*
X279345D01*
X253511Y413566D01*
X246250Y411372D01*
X243266Y411304D01*
X242716Y411291D01*
X238419D01*
X206711Y411849D01*
Y411863D01*
X170872Y410674D01*
X170865Y410673D01*
X170850Y410671D01*
X170845Y410670D01*
X170786Y410664D01*
X163512Y409366D01*
X162603Y409204D01*
X159121Y407663D01*
X149100Y397729D01*
X133330Y381959D01*
X131854Y377073D01*
X132273Y376296D01*
X131837Y374859D01*
X131058Y374444D01*
X131057Y374441D01*
X130622Y373007D01*
X129826Y370378D01*
X128199Y365004D01*
X127226Y304723D01*
X131627Y296361D01*
X132269Y293176D01*
X132942Y292729D01*
X133240Y291257D01*
X132791Y290584D01*
X133089Y289112D01*
X133762Y288665D01*
X134060Y287193D01*
X133611Y286520D01*
X133909Y285048D01*
X134582Y284601D01*
X134880Y283129D01*
X134431Y282456D01*
X135403Y277620D01*
X137498Y275300D01*
X142582Y274485D01*
X146544Y270523D01*
X147867Y269769D01*
X150700Y269858D01*
X152443Y271487D01*
G01X144400Y244061D02*
X143250Y245211D01*
X141902D01*
X140444Y244276D01*
X140355Y240876D01*
X140849Y239355D01*
X141482Y239032D01*
X141947Y237603D01*
X141622Y236970D01*
X142087Y235541D01*
X142720Y235218D01*
X143185Y233789D01*
X142860Y233156D01*
X143325Y231727D01*
X143958Y231404D01*
X144423Y229975D01*
X144098Y229342D01*
X144563Y227913D01*
X145196Y227590D01*
X145661Y226161D01*
X145336Y225528D01*
X145801Y224099D01*
X146434Y223776D01*
X146899Y222347D01*
X146574Y221714D01*
X147039Y220285D01*
X147672Y219962D01*
X148137Y218533D01*
X147812Y217900D01*
X157989Y186503D01*
X181699Y156399D01*
X183642Y155547D01*
X184350Y155825D01*
X185725Y155222D01*
X186001Y154515D01*
X187376Y153912D01*
X188084Y154189D01*
X189459Y153586D01*
X189735Y152879D01*
X191110Y152276D01*
X191818Y152553D01*
X193193Y151950D01*
X193469Y151243D01*
X194844Y150640D01*
X195552Y150917D01*
X196927Y150314D01*
X197203Y149607D01*
X202369Y147342D01*
X210770Y146843D01*
X214311D01*
X230105Y149580D01*
X230167D01*
X282152Y162928D01*
X282309D01*
X351338Y167051D01*
X369444Y168132D01*
X430339Y210712D01*
X433464Y212896D01*
X458469Y218267D01*
X475451Y230286D01*
X481511Y240865D01*
X513632Y269461D01*
X523010Y281984D01*
X528495Y287054D01*
X534375Y290754D01*
X534723Y290903D01*
X553083Y294525D01*
X564968Y295593D01*
X572286Y299233D01*
X573081D01*
X573093Y299245D01*
X575523Y299731D01*
X576635D01*
X577141Y300237D01*
X578641D01*
X579147Y299731D01*
X580647D01*
X581153Y300237D01*
X582653D01*
X583159Y299731D01*
X584659D01*
X585165Y300237D01*
X586665D01*
X587171Y299731D01*
X588171D01*
X590382Y301942D01*
Y303259D01*
X588607Y305034D01*
G01X144400Y247561D02*
X143250Y246411D01*
X141550D01*
X139261Y244943D01*
X139149Y240701D01*
X156913Y185928D01*
X180942Y155420D01*
X202084Y146156D01*
X210734Y145643D01*
X214415D01*
X230209Y148380D01*
X230319D01*
X282304Y161728D01*
X282345D01*
X351410Y165853D01*
X369854Y166954D01*
X431027Y209728D01*
X433953Y211773D01*
X458961Y217145D01*
X476361Y229459D01*
X482456Y240098D01*
X514521Y268644D01*
X523905Y281177D01*
X529228Y286097D01*
X534936Y289688D01*
X535080Y289750D01*
X553253Y293335D01*
X565301Y294417D01*
X572568Y298033D01*
X573081D01*
X573093Y298021D01*
X575642Y298531D01*
X588669D01*
X591582Y301444D01*
Y303009D01*
X593607Y305034D01*
G01X142795Y254914D02*
X144195Y253514D01*
X145529D01*
X146039Y254024D01*
X147539D01*
X148049Y253514D01*
X149549D01*
X150059Y254024D01*
X151559D01*
X152069Y253514D01*
X154849D01*
X158745Y257410D01*
X163248D01*
X167660Y252998D01*
X170040D01*
X170620Y253578D01*
X172120D01*
X172700Y252998D01*
X175636D01*
X178020Y255331D01*
Y257046D01*
X177381Y257685D01*
X175756D01*
Y257668D01*
G01X142795Y250914D02*
X144195Y252314D01*
X155347D01*
X159243Y256210D01*
X162750D01*
X167162Y251798D01*
X176126D01*
X179220Y254826D01*
Y256662D01*
X180218Y257660D01*
X181166D01*
X181176Y257650D01*
Y257643D01*
G01X142706Y266048D02*
X144520Y264234D01*
X167449D01*
X168891Y265676D01*
X175200D01*
G01X160874Y263034D02*
X144192D01*
X142706Y261548D01*
G01X170480Y278665D02*
X169150D01*
X164863Y280530D01*
X160214D01*
X158145Y280980D01*
X158140D01*
X152508Y283917D01*
X149349Y287109D01*
X148312Y288855D01*
X148497Y289574D01*
X147729Y290866D01*
X147010Y291049D01*
X146242Y292342D01*
X146427Y293060D01*
X145659Y294352D01*
X144940Y294535D01*
X144169Y295834D01*
X143585Y298028D01*
X143972Y298693D01*
X143584Y300144D01*
X142918Y300528D01*
X142530Y301979D01*
X142916Y302643D01*
X142528Y304094D01*
X141862Y304478D01*
X141618Y305389D01*
X141210Y333075D01*
X137920Y372018D01*
X141210Y382508D01*
X150190Y391696D01*
X158010Y398552D01*
X178100Y400814D01*
X192149Y405559D01*
X192716D01*
X199287Y406547D01*
X222203D01*
X235040Y402598D01*
X249090D01*
X253510Y402529D01*
X255957Y403836D01*
X261330Y408493D01*
X264930D01*
G01X170480Y277465D02*
X168900D01*
X164613Y279330D01*
X160085D01*
X158016Y279780D01*
X157845D01*
X151786Y282939D01*
X148392Y286370D01*
X143052Y295364D01*
X140420Y305223D01*
X140010Y333016D01*
X136704Y372152D01*
X140150Y383142D01*
X149364Y392568D01*
X157501Y399703D01*
X177838Y401993D01*
X191951Y406759D01*
X192626D01*
X199197Y407747D01*
X222384D01*
X235221Y403798D01*
X249100D01*
X253218Y403734D01*
X255272Y404832D01*
X260882Y409693D01*
X270645D01*
X281209Y409780D01*
X282409D01*
X305290Y409328D01*
X313690Y416197D01*
X321654Y421185D01*
X326149Y427573D01*
X328294Y431524D01*
X332117Y432469D01*
X341051Y432368D01*
X352169Y433958D01*
X357398Y437829D01*
X359490Y448993D01*
X359661Y468156D01*
X363465Y478363D01*
X363346Y479102D01*
X361810Y522142D01*
X361596Y553402D01*
X372337Y567920D01*
X389691Y573311D01*
X419185Y569986D01*
X456271Y568285D01*
X465560Y569288D01*
X467880D01*
G01X160874Y263034D02*
X162788D01*
X163354Y262468D01*
X164854D01*
X165420Y263034D01*
X167947D01*
X169389Y264476D01*
X179533D01*
X179952Y264895D01*
X181062D01*
X181602Y264355D01*
Y262656D01*
G01X168850Y268923D02*
X168731Y269042D01*
X159894D01*
G01X155593Y267487D02*
X157148Y269042D01*
X159894D01*
G01X155593Y271487D02*
X156426Y270654D01*
X156475D01*
X156887Y270242D01*
X162811D01*
X163479Y270910D01*
X164621D01*
X165289Y270242D01*
X167849D01*
G01X581650Y311446D02*
X580590Y310386D01*
Y307824D01*
X578212Y305446D01*
X564381D01*
X548867Y301193D01*
X548474Y301106D01*
X537488Y298708D01*
X529240Y296692D01*
X519030Y288341D01*
X513306Y277419D01*
X480555Y245420D01*
X469183Y230507D01*
X456409Y221527D01*
X431989Y216282D01*
X430802Y215452D01*
X368208Y171685D01*
X351410Y170682D01*
X281595Y166512D01*
X281504D01*
X231608Y153695D01*
Y153625D01*
X212713Y151668D01*
X212121Y151607D01*
X207611Y151863D01*
X187472Y160517D01*
X181133Y166696D01*
X173318Y184969D01*
X171819Y229084D01*
X173167Y231539D01*
X176118Y233559D01*
X176451Y233867D01*
X176900Y234316D01*
Y235126D01*
X175627Y236399D01*
G01X576650Y311446D02*
X578444D01*
X579390Y310500D01*
Y308322D01*
X577714Y306646D01*
X573955D01*
X573407Y307195D01*
X571907D01*
X571359Y306646D01*
X564219D01*
X548550Y302351D01*
X548237Y302283D01*
X548216Y302278D01*
X537217Y299878D01*
X528690Y297794D01*
X518080Y289116D01*
X512331Y278145D01*
X479661Y246226D01*
X479659D01*
X468341Y231382D01*
X455918Y222650D01*
X431500Y217405D01*
X427577Y214663D01*
X427578D01*
X367798Y172863D01*
X351338Y171880D01*
X281559Y167712D01*
X281352D01*
X230939Y154763D01*
X212093Y152811D01*
X207891Y153050D01*
X203745Y154832D01*
X203465Y155533D01*
X202086Y156126D01*
X201386Y155845D01*
X200007Y156438D01*
X199727Y157139D01*
X198348Y157732D01*
X197648Y157451D01*
X196269Y158044D01*
X195989Y158745D01*
X194610Y159338D01*
X193910Y159057D01*
X192531Y159650D01*
X192251Y160351D01*
X190872Y160944D01*
X190172Y160663D01*
X188150Y161532D01*
X182143Y167389D01*
X174510Y185234D01*
X173030Y228795D01*
X174081Y230710D01*
X176870Y232618D01*
X177284Y233002D01*
X178100Y233818D01*
Y234872D01*
X179627Y236399D01*
G01X175627Y239549D02*
X177150Y241072D01*
Y243198D01*
X179819Y245867D01*
X185684D01*
X197073Y257256D01*
Y265022D01*
G01X179627Y239549D02*
X178350Y240826D01*
Y242700D01*
X180317Y244667D01*
X186182D01*
X187643Y246128D01*
X188017D01*
X188019Y246126D01*
X188393D01*
X189455Y247188D01*
Y247562D01*
X189453Y247564D01*
Y247938D01*
X190515Y249000D01*
X190889D01*
X190891Y248998D01*
X191265D01*
X192327Y250060D01*
Y250434D01*
X192325Y250436D01*
Y250810D01*
X193856Y252341D01*
G01X175200Y265676D02*
X179035D01*
X179454Y266095D01*
X181560D01*
X182802Y264853D01*
Y264852D01*
X184117D01*
G01X167849Y270242D02*
X169229D01*
X169699Y269772D01*
G01X193856Y252341D02*
X195560Y254045D01*
X195920D01*
X195922Y254043D01*
X196282D01*
X197344Y255105D01*
Y255465D01*
X197342Y255467D01*
Y255827D01*
X198273Y256758D01*
Y262265D01*
X198809Y262801D01*
Y264301D01*
X198273Y264837D01*
Y265837D01*
X199223Y266787D01*
X200721D01*
X201518Y265990D01*
G01Y268887D02*
X200618Y267987D01*
X198725D01*
X197073Y266335D01*
Y265022D01*
G01X264930Y408493D02*
X270650D01*
X281218Y408579D01*
X282386Y408580D01*
X282397D01*
X305708Y408119D01*
X314391Y415220D01*
X322496Y420296D01*
X327171Y426939D01*
X329096Y430486D01*
X332256Y431267D01*
X341130Y431167D01*
X352640Y432812D01*
X358491Y437145D01*
X360690Y448876D01*
X360860Y467934D01*
X364590Y477944D01*
X364547Y479145D01*
X363010Y522168D01*
X362799Y553010D01*
X368755Y561060D01*
X369716Y561203D01*
X370610Y562410D01*
X370465Y563371D01*
X373069Y566890D01*
X389807Y572090D01*
X419090Y568789D01*
X456308Y567082D01*
X465625Y568088D01*
X474993D01*
X475073Y568008D01*
Y568002D01*
X476381Y566694D01*
X476385D01*
G01X449860Y267121D02*
Y268521D01*
X450360Y269021D01*
X455829D01*
X461860Y275052D01*
Y316380D01*
X466030Y320550D01*
Y374049D01*
X491350Y399369D01*
Y428654D01*
X488954Y431050D01*
Y463103D01*
X486022Y466035D01*
X483380D01*
X482880Y466535D01*
Y467935D01*
G01X449860Y272121D02*
Y270721D01*
X450360Y270221D01*
X455331D01*
X460660Y275550D01*
Y286983D01*
X460160Y287483D01*
Y288983D01*
X460660Y289483D01*
Y290983D01*
X460160Y291483D01*
Y292983D01*
X460660Y293483D01*
Y294983D01*
X460160Y295483D01*
Y296983D01*
X460660Y297483D01*
Y316878D01*
X464830Y321048D01*
Y374547D01*
X490150Y399867D01*
Y428156D01*
X487754Y430552D01*
Y437312D01*
X487240Y437826D01*
Y439326D01*
X487754Y439840D01*
Y441340D01*
X487240Y441854D01*
Y443354D01*
X487754Y443868D01*
Y445368D01*
X487240Y445882D01*
Y447382D01*
X487754Y447896D01*
Y449396D01*
X487240Y449910D01*
Y451410D01*
X487754Y451924D01*
Y453424D01*
X487240Y453938D01*
Y455438D01*
X487754Y455952D01*
Y457452D01*
X487240Y457966D01*
Y459466D01*
X487754Y459980D01*
Y462605D01*
X485524Y464835D01*
X483380D01*
X482880Y464335D01*
Y462935D01*
G01X476385Y560648D02*
X475002Y559265D01*
X473624D01*
X471804Y561085D01*
G01X476385Y556648D02*
X474968Y558065D01*
X473784D01*
X471804Y556085D01*
G01X476385Y570694D02*
X476378D01*
X474972Y569288D01*
X467880D01*
G01X479535Y556648D02*
X480935Y558048D01*
X481938D01*
X483838Y556148D01*
G01X479535Y560648D02*
X480935Y559248D01*
X481938D01*
X483838Y561148D01*
G01X479535Y570694D02*
X480935Y569294D01*
X481938D01*
X483838Y571194D01*
G01X479535Y566694D02*
X480935Y568094D01*
X481938D01*
X483838Y566194D01*
G01X510938Y536790D02*
X509478Y535330D01*
Y531635D01*
X509078Y531235D01*
Y522987D01*
X509070D01*
Y507562D01*
X515755Y500877D01*
X527621D01*
X530768Y497730D01*
X549443D01*
X557802Y489371D01*
X567268D01*
X572839Y483800D01*
Y481772D01*
X566821Y475754D01*
Y474718D01*
X567553Y473986D01*
X568589D01*
X574607Y480004D01*
X576635D01*
X581820Y474819D01*
Y469728D01*
X578315Y466223D01*
X574839D01*
X574837Y466221D01*
X574339Y466222D01*
X572440Y464323D01*
G01X506938Y536790D02*
X508278Y535450D01*
Y532133D01*
X507870Y531725D01*
Y523443D01*
X507340Y522913D01*
Y521413D01*
X507870Y520883D01*
Y519383D01*
X507340Y518853D01*
Y517353D01*
X507870Y516823D01*
Y515323D01*
X507340Y514793D01*
Y513293D01*
X507870Y512763D01*
Y511263D01*
X507340Y510733D01*
Y509233D01*
X507870Y508703D01*
Y507064D01*
X515257Y499677D01*
X527123D01*
X530270Y496530D01*
X548945D01*
X557304Y488171D01*
X566770D01*
X571639Y483302D01*
Y482270D01*
X565621Y476252D01*
Y474220D01*
X567055Y472786D01*
X569087D01*
X575105Y478804D01*
X576137D01*
X580620Y474321D01*
Y470226D01*
X577817Y467423D01*
X574340D01*
X572440Y469323D01*
G01X510938Y539940D02*
X509538Y541340D01*
Y545643D01*
X506316Y548865D01*
X504298D01*
X503338Y549825D01*
G01X506938Y539940D02*
X508338Y541340D01*
Y545145D01*
X505818Y547665D01*
X504438D01*
X503338Y546565D01*
Y544825D01*
G01X514430Y511801D02*
X515629D01*
X516330Y511100D01*
Y508289D01*
X518657Y505962D01*
X530069D01*
X531589Y504442D01*
X547903D01*
X559385Y492960D01*
X570839D01*
X585498Y478301D01*
X594430Y456968D01*
Y424755D01*
X597184Y407747D01*
X605553Y399378D01*
X610741D01*
X612641Y397478D01*
G01X519430Y511801D02*
X518315D01*
X517530Y511016D01*
Y508787D01*
X519155Y507162D01*
X523561D01*
X524095Y507696D01*
X525595D01*
X526129Y507162D01*
X530567D01*
X532087Y505642D01*
X533929D01*
X534449Y506163D01*
X535949D01*
X536469Y505642D01*
X537969D01*
X538489Y506163D01*
X539989D01*
X540509Y505642D01*
X542009D01*
X542529Y506163D01*
X544029D01*
X544549Y505642D01*
X548401D01*
X559883Y494160D01*
X571337D01*
X586514Y478983D01*
X595630Y457210D01*
Y424852D01*
X598307Y408322D01*
X606051Y400578D01*
X610741D01*
X612641Y402478D01*
G01X538038Y488323D02*
X536931D01*
X536138Y489116D01*
Y491023D01*
X538009Y492894D01*
X547231D01*
X559090Y481035D01*
Y470177D01*
X560980Y468287D01*
Y385010D01*
X587884Y358106D01*
Y354859D01*
X587070Y354045D01*
Y352545D01*
X587884Y351731D01*
Y350231D01*
X587070Y349417D01*
Y347917D01*
X587884Y347103D01*
Y345603D01*
X587070Y344789D01*
Y343289D01*
X587884Y342475D01*
Y340975D01*
X587070Y340161D01*
Y338661D01*
X587884Y337847D01*
Y336347D01*
X587070Y335533D01*
Y334033D01*
X587884Y333219D01*
Y323746D01*
X587384Y323246D01*
X585984D01*
G01X533038Y488323D02*
X534281D01*
X534938Y488980D01*
Y491521D01*
X537511Y494094D01*
X547729D01*
X560290Y481533D01*
Y470675D01*
X562180Y468785D01*
Y385508D01*
X589084Y358604D01*
Y325146D01*
X590984Y323246D01*
G01X609078Y393557D02*
X610978Y391657D01*
X614201D01*
X617260Y394716D01*
Y403577D01*
X612699Y408138D01*
X611990D01*
X610928Y409200D01*
X610929Y409554D01*
Y409908D01*
X609867Y410970D01*
X609158D01*
X608096Y412032D01*
X608097Y412386D01*
Y412740D01*
X605487Y415350D01*
X600504Y437269D01*
X600410Y440120D01*
Y444670D01*
X599890Y445190D01*
Y446690D01*
X600410Y447210D01*
Y448710D01*
X599890Y449230D01*
Y450730D01*
X600410Y451250D01*
Y452750D01*
X599890Y453270D01*
Y454770D01*
X600410Y455290D01*
Y457083D01*
X590327Y482025D01*
X574369Y497983D01*
X562635D01*
X560853Y499765D01*
X560499D01*
X560497Y499763D01*
X560143D01*
X559081Y500825D01*
Y501179D01*
X559083Y501181D01*
Y501535D01*
X558021Y502597D01*
X557667D01*
X557665Y502595D01*
X557311D01*
X556249Y503657D01*
Y504011D01*
X556251Y504013D01*
Y504367D01*
X555189Y505429D01*
X554835D01*
X554833Y505427D01*
X554479D01*
X553417Y506489D01*
Y506843D01*
X553419Y506845D01*
Y507199D01*
X552357Y508261D01*
X552003D01*
X552001Y508259D01*
X551647D01*
X550585Y509321D01*
Y509675D01*
X550587Y509677D01*
Y510031D01*
X548451Y512167D01*
X545090D01*
X544370Y511447D01*
Y510267D01*
G01X609078Y388557D02*
X610978Y390457D01*
X614699D01*
X618460Y394218D01*
Y404075D01*
X606581Y415954D01*
X601700Y437423D01*
X601610Y440140D01*
Y457317D01*
X591349Y482702D01*
X574867Y499183D01*
X563133D01*
X548949Y513367D01*
X545199D01*
X544370Y514196D01*
Y515267D01*
G01X564370Y504117D02*
X566270Y506017D01*
X567530D01*
X570790Y502757D01*
X576442D01*
X613770Y465429D01*
Y437427D01*
X625510Y425687D01*
Y409190D01*
X627793Y406907D01*
X628791D01*
X630691Y405007D01*
G01Y410007D02*
X628791Y408107D01*
X628291D01*
X626710Y409688D01*
Y426185D01*
X614970Y437925D01*
Y465927D01*
X576940Y503957D01*
X571288D01*
X568028Y507217D01*
X566270D01*
X564370Y509117D01*
G01X578840Y512108D02*
X576940Y514008D01*
Y534224D01*
X581150Y538434D01*
Y564223D01*
X586895Y569968D01*
X597055D01*
X600200Y573113D01*
Y595754D01*
X597159Y598795D01*
X595767D01*
X593867Y600695D01*
G01X573840Y512108D02*
X575740Y514008D01*
Y534722D01*
X579950Y538932D01*
Y564721D01*
X586397Y571168D01*
X587847D01*
X588381Y571702D01*
X589881D01*
X590415Y571168D01*
X591915D01*
X592449Y571702D01*
X593949D01*
X594483Y571168D01*
X596557D01*
X599000Y573611D01*
Y587017D01*
X598430Y587587D01*
Y589087D01*
X599000Y589657D01*
Y591157D01*
X598430Y591727D01*
Y593227D01*
X599000Y593797D01*
Y595256D01*
X596661Y597595D01*
X595767D01*
X593867Y595695D01*
G54D76*
G01X220943Y276987D02*
Y276442D01*
X224157Y273228D01*
X224357D01*
G01X222018Y280912D02*
Y279774D01*
X220943Y278699D01*
Y276987D01*
G01X230725Y331649D02*
X231497D01*
X231940Y331207D01*
X233598D01*
X234953Y332562D01*
X235518D01*
G01X650463Y683277D02*
X656254D01*
G01X657880Y680718D02*
X650463D01*
G54D58*
X481102Y34528D03*
G54D67*
X590999Y69167D03*
Y77041D03*
Y84915D03*
X615657Y69167D03*
Y77041D03*
Y84915D03*
G54D49*
X288613Y250180D03*
X288859Y246800D03*
G54D86*
G01X689527Y412843D02*
Y411383D01*
X689107Y410963D01*
X686298D01*
X682580Y407245D01*
Y289374D01*
X644160Y250954D01*
Y169628D01*
X652341Y161447D01*
X655275D01*
X655695Y161027D01*
Y159567D01*
G01X689527Y407843D02*
Y409303D01*
X689107Y409723D01*
X686812D01*
X683820Y406731D01*
Y288860D01*
X645400Y250440D01*
Y170142D01*
X652855Y162687D01*
X655275D01*
X655695Y163107D01*
Y164567D01*
G01X655642Y144915D02*
Y146375D01*
X656062Y146795D01*
X659878D01*
X663030Y149947D01*
Y167086D01*
X649770Y180346D01*
Y248642D01*
X694910Y293782D01*
Y392305D01*
X691573Y395642D01*
X687106D01*
X686686Y396062D01*
Y397522D01*
G01Y392522D02*
Y393982D01*
X687106Y394402D01*
X691059D01*
X693670Y391791D01*
Y294296D01*
X648530Y249156D01*
Y179832D01*
X661790Y166572D01*
Y150461D01*
X659364Y148035D01*
X656062D01*
X655642Y148455D01*
Y149915D01*
G01X648208Y427819D02*
X646748D01*
X646328Y427399D01*
Y425130D01*
X649391Y422067D01*
X689114D01*
X698990Y412191D01*
Y290852D01*
X654150Y246012D01*
Y242744D01*
X655367Y241527D01*
X657418D01*
X657838Y241947D01*
Y243407D01*
G01X643208Y427819D02*
X644668D01*
X645088Y427399D01*
Y424616D01*
X648877Y420827D01*
X688600D01*
X697750Y411677D01*
Y291366D01*
X652910Y246526D01*
Y242230D01*
X654853Y240287D01*
X657418D01*
X657838Y239867D01*
Y238407D01*
G01X655030Y228744D02*
X656957Y226817D01*
X659585D01*
X667520Y234752D01*
Y253960D01*
X705320Y291760D01*
Y410851D01*
X685424Y430747D01*
X663298D01*
X661459Y428908D01*
Y427481D01*
X663339Y425601D01*
G01X655030Y223744D02*
X656863Y225577D01*
X660099D01*
X668760Y234238D01*
Y253446D01*
X706560Y291246D01*
Y411365D01*
X685938Y431987D01*
X662784D01*
X660219Y429422D01*
Y427481D01*
X658339Y425601D01*
G54D77*
G01X389350Y711288D02*
Y709614D01*
X388967Y709231D01*
X383940D01*
G01X406940Y681081D02*
X410135D01*
X412250Y683196D01*
G01X504941Y213711D02*
Y210459D01*
X502682Y208200D01*
X491646D01*
X491046Y207600D01*
Y207506D01*
G01X514059Y226925D02*
X512128D01*
X510059Y225114D01*
Y221289D01*
G01X523611Y221459D02*
X520259D01*
X519300Y220500D01*
G01X531189Y216341D02*
X538284D01*
X538525Y216100D01*
G54D59*
X504941Y213711D03*
X507500D03*
X510059D03*
X504941Y221289D03*
X510059D03*
G54D68*
X590999Y92789D03*
X615657D03*
G54D87*
G01X241613Y259197D02*
X244034D01*
X244526Y258705D01*
G01X250872Y251117D02*
Y246964D01*
X250837Y246929D01*
G01X250872Y255117D02*
Y251117D01*
G01Y255117D02*
X250148D01*
X248418Y253387D01*
X245899D01*
X244568Y254718D01*
Y258663D01*
X244526Y258705D01*
G54D78*
G01X205940Y708231D02*
X201411D01*
G01X227679Y511865D02*
X228311Y511233D01*
Y511143D01*
X229579Y509875D01*
X230058D01*
X230476Y509457D01*
Y508891D01*
G01X228940Y680081D02*
X224289D01*
G01X245609Y517182D02*
X243876Y515449D01*
X243018D01*
G01X242993Y511465D02*
Y515424D01*
X243018Y515449D01*
G01X249344Y552984D02*
X249374D01*
X248596Y553762D01*
X246243D01*
X246209Y553728D01*
G01X327540Y653432D02*
X327384D01*
X326134Y652182D01*
X322468D01*
G01X446900Y714648D02*
X446960Y714588D01*
Y711751D01*
X446940Y711731D01*
G01X469940Y683581D02*
X478133D01*
X479409Y682305D01*
G54D69*
X605796Y165160D03*
X609733Y215672D03*
G54D88*
G01X240567Y293811D02*
X239324Y295054D01*
Y298373D01*
X240949Y299998D01*
G54D79*
G01X180634Y520053D02*
X179383D01*
X178085Y518755D01*
G01X171606Y527511D02*
Y524761D01*
X173513Y522854D01*
G01X178396Y524137D02*
X174796D01*
X173513Y522854D01*
G01X178082Y537654D02*
X176284Y539452D01*
X175954Y539647D01*
G01X193313Y325492D02*
X194323Y326502D01*
X196767D01*
X196887Y326622D01*
G01X196354Y331014D02*
X194278D01*
X190557Y327293D01*
Y325701D01*
G01X192519Y352761D02*
X194185Y351095D01*
Y349984D01*
G01X186908Y352760D02*
X189774Y349894D01*
X190058D01*
G01X186417Y518526D02*
X184890Y520053D01*
X183784D01*
G01X186467Y514036D02*
X185134Y512703D01*
Y511353D01*
G01X184920Y508626D02*
X184634Y508340D01*
Y505353D01*
G01X181232Y528205D02*
X181546Y527891D01*
Y524137D01*
G01X206299Y281098D02*
X205708Y280507D01*
Y277609D01*
G01X198653Y281646D02*
X202601D01*
X203149Y281098D01*
G01X206299Y290548D02*
X204728Y292119D01*
X204722D01*
X204035Y292806D01*
X201016D01*
X199494Y294328D01*
Y294848D01*
X197847Y296495D01*
Y297731D01*
G01X197468Y289193D02*
X198823Y290548D01*
X203149D01*
G01X206015Y300444D02*
Y299746D01*
X203484Y297215D01*
Y296821D01*
X202687Y296024D01*
G01D02*
X203777Y294934D01*
X205063D01*
X206299Y293698D01*
G01X198801Y318727D02*
X199611Y317917D01*
X207656D01*
X209449Y316124D01*
Y312598D01*
G01X206680Y320800D02*
X207600D01*
X212872Y315528D01*
Y313117D01*
G01X196887Y323472D02*
Y320641D01*
X198801Y318727D01*
G01X199504Y331014D02*
Y328701D01*
X200590Y327615D01*
G01X232118Y271587D02*
X227565D01*
X226995Y272157D01*
G01X220218Y272487D02*
X221648Y271057D01*
X225895D01*
X226995Y272157D01*
G01X220218Y272487D02*
Y273672D01*
X217072Y276818D01*
Y277567D01*
G01X213922D02*
X212943Y274382D01*
X213138Y274187D01*
G01X218150Y297006D02*
Y293088D01*
G01X218175Y297031D02*
X218150Y297006D01*
G01X227767Y333172D02*
Y326836D01*
X228954Y325649D01*
X230725D01*
G01X228057Y352837D02*
X227767Y352547D01*
Y336322D01*
G01X219634Y483278D02*
X220035Y482877D01*
X229279D01*
X231110Y484708D01*
Y485009D01*
X231209Y485108D01*
Y501858D01*
X230476Y502591D01*
G01X224193Y498103D02*
X224134Y495003D01*
X224209Y494928D01*
G01X224634Y515853D02*
Y511970D01*
X224529Y511865D01*
G01X227329Y508894D02*
X226668D01*
X224529Y511033D01*
Y511865D01*
G01X234060Y274542D02*
X237910D01*
G01X239569Y269639D02*
X237166D01*
X236618Y270187D01*
G01X237910Y274542D02*
Y272379D01*
X236618Y271087D01*
Y270187D01*
G01X241613Y271197D02*
X242084Y270726D01*
X244480D01*
G01X238545Y327149D02*
X236282Y329412D01*
X235518D01*
G01X245691Y341215D02*
X244882Y340406D01*
Y339395D01*
X243612Y338125D01*
Y336435D01*
G01X248690Y392083D02*
X246376Y394397D01*
X240334D01*
X239228Y393291D01*
G01X244480Y270726D02*
X248484D01*
X248625Y270867D01*
G01X252261Y272285D02*
X251240D01*
X249822Y270867D01*
X248625D01*
G01X250399Y284248D02*
X250553Y284402D01*
X252943D01*
G01X257057Y309636D02*
Y308831D01*
X258901Y306987D01*
X259943D01*
G01X262944Y309643D02*
X263093Y309494D01*
Y306987D01*
G01X276687Y385100D02*
X275113Y386674D01*
Y387669D01*
G01X273128Y384751D02*
X272687Y384310D01*
Y383694D01*
G01X288630Y727362D02*
Y725297D01*
X289240Y724687D01*
G01X389999Y668428D02*
X393033D01*
X394301Y669696D01*
X396411D01*
G01X466440Y739081D02*
Y735987D01*
G01X519440Y738081D02*
Y735681D01*
G01X555148Y735583D02*
X555440Y735875D01*
Y738381D01*
G01X690986Y479786D02*
X692520Y478252D01*
Y475042D01*
G01X698860Y479786D02*
X697759Y478685D01*
Y475492D01*
G01X689700Y774500D02*
X691000D01*
X709500Y756000D01*
Y743575D01*
G01X699600Y776000D02*
Y798100D01*
X699649D01*
X700849Y799300D01*
Y807872D01*
G01X689700Y774500D02*
X696900Y781700D01*
Y807872D01*
X696912D01*
G01X704000Y770800D02*
X702500Y772300D01*
Y795120D01*
X704786Y797406D01*
Y807872D01*
G01X729500Y731425D02*
Y729700D01*
X730800Y728400D01*
G01X729500Y743575D02*
Y746300D01*
G54D89*
G01X226847Y216901D02*
X227882Y217936D01*
Y219866D01*
X226847Y220901D01*
G01D02*
X228130Y222184D01*
Y225834D01*
G01X229997Y216901D02*
X228962Y217936D01*
Y219866D01*
X229997Y220901D01*
G01X228130Y225834D02*
Y241180D01*
X229432Y242482D01*
X230550D01*
X231710Y243642D01*
G01X229997Y220901D02*
X229210Y221688D01*
Y240732D01*
X229880Y241402D01*
X230550D01*
X231710Y240242D01*
G01X242064Y242228D02*
X243099Y243263D01*
Y245193D01*
X242064Y246228D01*
G01D02*
X242952Y247116D01*
Y252300D01*
X241593Y253662D01*
X240582Y254672D01*
X238326D01*
X236593Y256405D01*
Y258887D01*
G01X239569Y263639D02*
X237763Y261833D01*
Y256890D01*
X238811Y255842D01*
X241067D01*
X242421Y254489D01*
X244122Y252784D01*
Y250972D01*
G01X233793Y263697D02*
X236593Y260897D01*
Y258887D01*
G01X245214Y242228D02*
X244179Y243263D01*
Y245193D01*
X245214Y246228D01*
G01D02*
X244122Y247320D01*
Y250972D01*
M02*
